G04 ================== begin FILE IDENTIFICATION RECORD ==================*
G04 Layout Name:  9127_F0T_Expander_BD_F_v02_0110_1240.brd*
G04 Film Name:    fab*
G04 File Format:  Gerber RS274X*
G04 File Origin:  Cadence Allegro 17.2-S081*
G04 Origin Date:  Wed Jan 11 16:06:34 2023*
G04 *
G04 Layer:  MANUFACTURING/NCBACKDRILL-1-15*
G04 Layer:  MANUFACTURING/NCBACKDRILL-1-13*
G04 Layer:  MANUFACTURING/NCBACKDRILL-1-11*
G04 Layer:  MANUFACTURING/NCLEGEND-SLOTS-1-18*
G04 Layer:  MANUFACTURING/NCBACKDRILL-18-9*
G04 Layer:  MANUFACTURING/NCBACKDRILL-18-7*
G04 Layer:  MANUFACTURING/NCBACKDRILL-18-17*
G04 Layer:  MANUFACTURING/NCBACKDRILL-18-15*
G04 Layer:  MANUFACTURING/NCBACKDRILL-18-13*
G04 Layer:  MANUFACTURING/NCBACKDRILL-18-11*
G04 Layer:  PIN/SPECIAL_DRILL*
G04 Layer:  DRAWING FORMAT/TITLE_BLOCK_A*
G04 Layer:  MANUFACTURING/NCLEGEND-1-18*
G04 Layer:  BOARD GEOMETRY/DESIGN_OUTLINE*
G04 Layer:  BOARD GEOMETRY/CUTOUT*
G04 Layer:  MANUFACTURING/NCDRILL_LEGEND*
G04 Layer:  MANUFACTURING/NCDRILL_FIGURE*
G04 Layer:  MANUFACTURING/PHOTOPLOT_OUTLINE*
G04 Layer:  MANUFACTURING/DIMENSION*
G04 Layer:  MANUFACTURING/DETAILS*
G04 Layer:  DRAWING FORMAT/TITLE_BLOCK*
G04 Layer:  DRAWING FORMAT/TITLE_DATA_FAB*
G04 *
G04 Offset:    (0.00 0.00)*
G04 Mirror:    No*
G04 Mode:      Positive*
G04 Rotation:  0*
G04 FullContactRelief:  No*
G04 UndefLineWidth:     6.00*
G04 ================== end FILE IDENTIFICATION RECORD ====================*
%FSLAX25Y25*MOIN*%
%IR0*IPPOS*OFA0.00000B0.00000*MIA0B0*SFA1.00000B1.00000*%
%AMMACRO23*
1,1,.006,.014497,-.035*
20,1,.006,.014497,-.035,-.014497,-.035,0.0*
1,1,.006,-.014497,-.035*
20,1,.006,-.014497,-.035,-.035,-.014497,0.0*
1,1,.006,-.035,-.014497*
20,1,.006,-.035,-.014497,-.035,.014497,0.0*
1,1,.006,-.035,.014497*
20,1,.006,-.035,.014497,-.014497,.035,0.0*
1,1,.006,-.014497,.035*
20,1,.006,-.014497,.035,.014497,.035,0.0*
1,1,.006,.014497,.035*
20,1,.006,.014497,.035,.035,.014497,0.0*
1,1,.006,.035,.014497*
20,1,.006,.035,.014497,.035,-.014497,0.0*
1,1,.006,.035,-.014497*
20,1,.006,.035,-.014497,.014497,-.035,0.0*
1,1,.006,.014497,-.035*
1,1,.006,-.0229,-.01041*
20,1,.006,-.0229,-.01041,-.0229,.00729,0.0*
1,1,.006,-.0229,.00729*
20,1,.006,-.0229,.00729,-.02221,.00902,0.0*
1,1,.006,-.02221,.00902*
20,1,.006,-.02221,.00902,-.02082,.01006,0.0*
1,1,.006,-.02082,.01006*
20,1,.006,-.02082,.01006,-.01874,.01041,0.0*
1,1,.006,-.01874,.01041*
20,1,.006,-.01874,.01041,-.01666,.00972,0.0*
1,1,.006,-.01666,.00972*
20,1,.006,-.01666,.00972,-.01562,.00798,0.0*
1,1,.006,-.01562,.00798*
1,1,.006,-.01978,.00208*
20,1,.006,-.01978,.00208,-.02672,.00208,0.0*
1,1,.006,-.02672,.00208*
1,1,.006,.00001,.00347*
20,1,.006,.00001,.00347,.00001,-.01041,0.0*
1,1,.006,.00001,-.01041*
1,1,.006,.00001,.00902*
20,1,.006,.00001,.00902,-.00068,.00937,0.0*
1,1,.006,-.00068,.00937*
20,1,.006,-.00068,.00937,-.00068,.01006,0.0*
1,1,.006,-.00068,.01006*
20,1,.006,-.00068,.01006,.00001,.01041,0.0*
1,1,.006,.00001,.01041*
20,1,.006,.00001,.01041,.0007,.01006,0.0*
1,1,.006,.0007,.01006*
20,1,.006,.0007,.01006,.0007,.00937,0.0*
1,1,.006,.0007,.00937*
20,1,.006,.0007,.00937,.00001,.00902,0.0*
1,1,.006,.00001,.00902*
1,1,.006,.02084,.01041*
20,1,.006,.02084,.01041,.02084,-.01041,0.0*
1,1,.006,.02084,-.01041*
1,1,.006,.01598,.00347*
20,1,.006,.01598,.00347,.0257,.00347,0.0*
1,1,.006,.0257,.00347*
%
%ADD23MACRO23*%
%AMMACRO30*
1,1,.006,.035,.035*
20,1,.006,.035,.035,.035,-.035,0.0*
1,1,.006,.035,-.035*
20,1,.006,.035,-.035,-.035,-.035,0.0*
1,1,.006,-.035,-.035*
20,1,.006,-.035,-.035,-.035,.035,0.0*
1,1,.006,-.035,.035*
20,1,.006,-.035,.035,.035,.035,0.0*
1,1,.006,.035,.035*
1,1,.006,-.03185,-.02042*
20,1,.006,-.03185,-.02042,-.03185,.00408,0.0*
1,1,.006,-.03185,.00408*
1,1,.006,-.03185,.00041*
20,1,.006,-.03185,.00041,-.02981,.00245,0.0*
1,1,.006,-.02981,.00245*
20,1,.006,-.02981,.00245,-.02777,.00367,0.0*
1,1,.006,-.02777,.00367*
20,1,.006,-.02777,.00367,-.0245,.00408,0.0*
1,1,.006,-.0245,.00408*
20,1,.006,-.0245,.00408,-.02164,.00367,0.0*
1,1,.006,-.02164,.00367*
20,1,.006,-.02164,.00367,-.01878,.00163,0.0*
1,1,.006,-.01878,.00163*
20,1,.006,-.01878,.00163,-.01756,-.00123,0.0*
1,1,.006,-.01756,-.00123*
20,1,.006,-.01756,-.00123,-.01715,-.00408,0.0*
1,1,.006,-.01715,-.00408*
20,1,.006,-.01715,-.00408,-.01756,-.00694,0.0*
1,1,.006,-.01756,-.00694*
20,1,.006,-.01756,-.00694,-.01878,-.0098,0.0*
1,1,.006,-.01878,-.0098*
20,1,.006,-.01878,-.0098,-.02123,-.01143,0.0*
1,1,.006,-.02123,-.01143*
20,1,.006,-.02123,-.01143,-.0245,-.01225,0.0*
1,1,.006,-.0245,-.01225*
20,1,.006,-.0245,-.01225,-.02736,-.01184,0.0*
1,1,.006,-.02736,-.01184*
20,1,.006,-.02736,-.01184,-.03022,-.01062,0.0*
1,1,.006,-.03022,-.01062*
20,1,.006,-.03022,-.01062,-.03185,-.00898,0.0*
1,1,.006,-.03185,-.00898*
1,1,.006,-.00611,-.00123*
20,1,.006,-.00611,-.00123,.00695,-.00123,0.0*
1,1,.006,.00695,-.00123*
20,1,.006,.00695,-.00123,.00573,.00163,0.0*
1,1,.006,.00573,.00163*
20,1,.006,.00573,.00163,.00369,.00327,0.0*
1,1,.006,.00369,.00327*
20,1,.006,.00369,.00327,.00083,.00408,0.0*
1,1,.006,.00083,.00408*
20,1,.006,.00083,.00408,-.00203,.00367,0.0*
1,1,.006,-.00203,.00367*
20,1,.006,-.00203,.00367,-.00448,.00245,0.0*
1,1,.006,-.00448,.00245*
20,1,.006,-.00448,.00245,-.00611,-.00041,0.0*
1,1,.006,-.00611,-.00041*
20,1,.006,-.00611,-.00041,-.00693,-.00286,0.0*
1,1,.006,-.00693,-.00286*
20,1,.006,-.00693,-.00286,-.00693,-.00531,0.0*
1,1,.006,-.00693,-.00531*
20,1,.006,-.00693,-.00531,-.00611,-.00776,0.0*
1,1,.006,-.00611,-.00776*
20,1,.006,-.00611,-.00776,-.00407,-.01021,0.0*
1,1,.006,-.00407,-.01021*
20,1,.006,-.00407,-.01021,-.00162,-.01184,0.0*
1,1,.006,-.00162,-.01184*
20,1,.006,-.00162,-.01184,.00124,-.01225,0.0*
1,1,.006,.00124,-.01225*
20,1,.006,.00124,-.01225,.00409,-.01143,0.0*
1,1,.006,.00409,-.01143*
20,1,.006,.00409,-.01143,.00695,-.00898,0.0*
1,1,.006,.00695,-.00898*
1,1,.006,.01717,-.02042*
20,1,.006,.01717,-.02042,.01717,.00408,0.0*
1,1,.006,.01717,.00408*
1,1,.006,.01717,.00041*
20,1,.006,.01717,.00041,.01921,.00245,0.0*
1,1,.006,.01921,.00245*
20,1,.006,.01921,.00245,.02125,.00367,0.0*
1,1,.006,.02125,.00367*
20,1,.006,.02125,.00367,.02452,.00408,0.0*
1,1,.006,.02452,.00408*
20,1,.006,.02452,.00408,.02738,.00367,0.0*
1,1,.006,.02738,.00367*
20,1,.006,.02738,.00367,.03024,.00163,0.0*
1,1,.006,.03024,.00163*
20,1,.006,.03024,.00163,.03146,-.00123,0.0*
1,1,.006,.03146,-.00123*
20,1,.006,.03146,-.00123,.03187,-.00408,0.0*
1,1,.006,.03187,-.00408*
20,1,.006,.03187,-.00408,.03146,-.00694,0.0*
1,1,.006,.03146,-.00694*
20,1,.006,.03146,-.00694,.03024,-.0098,0.0*
1,1,.006,.03024,-.0098*
20,1,.006,.03024,-.0098,.02779,-.01143,0.0*
1,1,.006,.02779,-.01143*
20,1,.006,.02779,-.01143,.02452,-.01225,0.0*
1,1,.006,.02452,-.01225*
20,1,.006,.02452,-.01225,.02166,-.01184,0.0*
1,1,.006,.02166,-.01184*
20,1,.006,.02166,-.01184,.0188,-.01062,0.0*
1,1,.006,.0188,-.01062*
20,1,.006,.0188,-.01062,.01717,-.00898,0.0*
1,1,.006,.01717,-.00898*
%
%ADD30MACRO30*%
%AMMACRO16*
1,1,.006,0.0,.0395*
20,1,.006,0.0,.0395,.034208,-.01975,0.0*
1,1,.006,.034208,-.01975*
20,1,.006,.034208,-.01975,-.034208,-.01975,0.0*
1,1,.006,-.034208,-.01975*
20,1,.006,-.034208,-.01975,0.0,.0395,0.0*
1,1,.006,0.0,.0395*
1,1,.006,-.01244,.00622*
20,1,.006,-.01244,.00622,-.0141,.00581,0.0*
1,1,.006,-.0141,.00581*
20,1,.006,-.0141,.00581,-.01534,.00477,0.0*
1,1,.006,-.01534,.00477*
20,1,.006,-.01534,.00477,-.01617,.00352,0.0*
1,1,.006,-.01617,.00352*
20,1,.006,-.01617,.00352,-.01679,.00187,0.0*
1,1,.006,-.01679,.00187*
20,1,.006,-.01679,.00187,-.017,0.0,0.0*
1,1,.006,-.017,0.0*
20,1,.006,-.017,0.0,-.01679,-.00187,0.0*
1,1,.006,-.01679,-.00187*
20,1,.006,-.01679,-.00187,-.01617,-.00352,0.0*
1,1,.006,-.01617,-.00352*
20,1,.006,-.01617,-.00352,-.01534,-.00477,0.0*
1,1,.006,-.01534,-.00477*
20,1,.006,-.01534,-.00477,-.0141,-.00581,0.0*
1,1,.006,-.0141,-.00581*
20,1,.006,-.0141,-.00581,-.01244,-.00622,0.0*
1,1,.006,-.01244,-.00622*
20,1,.006,-.01244,-.00622,-.01078,-.00581,0.0*
1,1,.006,-.01078,-.00581*
20,1,.006,-.01078,-.00581,-.00954,-.00477,0.0*
1,1,.006,-.00954,-.00477*
20,1,.006,-.00954,-.00477,-.00871,-.00352,0.0*
1,1,.006,-.00871,-.00352*
20,1,.006,-.00871,-.00352,-.00809,-.00187,0.0*
1,1,.006,-.00809,-.00187*
20,1,.006,-.00809,-.00187,-.00788,0.0,0.0*
1,1,.006,-.00788,0.0*
20,1,.006,-.00788,0.0,-.00809,.00187,0.0*
1,1,.006,-.00809,.00187*
20,1,.006,-.00809,.00187,-.00871,.00352,0.0*
1,1,.006,-.00871,.00352*
20,1,.006,-.00871,.00352,-.00954,.00477,0.0*
1,1,.006,-.00954,.00477*
20,1,.006,-.00954,.00477,-.01078,.00581,0.0*
1,1,.006,-.01078,.00581*
20,1,.006,-.01078,.00581,-.01244,.00622,0.0*
1,1,.006,-.01244,.00622*
1,1,.006,-.0004,-.00622*
20,1,.006,-.0004,-.00622,.00001,-.00352,0.0*
1,1,.006,.00001,-.00352*
20,1,.006,.00001,-.00352,.00063,-.00124,0.0*
1,1,.006,.00063,-.00124*
20,1,.006,.00063,-.00124,.00146,.00083,0.0*
1,1,.006,.00146,.00083*
20,1,.006,.00146,.00083,.0025,.00311,0.0*
1,1,.006,.0025,.00311*
20,1,.006,.0025,.00311,.00416,.00622,0.0*
1,1,.006,.00416,.00622*
20,1,.006,.00416,.00622,-.00414,.00622,0.0*
1,1,.006,-.00414,.00622*
1,1,.006,.00894,-.00477*
20,1,.006,.00894,-.00477,.01039,-.00581,0.0*
1,1,.006,.01039,-.00581*
20,1,.006,.01039,-.00581,.01205,-.00622,0.0*
1,1,.006,.01205,-.00622*
20,1,.006,.01205,-.00622,.0137,-.00581,0.0*
1,1,.006,.0137,-.00581*
20,1,.006,.0137,-.00581,.01516,-.00456,0.0*
1,1,.006,.01516,-.00456*
20,1,.006,.01516,-.00456,.01619,-.0027,0.0*
1,1,.006,.01619,-.0027*
20,1,.006,.01619,-.0027,.01661,-.00083,0.0*
1,1,.006,.01661,-.00083*
20,1,.006,.01661,-.00083,.01661,.00145,0.0*
1,1,.006,.01661,.00145*
20,1,.006,.01661,.00145,.01619,.00332,0.0*
1,1,.006,.01619,.00332*
20,1,.006,.01619,.00332,.01516,.00498,0.0*
1,1,.006,.01516,.00498*
20,1,.006,.01516,.00498,.01391,.00581,0.0*
1,1,.006,.01391,.00581*
20,1,.006,.01391,.00581,.01246,.00622,0.0*
1,1,.006,.01246,.00622*
20,1,.006,.01246,.00622,.0108,.00581,0.0*
1,1,.006,.0108,.00581*
20,1,.006,.0108,.00581,.00956,.00498,0.0*
1,1,.006,.00956,.00498*
20,1,.006,.00956,.00498,.00873,.00373,0.0*
1,1,.006,.00873,.00373*
20,1,.006,.00873,.00373,.00831,.00207,0.0*
1,1,.006,.00831,.00207*
20,1,.006,.00831,.00207,.00873,.00062,0.0*
1,1,.006,.00873,.00062*
20,1,.006,.00873,.00062,.00976,-.00083,0.0*
1,1,.006,.00976,-.00083*
20,1,.006,.00976,-.00083,.01101,-.00166,0.0*
1,1,.006,.01101,-.00166*
20,1,.006,.01101,-.00166,.01246,-.00187,0.0*
1,1,.006,.01246,-.00187*
20,1,.006,.01246,-.00187,.01412,-.00145,0.0*
1,1,.006,.01412,-.00145*
20,1,.006,.01412,-.00145,.01536,-.00041,0.0*
1,1,.006,.01536,-.00041*
20,1,.006,.01536,-.00041,.01661,.00145,0.0*
1,1,.006,.01661,.00145*
%
%ADD16MACRO16*%
%AMMACRO15*
1,1,.006,.045771,-.1105*
20,1,.006,.045771,-.1105,-.045771,-.1105,0.0*
1,1,.006,-.045771,-.1105*
20,1,.006,-.045771,-.1105,-.1105,-.045771,0.0*
1,1,.006,-.1105,-.045771*
20,1,.006,-.1105,-.045771,-.1105,.045771,0.0*
1,1,.006,-.1105,.045771*
20,1,.006,-.1105,.045771,-.045771,.1105,0.0*
1,1,.006,-.045771,.1105*
20,1,.006,-.045771,.1105,.045771,.1105,0.0*
1,1,.006,.045771,.1105*
20,1,.006,.045771,.1105,.1105,.045771,0.0*
1,1,.006,.1105,.045771*
20,1,.006,.1105,.045771,.1105,-.045771,0.0*
1,1,.006,.1105,-.045771*
20,1,.006,.1105,-.045771,.045771,-.1105,0.0*
1,1,.006,.045771,-.1105*
1,1,.006,-.08657,.02192*
20,1,.006,-.08657,.02192,-.07999,.0285,0.0*
1,1,.006,-.07999,.0285*
20,1,.006,-.07999,.0285,-.07232,.03178,0.0*
1,1,.006,-.07232,.03178*
20,1,.006,-.07232,.03178,-.06355,.03288,0.0*
1,1,.006,-.06355,.03288*
20,1,.006,-.06355,.03288,-.05259,.03069,0.0*
1,1,.006,-.05259,.03069*
20,1,.006,-.05259,.03069,-.04492,.02521,0.0*
1,1,.006,-.04492,.02521*
20,1,.006,-.04492,.02521,-.04273,.01864,0.0*
1,1,.006,-.04273,.01864*
20,1,.006,-.04273,.01864,-.04383,.01206,0.0*
1,1,.006,-.04383,.01206*
20,1,.006,-.04383,.01206,-.04821,.00658,0.0*
1,1,.006,-.04821,.00658*
20,1,.006,-.04821,.00658,-.07013,-.00438,0.0*
1,1,.006,-.07013,-.00438*
20,1,.006,-.07013,-.00438,-.07999,-.01205,0.0*
1,1,.006,-.07999,-.01205*
20,1,.006,-.07999,-.01205,-.08657,-.02301,0.0*
1,1,.006,-.08657,-.02301*
20,1,.006,-.08657,-.02301,-.08876,-.03287,0.0*
1,1,.006,-.08876,-.03287*
20,1,.006,-.08876,-.03287,-.04273,-.03287,0.0*
1,1,.006,-.04273,-.03287*
1,1,.006,-.02081,.02192*
20,1,.006,-.02081,.02192,-.01423,.0285,0.0*
1,1,.006,-.01423,.0285*
20,1,.006,-.01423,.0285,-.00656,.03178,0.0*
1,1,.006,-.00656,.03178*
20,1,.006,-.00656,.03178,.00221,.03288,0.0*
1,1,.006,.00221,.03288*
20,1,.006,.00221,.03288,.01317,.03069,0.0*
1,1,.006,.01317,.03069*
20,1,.006,.01317,.03069,.02084,.02521,0.0*
1,1,.006,.02084,.02521*
20,1,.006,.02084,.02521,.02303,.01864,0.0*
1,1,.006,.02303,.01864*
20,1,.006,.02303,.01864,.02193,.01206,0.0*
1,1,.006,.02193,.01206*
20,1,.006,.02193,.01206,.01755,.00658,0.0*
1,1,.006,.01755,.00658*
20,1,.006,.01755,.00658,-.00437,-.00438,0.0*
1,1,.006,-.00437,-.00438*
20,1,.006,-.00437,-.00438,-.01423,-.01205,0.0*
1,1,.006,-.01423,-.01205*
20,1,.006,-.01423,-.01205,-.02081,-.02301,0.0*
1,1,.006,-.02081,-.02301*
20,1,.006,-.02081,-.02301,-.023,-.03287,0.0*
1,1,.006,-.023,-.03287*
20,1,.006,-.023,-.03287,.02303,-.03287,0.0*
1,1,.006,.02303,-.03287*
1,1,.006,.06577,-.03287*
20,1,.006,.06577,-.03287,.06577,.03288,0.0*
1,1,.006,.06577,.03288*
20,1,.006,.06577,.03288,.05262,.01973,0.0*
1,1,.006,.05262,.01973*
1,1,.006,.05262,-.03287*
20,1,.006,.05262,-.03287,.07892,-.03287,0.0*
1,1,.006,.07892,-.03287*
%
%ADD15MACRO15*%
%AMMACRO22*
1,1,.006,-.1246,-.14833*
20,1,.006,-.1246,-.14833,-.1246,.02966,0.0*
1,1,.006,-.1246,.02966*
1,1,.006,-.1246,.00297*
20,1,.006,-.1246,.00297,-.13943,.0178,0.0*
1,1,.006,-.13943,.0178*
20,1,.006,-.13943,.0178,-.15724,.0267,0.0*
1,1,.006,-.15724,.0267*
20,1,.006,-.15724,.0267,-.178,.02966,0.0*
1,1,.006,-.178,.02966*
20,1,.006,-.178,.02966,-.1958,.0267,0.0*
1,1,.006,-.1958,.0267*
20,1,.006,-.1958,.0267,-.21657,.01187,0.0*
1,1,.006,-.21657,.01187*
20,1,.006,-.21657,.01187,-.22844,-.0089,0.0*
1,1,.006,-.22844,-.0089*
20,1,.006,-.22844,-.0089,-.2314,-.02967,0.0*
1,1,.006,-.2314,-.02967*
20,1,.006,-.2314,-.02967,-.22844,-.05044,0.0*
1,1,.006,-.22844,-.05044*
20,1,.006,-.22844,-.05044,-.21657,-.0712,0.0*
1,1,.006,-.21657,-.0712*
20,1,.006,-.21657,-.0712,-.1958,-.08603,0.0*
1,1,.006,-.1958,-.08603*
20,1,.006,-.1958,-.08603,-.178,-.089,0.0*
1,1,.006,-.178,-.089*
20,1,.006,-.178,-.089,-.15724,-.08603,0.0*
1,1,.006,-.15724,-.08603*
20,1,.006,-.15724,-.08603,-.13943,-.07714,0.0*
1,1,.006,-.13943,-.07714*
20,1,.006,-.13943,-.07714,-.1246,-.06231,0.0*
1,1,.006,-.1246,-.06231*
1,1,.006,-.05043,.02966*
20,1,.006,-.05043,.02966,-.05043,-.0534,0.0*
1,1,.006,-.05043,-.0534*
20,1,.006,-.05043,-.0534,-.03856,-.07417,0.0*
1,1,.006,-.03856,-.07417*
20,1,.006,-.03856,-.07417,-.02075,-.08603,0.0*
1,1,.006,-.02075,-.08603*
20,1,.006,-.02075,-.08603,.00001,-.089,0.0*
1,1,.006,.00001,-.089*
20,1,.006,.00001,-.089,.02077,-.08603,0.0*
1,1,.006,.02077,-.08603*
20,1,.006,.02077,-.08603,.03858,-.07417,0.0*
1,1,.006,.03858,-.07417*
20,1,.006,.03858,-.07417,.05045,-.0534,0.0*
1,1,.006,.05045,-.0534*
1,1,.006,.05045,-.089*
20,1,.006,.05045,-.089,.05045,.02966,0.0*
1,1,.006,.05045,.02966*
1,1,.006,.17802,.02966*
20,1,.006,.17802,.02966,.17802,-.089,0.0*
1,1,.006,.17802,-.089*
1,1,.006,.17802,.07713*
20,1,.006,.17802,.07713,.17209,.0801,0.0*
1,1,.006,.17209,.0801*
20,1,.006,.17209,.0801,.17209,.08603,0.0*
1,1,.006,.17209,.08603*
20,1,.006,.17209,.08603,.17802,.089,0.0*
1,1,.006,.17802,.089*
20,1,.006,.17802,.089,.18395,.08603,0.0*
1,1,.006,.18395,.08603*
20,1,.006,.18395,.08603,.18395,.0801,0.0*
1,1,.006,.18395,.0801*
20,1,.006,.18395,.0801,.17802,.07713,0.0*
1,1,.006,.17802,.07713*
%
%ADD22MACRO22*%
%AMMACRO13*
1,1,.006,.035,0.0*
20,1,.006,.035,0.0,.034468,-.006078,0.0*
1,1,.006,.034468,-.006078*
20,1,.006,.034468,-.006078,.032889,-.011971,0.0*
1,1,.006,.032889,-.011971*
20,1,.006,.032889,-.011971,.030311,-.0175,0.0*
1,1,.006,.030311,-.0175*
20,1,.006,.030311,-.0175,.026812,-.022498,0.0*
1,1,.006,.026812,-.022498*
20,1,.006,.026812,-.022498,.022498,-.026812,0.0*
1,1,.006,.022498,-.026812*
20,1,.006,.022498,-.026812,.0175,-.030311,0.0*
1,1,.006,.0175,-.030311*
20,1,.006,.0175,-.030311,.011971,-.032889,0.0*
1,1,.006,.011971,-.032889*
20,1,.006,.011971,-.032889,.006078,-.034468,0.0*
1,1,.006,.006078,-.034468*
20,1,.006,.006078,-.034468,0.0,-.035,0.0*
1,1,.006,0.0,-.035*
20,1,.006,0.0,-.035,-.006078,-.034468,0.0*
1,1,.006,-.006078,-.034468*
20,1,.006,-.006078,-.034468,-.011971,-.032889,0.0*
1,1,.006,-.011971,-.032889*
20,1,.006,-.011971,-.032889,-.0175,-.030311,0.0*
1,1,.006,-.0175,-.030311*
20,1,.006,-.0175,-.030311,-.022498,-.026812,0.0*
1,1,.006,-.022498,-.026812*
20,1,.006,-.022498,-.026812,-.026812,-.022498,0.0*
1,1,.006,-.026812,-.022498*
20,1,.006,-.026812,-.022498,-.030311,-.0175,0.0*
1,1,.006,-.030311,-.0175*
20,1,.006,-.030311,-.0175,-.032889,-.011971,0.0*
1,1,.006,-.032889,-.011971*
20,1,.006,-.032889,-.011971,-.034468,-.006078,0.0*
1,1,.006,-.034468,-.006078*
20,1,.006,-.034468,-.006078,-.035,0.0,0.0*
1,1,.006,-.035,0.0*
20,1,.006,-.035,0.0,-.034468,.006078,0.0*
1,1,.006,-.034468,.006078*
20,1,.006,-.034468,.006078,-.032889,.011971,0.0*
1,1,.006,-.032889,.011971*
20,1,.006,-.032889,.011971,-.030311,.0175,0.0*
1,1,.006,-.030311,.0175*
20,1,.006,-.030311,.0175,-.026812,.022498,0.0*
1,1,.006,-.026812,.022498*
20,1,.006,-.026812,.022498,-.022498,.026812,0.0*
1,1,.006,-.022498,.026812*
20,1,.006,-.022498,.026812,-.0175,.030311,0.0*
1,1,.006,-.0175,.030311*
20,1,.006,-.0175,.030311,-.011971,.032889,0.0*
1,1,.006,-.011971,.032889*
20,1,.006,-.011971,.032889,-.006078,.034468,0.0*
1,1,.006,-.006078,.034468*
20,1,.006,-.006078,.034468,0.0,.035,0.0*
1,1,.006,0.0,.035*
20,1,.006,0.0,.035,.006078,.034468,0.0*
1,1,.006,.006078,.034468*
20,1,.006,.006078,.034468,.011971,.032889,0.0*
1,1,.006,.011971,.032889*
20,1,.006,.011971,.032889,.0175,.030311,0.0*
1,1,.006,.0175,.030311*
20,1,.006,.0175,.030311,.022498,.026812,0.0*
1,1,.006,.022498,.026812*
20,1,.006,.022498,.026812,.026812,.022498,0.0*
1,1,.006,.026812,.022498*
20,1,.006,.026812,.022498,.030311,.0175,0.0*
1,1,.006,.030311,.0175*
20,1,.006,.030311,.0175,.032889,.011971,0.0*
1,1,.006,.032889,.011971*
20,1,.006,.032889,.011971,.034468,.006078,0.0*
1,1,.006,.034468,.006078*
20,1,.006,.034468,.006078,.035,0.0,0.0*
1,1,.006,.035,0.0*
1,1,.006,-.02082,.01041*
20,1,.006,-.02082,.01041,-.02082,-.01041,0.0*
1,1,.006,-.02082,-.01041*
1,1,.006,-.0288,.01041*
20,1,.006,-.0288,.01041,-.01284,.01041,0.0*
1,1,.006,-.01284,.01041*
1,1,.006,-.00693,-.01041*
20,1,.006,-.00693,-.01041,-.00693,.01041,0.0*
1,1,.006,-.00693,.01041*
20,1,.006,-.00693,.01041,.0014,.01041,0.0*
1,1,.006,.0014,.01041*
20,1,.006,.0014,.01041,.00417,.00937,0.0*
1,1,.006,.00417,.00937*
20,1,.006,.00417,.00937,.00626,.00694,0.0*
1,1,.006,.00626,.00694*
20,1,.006,.00626,.00694,.00695,.00416,0.0*
1,1,.006,.00695,.00416*
20,1,.006,.00695,.00416,.00626,.00139,0.0*
1,1,.006,.00626,.00139*
20,1,.006,.00626,.00139,.00452,-.00069,0.0*
1,1,.006,.00452,-.00069*
20,1,.006,.00452,-.00069,.0014,-.00174,0.0*
1,1,.006,.0014,-.00174*
20,1,.006,.0014,-.00174,-.00693,-.00174,0.0*
1,1,.006,-.00693,-.00174*
1,1,.006,.01216,.01041*
20,1,.006,.01216,.01041,.02084,-.01041,0.0*
1,1,.006,.02084,-.01041*
20,1,.006,.02084,-.01041,.02952,.01041,0.0*
1,1,.006,.02952,.01041*
%
%ADD13MACRO13*%
%AMMACRO21*
1,1,.006,.035,.035*
20,1,.006,.035,.035,.035,-.035,0.0*
1,1,.006,.035,-.035*
20,1,.006,.035,-.035,-.035,-.035,0.0*
1,1,.006,-.035,-.035*
20,1,.006,-.035,-.035,-.035,.035,0.0*
1,1,.006,-.035,.035*
20,1,.006,-.035,.035,.035,.035,0.0*
1,1,.006,.035,.035*
1,1,.006,-.0245,.01225*
20,1,.006,-.0245,.01225,-.02777,.01143,0.0*
1,1,.006,-.02777,.01143*
20,1,.006,-.02777,.01143,-.03022,.00939,0.0*
1,1,.006,-.03022,.00939*
20,1,.006,-.03022,.00939,-.03185,.00694,0.0*
1,1,.006,-.03185,.00694*
20,1,.006,-.03185,.00694,-.03308,.00367,0.0*
1,1,.006,-.03308,.00367*
20,1,.006,-.03308,.00367,-.03348,0.0,0.0*
1,1,.006,-.03348,0.0*
20,1,.006,-.03348,0.0,-.03308,-.00368,0.0*
1,1,.006,-.03308,-.00368*
20,1,.006,-.03308,-.00368,-.03185,-.00694,0.0*
1,1,.006,-.03185,-.00694*
20,1,.006,-.03185,-.00694,-.03022,-.00939,0.0*
1,1,.006,-.03022,-.00939*
20,1,.006,-.03022,-.00939,-.02777,-.01143,0.0*
1,1,.006,-.02777,-.01143*
20,1,.006,-.02777,-.01143,-.0245,-.01225,0.0*
1,1,.006,-.0245,-.01225*
20,1,.006,-.0245,-.01225,-.02123,-.01143,0.0*
1,1,.006,-.02123,-.01143*
20,1,.006,-.02123,-.01143,-.01878,-.00939,0.0*
1,1,.006,-.01878,-.00939*
20,1,.006,-.01878,-.00939,-.01715,-.00694,0.0*
1,1,.006,-.01715,-.00694*
20,1,.006,-.01715,-.00694,-.01592,-.00368,0.0*
1,1,.006,-.01592,-.00368*
20,1,.006,-.01592,-.00368,-.01552,0.0,0.0*
1,1,.006,-.01552,0.0*
20,1,.006,-.01552,0.0,-.01592,.00367,0.0*
1,1,.006,-.01592,.00367*
20,1,.006,-.01592,.00367,-.01715,.00694,0.0*
1,1,.006,-.01715,.00694*
20,1,.006,-.01715,.00694,-.01878,.00939,0.0*
1,1,.006,-.01878,.00939*
20,1,.006,-.01878,.00939,-.02123,.01143,0.0*
1,1,.006,-.02123,.01143*
20,1,.006,-.02123,.01143,-.0245,.01225,0.0*
1,1,.006,-.0245,.01225*
1,1,.006,-.00775,.00817*
20,1,.006,-.00775,.00817,-.0053,.01062,0.0*
1,1,.006,-.0053,.01062*
20,1,.006,-.0053,.01062,-.00244,.01184,0.0*
1,1,.006,-.00244,.01184*
20,1,.006,-.00244,.01184,.00083,.01225,0.0*
1,1,.006,.00083,.01225*
20,1,.006,.00083,.01225,.00491,.01143,0.0*
1,1,.006,.00491,.01143*
20,1,.006,.00491,.01143,.00777,.00939,0.0*
1,1,.006,.00777,.00939*
20,1,.006,.00777,.00939,.00859,.00694,0.0*
1,1,.006,.00859,.00694*
20,1,.006,.00859,.00694,.00818,.00449,0.0*
1,1,.006,.00818,.00449*
20,1,.006,.00818,.00449,.00654,.00245,0.0*
1,1,.006,.00654,.00245*
20,1,.006,.00654,.00245,-.00162,-.00163,0.0*
1,1,.006,-.00162,-.00163*
20,1,.006,-.00162,-.00163,-.0053,-.00449,0.0*
1,1,.006,-.0053,-.00449*
20,1,.006,-.0053,-.00449,-.00775,-.00858,0.0*
1,1,.006,-.00775,-.00858*
20,1,.006,-.00775,-.00858,-.00857,-.01225,0.0*
1,1,.006,-.00857,-.01225*
20,1,.006,-.00857,-.01225,.00859,-.01225,0.0*
1,1,.006,.00859,-.01225*
1,1,.006,.01676,.00817*
20,1,.006,.01676,.00817,.01921,.01062,0.0*
1,1,.006,.01921,.01062*
20,1,.006,.01921,.01062,.02207,.01184,0.0*
1,1,.006,.02207,.01184*
20,1,.006,.02207,.01184,.02534,.01225,0.0*
1,1,.006,.02534,.01225*
20,1,.006,.02534,.01225,.02942,.01143,0.0*
1,1,.006,.02942,.01143*
20,1,.006,.02942,.01143,.03228,.00939,0.0*
1,1,.006,.03228,.00939*
20,1,.006,.03228,.00939,.0331,.00694,0.0*
1,1,.006,.0331,.00694*
20,1,.006,.0331,.00694,.03269,.00449,0.0*
1,1,.006,.03269,.00449*
20,1,.006,.03269,.00449,.03105,.00245,0.0*
1,1,.006,.03105,.00245*
20,1,.006,.03105,.00245,.02289,-.00163,0.0*
1,1,.006,.02289,-.00163*
20,1,.006,.02289,-.00163,.01921,-.00449,0.0*
1,1,.006,.01921,-.00449*
20,1,.006,.01921,-.00449,.01676,-.00858,0.0*
1,1,.006,.01676,-.00858*
20,1,.006,.01676,-.00858,.01594,-.01225,0.0*
1,1,.006,.01594,-.01225*
20,1,.006,.01594,-.01225,.0331,-.01225,0.0*
1,1,.006,.0331,-.01225*
%
%ADD21MACRO21*%
%AMMACRO28*
1,1,.006,.035,.035*
20,1,.006,.035,.035,.035,-.035,0.0*
1,1,.006,.035,-.035*
20,1,.006,.035,-.035,-.035,-.035,0.0*
1,1,.006,-.035,-.035*
20,1,.006,-.035,-.035,-.035,.035,0.0*
1,1,.006,-.035,.035*
20,1,.006,-.035,.035,.035,.035,0.0*
1,1,.006,.035,.035*
1,1,.006,-.0245,.01225*
20,1,.006,-.0245,.01225,-.02777,.01143,0.0*
1,1,.006,-.02777,.01143*
20,1,.006,-.02777,.01143,-.03022,.00939,0.0*
1,1,.006,-.03022,.00939*
20,1,.006,-.03022,.00939,-.03185,.00694,0.0*
1,1,.006,-.03185,.00694*
20,1,.006,-.03185,.00694,-.03308,.00367,0.0*
1,1,.006,-.03308,.00367*
20,1,.006,-.03308,.00367,-.03348,0.0,0.0*
1,1,.006,-.03348,0.0*
20,1,.006,-.03348,0.0,-.03308,-.00368,0.0*
1,1,.006,-.03308,-.00368*
20,1,.006,-.03308,-.00368,-.03185,-.00694,0.0*
1,1,.006,-.03185,-.00694*
20,1,.006,-.03185,-.00694,-.03022,-.00939,0.0*
1,1,.006,-.03022,-.00939*
20,1,.006,-.03022,-.00939,-.02777,-.01143,0.0*
1,1,.006,-.02777,-.01143*
20,1,.006,-.02777,-.01143,-.0245,-.01225,0.0*
1,1,.006,-.0245,-.01225*
20,1,.006,-.0245,-.01225,-.02123,-.01143,0.0*
1,1,.006,-.02123,-.01143*
20,1,.006,-.02123,-.01143,-.01878,-.00939,0.0*
1,1,.006,-.01878,-.00939*
20,1,.006,-.01878,-.00939,-.01715,-.00694,0.0*
1,1,.006,-.01715,-.00694*
20,1,.006,-.01715,-.00694,-.01592,-.00368,0.0*
1,1,.006,-.01592,-.00368*
20,1,.006,-.01592,-.00368,-.01552,0.0,0.0*
1,1,.006,-.01552,0.0*
20,1,.006,-.01552,0.0,-.01592,.00367,0.0*
1,1,.006,-.01592,.00367*
20,1,.006,-.01592,.00367,-.01715,.00694,0.0*
1,1,.006,-.01715,.00694*
20,1,.006,-.01715,.00694,-.01878,.00939,0.0*
1,1,.006,-.01878,.00939*
20,1,.006,-.01878,.00939,-.02123,.01143,0.0*
1,1,.006,-.02123,.01143*
20,1,.006,-.02123,.01143,-.0245,.01225,0.0*
1,1,.006,-.0245,.01225*
1,1,.006,-.00897,-.00735*
20,1,.006,-.00897,-.00735,-.00652,-.01021,0.0*
1,1,.006,-.00652,-.01021*
20,1,.006,-.00652,-.01021,-.00326,-.01184,0.0*
1,1,.006,-.00326,-.01184*
20,1,.006,-.00326,-.01184,.00042,-.01225,0.0*
1,1,.006,.00042,-.01225*
20,1,.006,.00042,-.01225,.00369,-.01184,0.0*
1,1,.006,.00369,-.01184*
20,1,.006,.00369,-.01184,.00695,-.0098,0.0*
1,1,.006,.00695,-.0098*
20,1,.006,.00695,-.0098,.00899,-.00735,0.0*
1,1,.006,.00899,-.00735*
20,1,.006,.00899,-.00735,.0094,-.0049,0.0*
1,1,.006,.0094,-.0049*
20,1,.006,.0094,-.0049,.00859,-.00204,0.0*
1,1,.006,.00859,-.00204*
20,1,.006,.00859,-.00204,.00573,0.0,0.0*
1,1,.006,.00573,0.0*
20,1,.006,.00573,0.0,.00287,.00082,0.0*
1,1,.006,.00287,.00082*
20,1,.006,.00287,.00082,-.00081,.00082,0.0*
1,1,.006,-.00081,.00082*
1,1,.006,.00287,.00082*
20,1,.006,.00287,.00082,.00532,.00204,0.0*
1,1,.006,.00532,.00204*
20,1,.006,.00532,.00204,.00736,.00408,0.0*
1,1,.006,.00736,.00408*
20,1,.006,.00736,.00408,.00818,.00653,0.0*
1,1,.006,.00818,.00653*
20,1,.006,.00818,.00653,.00736,.00898,0.0*
1,1,.006,.00736,.00898*
20,1,.006,.00736,.00898,.00532,.01102,0.0*
1,1,.006,.00532,.01102*
20,1,.006,.00532,.01102,.00164,.01225,0.0*
1,1,.006,.00164,.01225*
20,1,.006,.00164,.01225,-.00203,.01184,0.0*
1,1,.006,-.00203,.01184*
20,1,.006,-.00203,.01184,-.00571,.01021,0.0*
1,1,.006,-.00571,.01021*
1,1,.006,.01676,.00817*
20,1,.006,.01676,.00817,.01921,.01062,0.0*
1,1,.006,.01921,.01062*
20,1,.006,.01921,.01062,.02207,.01184,0.0*
1,1,.006,.02207,.01184*
20,1,.006,.02207,.01184,.02534,.01225,0.0*
1,1,.006,.02534,.01225*
20,1,.006,.02534,.01225,.02942,.01143,0.0*
1,1,.006,.02942,.01143*
20,1,.006,.02942,.01143,.03228,.00939,0.0*
1,1,.006,.03228,.00939*
20,1,.006,.03228,.00939,.0331,.00694,0.0*
1,1,.006,.0331,.00694*
20,1,.006,.0331,.00694,.03269,.00449,0.0*
1,1,.006,.03269,.00449*
20,1,.006,.03269,.00449,.03105,.00245,0.0*
1,1,.006,.03105,.00245*
20,1,.006,.03105,.00245,.02289,-.00163,0.0*
1,1,.006,.02289,-.00163*
20,1,.006,.02289,-.00163,.01921,-.00449,0.0*
1,1,.006,.01921,-.00449*
20,1,.006,.01921,-.00449,.01676,-.00858,0.0*
1,1,.006,.01676,-.00858*
20,1,.006,.01676,-.00858,.01594,-.01225,0.0*
1,1,.006,.01594,-.01225*
20,1,.006,.01594,-.01225,.0331,-.01225,0.0*
1,1,.006,.0331,-.01225*
%
%ADD28MACRO28*%
%AMMACRO34*
1,1,.006,-.01,-.0215*
20,1,.006,-.01,-.0215,-.01,.0215,0.0*
1,1,.006,-.01,.0215*
20,1,.006,-.01,.0215,-.009848,.023236,0.0*
1,1,.006,-.009848,.023236*
20,1,.006,-.009848,.023236,-.009397,.02492,0.0*
1,1,.006,-.009397,.02492*
20,1,.006,-.009397,.02492,-.00866,.0265,0.0*
1,1,.006,-.00866,.0265*
20,1,.006,-.00866,.0265,-.00766,.027928,0.0*
1,1,.006,-.00766,.027928*
20,1,.006,-.00766,.027928,-.006428,.02916,0.0*
1,1,.006,-.006428,.02916*
20,1,.006,-.006428,.02916,-.005,.03016,0.0*
1,1,.006,-.005,.03016*
20,1,.006,-.005,.03016,-.00342,.030897,0.0*
1,1,.006,-.00342,.030897*
20,1,.006,-.00342,.030897,-.001736,.031348,0.0*
1,1,.006,-.001736,.031348*
20,1,.006,-.001736,.031348,0.0,.0315,0.0*
1,1,.006,0.0,.0315*
20,1,.006,0.0,.0315,.001736,.031348,0.0*
1,1,.006,.001736,.031348*
20,1,.006,.001736,.031348,.00342,.030897,0.0*
1,1,.006,.00342,.030897*
20,1,.006,.00342,.030897,.005,.03016,0.0*
1,1,.006,.005,.03016*
20,1,.006,.005,.03016,.006428,.02916,0.0*
1,1,.006,.006428,.02916*
20,1,.006,.006428,.02916,.00766,.027928,0.0*
1,1,.006,.00766,.027928*
20,1,.006,.00766,.027928,.00866,.0265,0.0*
1,1,.006,.00866,.0265*
20,1,.006,.00866,.0265,.009397,.02492,0.0*
1,1,.006,.009397,.02492*
20,1,.006,.009397,.02492,.009848,.023236,0.0*
1,1,.006,.009848,.023236*
20,1,.006,.009848,.023236,.01,.0215,0.0*
1,1,.006,.01,.0215*
20,1,.006,.01,.0215,.01,-.0215,0.0*
1,1,.006,.01,-.0215*
20,1,.006,.01,-.0215,.009848,-.023236,0.0*
1,1,.006,.009848,-.023236*
20,1,.006,.009848,-.023236,.009397,-.02492,0.0*
1,1,.006,.009397,-.02492*
20,1,.006,.009397,-.02492,.00866,-.0265,0.0*
1,1,.006,.00866,-.0265*
20,1,.006,.00866,-.0265,.00766,-.027928,0.0*
1,1,.006,.00766,-.027928*
20,1,.006,.00766,-.027928,.006428,-.02916,0.0*
1,1,.006,.006428,-.02916*
20,1,.006,.006428,-.02916,.005,-.03016,0.0*
1,1,.006,.005,-.03016*
20,1,.006,.005,-.03016,.00342,-.030897,0.0*
1,1,.006,.00342,-.030897*
20,1,.006,.00342,-.030897,.001736,-.031348,0.0*
1,1,.006,.001736,-.031348*
20,1,.006,.001736,-.031348,0.0,-.0315,0.0*
1,1,.006,0.0,-.0315*
20,1,.006,0.0,-.0315,-.001736,-.031348,0.0*
1,1,.006,-.001736,-.031348*
20,1,.006,-.001736,-.031348,-.00342,-.030897,0.0*
1,1,.006,-.00342,-.030897*
20,1,.006,-.00342,-.030897,-.005,-.03016,0.0*
1,1,.006,-.005,-.03016*
20,1,.006,-.005,-.03016,-.006428,-.02916,0.0*
1,1,.006,-.006428,-.02916*
20,1,.006,-.006428,-.02916,-.00766,-.027928,0.0*
1,1,.006,-.00766,-.027928*
20,1,.006,-.00766,-.027928,-.00866,-.0265,0.0*
1,1,.006,-.00866,-.0265*
20,1,.006,-.00866,-.0265,-.009397,-.02492,0.0*
1,1,.006,-.009397,-.02492*
20,1,.006,-.009397,-.02492,-.009848,-.023236,0.0*
1,1,.006,-.009848,-.023236*
20,1,.006,-.009848,-.023236,-.01,-.0215,0.0*
1,1,.006,-.01,-.0215*
1,1,.006,-.00887,-.00525*
20,1,.006,-.00887,-.00525,-.00805,-.00572,0.0*
1,1,.006,-.00805,-.00572*
20,1,.006,-.00805,-.00572,-.00735,-.00583,0.0*
1,1,.006,-.00735,-.00583*
20,1,.006,-.00735,-.00583,-.00642,-.0056,0.0*
1,1,.006,-.00642,-.0056*
20,1,.006,-.00642,-.0056,-.00572,-.00502,0.0*
1,1,.006,-.00572,-.00502*
20,1,.006,-.00572,-.00502,-.00537,-.00397,0.0*
1,1,.006,-.00537,-.00397*
20,1,.006,-.00537,-.00397,-.00537,.00117,0.0*
1,1,.006,-.00537,.00117*
1,1,.006,-.00537,.00303*
20,1,.006,-.00537,.00303,-.0056,.00315,0.0*
1,1,.006,-.0056,.00315*
20,1,.006,-.0056,.00315,-.0056,.00338,0.0*
1,1,.006,-.0056,.00338*
20,1,.006,-.0056,.00338,-.00537,.0035,0.0*
1,1,.006,-.00537,.0035*
20,1,.006,-.00537,.0035,-.00513,.00338,0.0*
1,1,.006,-.00513,.00338*
20,1,.006,-.00513,.00338,-.00513,.00315,0.0*
1,1,.006,-.00513,.00315*
20,1,.006,-.00513,.00315,-.00537,.00303,0.0*
1,1,.006,-.00537,.00303*
1,1,.006,.00211,-.0035*
20,1,.006,.00211,-.0035,.00211,.00117,0.0*
1,1,.006,.00211,.00117*
1,1,.006,.00211,.00035*
20,1,.006,.00211,.00035,.00164,.00082,0.0*
1,1,.006,.00164,.00082*
20,1,.006,.00164,.00082,.00094,.00105,0.0*
1,1,.006,.00094,.00105*
20,1,.006,.00094,.00105,.00013,.00117,0.0*
1,1,.006,.00013,.00117*
20,1,.006,.00013,.00117,-.00069,.00093,0.0*
1,1,.006,-.00069,.00093*
20,1,.006,-.00069,.00093,-.00139,.00047,0.0*
1,1,.006,-.00139,.00047*
20,1,.006,-.00139,.00047,-.00186,-.00023,0.0*
1,1,.006,-.00186,-.00023*
20,1,.006,-.00186,-.00023,-.00209,-.00117,0.0*
1,1,.006,-.00209,-.00117*
20,1,.006,-.00209,-.00117,-.00186,-.0021,0.0*
1,1,.006,-.00186,-.0021*
20,1,.006,-.00186,-.0021,-.00139,-.0028,0.0*
1,1,.006,-.00139,-.0028*
20,1,.006,-.00139,-.0028,-.00069,-.00327,0.0*
1,1,.006,-.00069,-.00327*
20,1,.006,-.00069,-.00327,.00013,-.0035,0.0*
1,1,.006,.00013,-.0035*
20,1,.006,.00013,-.0035,.00094,-.00338,0.0*
1,1,.006,.00094,-.00338*
20,1,.006,.00094,-.00338,.00164,-.00303,0.0*
1,1,.006,.00164,-.00303*
20,1,.006,.00164,-.00303,.00211,-.00257,0.0*
1,1,.006,.00211,-.00257*
1,1,.006,.00352,-.0035*
20,1,.006,.00352,-.0035,.00352,.00117,0.0*
1,1,.006,.00352,.00117*
1,1,.006,.00352,-.00012*
20,1,.006,.00352,-.00012,.00387,.00047,0.0*
1,1,.006,.00387,.00047*
20,1,.006,.00387,.00047,.00445,.00093,0.0*
1,1,.006,.00445,.00093*
20,1,.006,.00445,.00093,.00527,.00117,0.0*
1,1,.006,.00527,.00117*
20,1,.006,.00527,.00117,.00609,.00093,0.0*
1,1,.006,.00609,.00093*
20,1,.006,.00609,.00093,.00667,.00047,0.0*
1,1,.006,.00667,.00047*
20,1,.006,.00667,.00047,.00702,-.00012,0.0*
1,1,.006,.00702,-.00012*
20,1,.006,.00702,-.00012,.00702,-.0035,0.0*
1,1,.006,.00702,-.0035*
1,1,.006,.00702,-.00012*
20,1,.006,.00702,-.00012,.00737,.00047,0.0*
1,1,.006,.00737,.00047*
20,1,.006,.00737,.00047,.00795,.00093,0.0*
1,1,.006,.00795,.00093*
20,1,.006,.00795,.00093,.00877,.00117,0.0*
1,1,.006,.00877,.00117*
20,1,.006,.00877,.00117,.00959,.00093,0.0*
1,1,.006,.00959,.00093*
20,1,.006,.00959,.00093,.01017,.00047,0.0*
1,1,.006,.01017,.00047*
20,1,.006,.01017,.00047,.01052,-.00023,0.0*
1,1,.006,.01052,-.00023*
20,1,.006,.01052,-.00023,.01052,-.0035,0.0*
1,1,.006,.01052,-.0035*
%
%ADD34MACRO34*%
%AMMACRO27*
1,1,.006,-.166,-.083*
20,1,.006,-.166,-.083,-.166,.083,0.0*
1,1,.006,-.166,.083*
20,1,.006,-.166,.083,-.1992,.0498,0.0*
1,1,.006,-.1992,.0498*
1,1,.006,-.1992,-.083*
20,1,.006,-.1992,-.083,-.1328,-.083,0.0*
1,1,.006,-.1328,-.083*
1,1,.006,-.05256,-.01384*
20,1,.006,-.05256,-.01384,-.03319,.00553,0.0*
1,1,.006,-.03319,.00553*
20,1,.006,-.03319,.00553,-.01659,.0166,0.0*
1,1,.006,-.01659,.0166*
20,1,.006,-.01659,.0166,.00554,.02213,0.0*
1,1,.006,.00554,.02213*
20,1,.006,.00554,.02213,.02491,.0166,0.0*
1,1,.006,.02491,.0166*
20,1,.006,.02491,.0166,.03874,.00553,0.0*
1,1,.006,.03874,.00553*
20,1,.006,.03874,.00553,.04981,-.01107,0.0*
1,1,.006,.04981,-.01107*
20,1,.006,.04981,-.01107,.05258,-.03043,0.0*
1,1,.006,.05258,-.03043*
20,1,.006,.05258,-.03043,.04981,-.04704,0.0*
1,1,.006,.04981,-.04704*
20,1,.006,.04981,-.04704,.03874,-.06364,0.0*
1,1,.006,.03874,-.06364*
20,1,.006,.03874,-.06364,.02214,-.07747,0.0*
1,1,.006,.02214,-.07747*
20,1,.006,.02214,-.07747,.00278,-.083,0.0*
1,1,.006,.00278,-.083*
20,1,.006,.00278,-.083,-.01936,-.07747,0.0*
1,1,.006,-.01936,-.07747*
20,1,.006,-.01936,-.07747,-.03872,-.06087,0.0*
1,1,.006,-.03872,-.06087*
20,1,.006,-.03872,-.06087,-.04979,-.03597,0.0*
1,1,.006,-.04979,-.03597*
20,1,.006,-.04979,-.03597,-.05256,-.0083,0.0*
1,1,.006,-.05256,-.0083*
20,1,.006,-.05256,-.0083,-.04703,.02766,0.0*
1,1,.006,-.04703,.02766*
20,1,.006,-.04703,.02766,-.03872,.04704,0.0*
1,1,.006,-.03872,.04704*
20,1,.006,-.03872,.04704,-.02489,.0664,0.0*
1,1,.006,-.02489,.0664*
20,1,.006,-.02489,.0664,-.00552,.08023,0.0*
1,1,.006,-.00552,.08023*
20,1,.006,-.00552,.08023,.01384,.083,0.0*
1,1,.006,.01384,.083*
20,1,.006,.01384,.083,.03321,.07747,0.0*
1,1,.006,.03321,.07747*
20,1,.006,.03321,.07747,.04705,.06363,0.0*
1,1,.006,.04705,.06363*
1,1,.006,.11345,-.01384*
20,1,.006,.11345,-.01384,.13282,.00553,0.0*
1,1,.006,.13282,.00553*
20,1,.006,.13282,.00553,.14942,.0166,0.0*
1,1,.006,.14942,.0166*
20,1,.006,.14942,.0166,.17155,.02213,0.0*
1,1,.006,.17155,.02213*
20,1,.006,.17155,.02213,.19092,.0166,0.0*
1,1,.006,.19092,.0166*
20,1,.006,.19092,.0166,.20475,.00553,0.0*
1,1,.006,.20475,.00553*
20,1,.006,.20475,.00553,.21582,-.01107,0.0*
1,1,.006,.21582,-.01107*
20,1,.006,.21582,-.01107,.21859,-.03043,0.0*
1,1,.006,.21859,-.03043*
20,1,.006,.21859,-.03043,.21582,-.04704,0.0*
1,1,.006,.21582,-.04704*
20,1,.006,.21582,-.04704,.20475,-.06364,0.0*
1,1,.006,.20475,-.06364*
20,1,.006,.20475,-.06364,.18815,-.07747,0.0*
1,1,.006,.18815,-.07747*
20,1,.006,.18815,-.07747,.16879,-.083,0.0*
1,1,.006,.16879,-.083*
20,1,.006,.16879,-.083,.14665,-.07747,0.0*
1,1,.006,.14665,-.07747*
20,1,.006,.14665,-.07747,.12729,-.06087,0.0*
1,1,.006,.12729,-.06087*
20,1,.006,.12729,-.06087,.11622,-.03597,0.0*
1,1,.006,.11622,-.03597*
20,1,.006,.11622,-.03597,.11345,-.0083,0.0*
1,1,.006,.11345,-.0083*
20,1,.006,.11345,-.0083,.11898,.02766,0.0*
1,1,.006,.11898,.02766*
20,1,.006,.11898,.02766,.12729,.04704,0.0*
1,1,.006,.12729,.04704*
20,1,.006,.12729,.04704,.14112,.0664,0.0*
1,1,.006,.14112,.0664*
20,1,.006,.14112,.0664,.16049,.08023,0.0*
1,1,.006,.16049,.08023*
20,1,.006,.16049,.08023,.17985,.083,0.0*
1,1,.006,.17985,.083*
20,1,.006,.17985,.083,.19922,.07747,0.0*
1,1,.006,.19922,.07747*
20,1,.006,.19922,.07747,.21306,.06363,0.0*
1,1,.006,.21306,.06363*
%
%ADD27MACRO27*%
%AMMACRO20*
1,1,.006,.035,0.0*
20,1,.006,.035,0.0,.034468,-.006078,0.0*
1,1,.006,.034468,-.006078*
20,1,.006,.034468,-.006078,.032889,-.011971,0.0*
1,1,.006,.032889,-.011971*
20,1,.006,.032889,-.011971,.030311,-.0175,0.0*
1,1,.006,.030311,-.0175*
20,1,.006,.030311,-.0175,.026812,-.022498,0.0*
1,1,.006,.026812,-.022498*
20,1,.006,.026812,-.022498,.022498,-.026812,0.0*
1,1,.006,.022498,-.026812*
20,1,.006,.022498,-.026812,.0175,-.030311,0.0*
1,1,.006,.0175,-.030311*
20,1,.006,.0175,-.030311,.011971,-.032889,0.0*
1,1,.006,.011971,-.032889*
20,1,.006,.011971,-.032889,.006078,-.034468,0.0*
1,1,.006,.006078,-.034468*
20,1,.006,.006078,-.034468,0.0,-.035,0.0*
1,1,.006,0.0,-.035*
20,1,.006,0.0,-.035,-.006078,-.034468,0.0*
1,1,.006,-.006078,-.034468*
20,1,.006,-.006078,-.034468,-.011971,-.032889,0.0*
1,1,.006,-.011971,-.032889*
20,1,.006,-.011971,-.032889,-.0175,-.030311,0.0*
1,1,.006,-.0175,-.030311*
20,1,.006,-.0175,-.030311,-.022498,-.026812,0.0*
1,1,.006,-.022498,-.026812*
20,1,.006,-.022498,-.026812,-.026812,-.022498,0.0*
1,1,.006,-.026812,-.022498*
20,1,.006,-.026812,-.022498,-.030311,-.0175,0.0*
1,1,.006,-.030311,-.0175*
20,1,.006,-.030311,-.0175,-.032889,-.011971,0.0*
1,1,.006,-.032889,-.011971*
20,1,.006,-.032889,-.011971,-.034468,-.006078,0.0*
1,1,.006,-.034468,-.006078*
20,1,.006,-.034468,-.006078,-.035,0.0,0.0*
1,1,.006,-.035,0.0*
20,1,.006,-.035,0.0,-.034468,.006078,0.0*
1,1,.006,-.034468,.006078*
20,1,.006,-.034468,.006078,-.032889,.011971,0.0*
1,1,.006,-.032889,.011971*
20,1,.006,-.032889,.011971,-.030311,.0175,0.0*
1,1,.006,-.030311,.0175*
20,1,.006,-.030311,.0175,-.026812,.022498,0.0*
1,1,.006,-.026812,.022498*
20,1,.006,-.026812,.022498,-.022498,.026812,0.0*
1,1,.006,-.022498,.026812*
20,1,.006,-.022498,.026812,-.0175,.030311,0.0*
1,1,.006,-.0175,.030311*
20,1,.006,-.0175,.030311,-.011971,.032889,0.0*
1,1,.006,-.011971,.032889*
20,1,.006,-.011971,.032889,-.006078,.034468,0.0*
1,1,.006,-.006078,.034468*
20,1,.006,-.006078,.034468,0.0,.035,0.0*
1,1,.006,0.0,.035*
20,1,.006,0.0,.035,.006078,.034468,0.0*
1,1,.006,.006078,.034468*
20,1,.006,.006078,.034468,.011971,.032889,0.0*
1,1,.006,.011971,.032889*
20,1,.006,.011971,.032889,.0175,.030311,0.0*
1,1,.006,.0175,.030311*
20,1,.006,.0175,.030311,.022498,.026812,0.0*
1,1,.006,.022498,.026812*
20,1,.006,.022498,.026812,.026812,.022498,0.0*
1,1,.006,.026812,.022498*
20,1,.006,.026812,.022498,.030311,.0175,0.0*
1,1,.006,.030311,.0175*
20,1,.006,.030311,.0175,.032889,.011971,0.0*
1,1,.006,.032889,.011971*
20,1,.006,.032889,.011971,.034468,.006078,0.0*
1,1,.006,.034468,.006078*
20,1,.006,.034468,.006078,.035,0.0,0.0*
1,1,.006,.035,0.0*
1,1,.006,-.01488,.01488*
20,1,.006,-.01488,.01488,-.01488,-.01487,0.0*
1,1,.006,-.01488,-.01487*
1,1,.006,-.02628,.01488*
20,1,.006,-.02628,.01488,-.00347,.01488,0.0*
1,1,.006,-.00347,.01488*
1,1,.006,.00497,-.01487*
20,1,.006,.00497,-.01487,.00497,.01488,0.0*
1,1,.006,.00497,.01488*
20,1,.006,.00497,.01488,.01687,.01488,0.0*
1,1,.006,.01687,.01488*
20,1,.006,.01687,.01488,.02084,.01339,0.0*
1,1,.006,.02084,.01339*
20,1,.006,.02084,.01339,.02381,.00992,0.0*
1,1,.006,.02381,.00992*
20,1,.006,.02381,.00992,.0248,.00596,0.0*
1,1,.006,.0248,.00596*
20,1,.006,.0248,.00596,.02381,.00199,0.0*
1,1,.006,.02381,.00199*
20,1,.006,.02381,.00199,.02133,-.00099,0.0*
1,1,.006,.02133,-.00099*
20,1,.006,.02133,-.00099,.01687,-.00247,0.0*
1,1,.006,.01687,-.00247*
20,1,.006,.01687,-.00247,.00497,-.00247,0.0*
1,1,.006,.00497,-.00247*
%
%ADD20MACRO20*%
%AMMACRO26*
1,1,.006,.067,0.0*
20,1,.006,.067,0.0,.0335,.058024,0.0*
1,1,.006,.0335,.058024*
20,1,.006,.0335,.058024,-.0335,.058024,0.0*
1,1,.006,-.0335,.058024*
20,1,.006,-.0335,.058024,-.067,0.0,0.0*
1,1,.006,-.067,0.0*
20,1,.006,-.067,0.0,-.0335,-.058024,0.0*
1,1,.006,-.0335,-.058024*
20,1,.006,-.0335,-.058024,.0335,-.058024,0.0*
1,1,.006,.0335,-.058024*
20,1,.006,.0335,-.058024,.067,0.0,0.0*
1,1,.006,.067,0.0*
1,1,.006,-.02298,-.02735*
20,1,.006,-.02298,-.02735,-.02298,.00548,0.0*
1,1,.006,-.02298,.00548*
1,1,.006,-.02298,.00055*
20,1,.006,-.02298,.00055,-.02571,.00329,0.0*
1,1,.006,-.02571,.00329*
20,1,.006,-.02571,.00329,-.029,.00493,0.0*
1,1,.006,-.029,.00493*
20,1,.006,-.029,.00493,-.03283,.00548,0.0*
1,1,.006,-.03283,.00548*
20,1,.006,-.03283,.00548,-.03611,.00493,0.0*
1,1,.006,-.03611,.00493*
20,1,.006,-.03611,.00493,-.03994,.00219,0.0*
1,1,.006,-.03994,.00219*
20,1,.006,-.03994,.00219,-.04213,-.00164,0.0*
1,1,.006,-.04213,-.00164*
20,1,.006,-.04213,-.00164,-.04267,-.00547,0.0*
1,1,.006,-.04267,-.00547*
20,1,.006,-.04267,-.00547,-.04213,-.0093,0.0*
1,1,.006,-.04213,-.0093*
20,1,.006,-.04213,-.0093,-.03994,-.01313,0.0*
1,1,.006,-.03994,-.01313*
20,1,.006,-.03994,-.01313,-.03611,-.01586,0.0*
1,1,.006,-.03611,-.01586*
20,1,.006,-.03611,-.01586,-.03283,-.01641,0.0*
1,1,.006,-.03283,-.01641*
20,1,.006,-.03283,-.01641,-.029,-.01586,0.0*
1,1,.006,-.029,-.01586*
20,1,.006,-.029,-.01586,-.02571,-.01422,0.0*
1,1,.006,-.02571,-.01422*
20,1,.006,-.02571,-.01422,-.02298,-.01149,0.0*
1,1,.006,-.02298,-.01149*
1,1,.006,-.00819,-.00164*
20,1,.006,-.00819,-.00164,.00932,-.00164,0.0*
1,1,.006,.00932,-.00164*
20,1,.006,.00932,-.00164,.00768,.00219,0.0*
1,1,.006,.00768,.00219*
20,1,.006,.00768,.00219,.00494,.00438,0.0*
1,1,.006,.00494,.00438*
20,1,.006,.00494,.00438,.00111,.00548,0.0*
1,1,.006,.00111,.00548*
20,1,.006,.00111,.00548,-.00272,.00493,0.0*
1,1,.006,-.00272,.00493*
20,1,.006,-.00272,.00493,-.006,.00329,0.0*
1,1,.006,-.006,.00329*
20,1,.006,-.006,.00329,-.00819,-.00054,0.0*
1,1,.006,-.00819,-.00054*
20,1,.006,-.00819,-.00054,-.00929,-.00383,0.0*
1,1,.006,-.00929,-.00383*
20,1,.006,-.00929,-.00383,-.00929,-.00711,0.0*
1,1,.006,-.00929,-.00711*
20,1,.006,-.00929,-.00711,-.00819,-.01039,0.0*
1,1,.006,-.00819,-.01039*
20,1,.006,-.00819,-.01039,-.00546,-.01367,0.0*
1,1,.006,-.00546,-.01367*
20,1,.006,-.00546,-.01367,-.00217,-.01586,0.0*
1,1,.006,-.00217,-.01586*
20,1,.006,-.00217,-.01586,.00166,-.01641,0.0*
1,1,.006,.00166,-.01641*
20,1,.006,.00166,-.01641,.00549,-.01532,0.0*
1,1,.006,.00549,-.01532*
20,1,.006,.00549,-.01532,.00932,-.01203,0.0*
1,1,.006,.00932,-.01203*
1,1,.006,.02519,-.01641*
20,1,.006,.02519,-.01641,.02519,.00548,0.0*
1,1,.006,.02519,.00548*
1,1,.006,.02519,.0011*
20,1,.006,.02519,.0011,.02793,.00329,0.0*
1,1,.006,.02793,.00329*
20,1,.006,.02793,.00329,.03067,.00493,0.0*
1,1,.006,.03067,.00493*
20,1,.006,.03067,.00493,.0345,.00548,0.0*
1,1,.006,.0345,.00548*
20,1,.006,.0345,.00548,.03723,.00493,0.0*
1,1,.006,.03723,.00493*
20,1,.006,.03723,.00493,.04052,.00329,0.0*
1,1,.006,.04052,.00329*
%
%ADD26MACRO26*%
%AMMACRO10*
1,1,.006,.035,0.0*
20,1,.006,.035,0.0,.034468,-.006078,0.0*
1,1,.006,.034468,-.006078*
20,1,.006,.034468,-.006078,.032889,-.011971,0.0*
1,1,.006,.032889,-.011971*
20,1,.006,.032889,-.011971,.030311,-.0175,0.0*
1,1,.006,.030311,-.0175*
20,1,.006,.030311,-.0175,.026812,-.022498,0.0*
1,1,.006,.026812,-.022498*
20,1,.006,.026812,-.022498,.022498,-.026812,0.0*
1,1,.006,.022498,-.026812*
20,1,.006,.022498,-.026812,.0175,-.030311,0.0*
1,1,.006,.0175,-.030311*
20,1,.006,.0175,-.030311,.011971,-.032889,0.0*
1,1,.006,.011971,-.032889*
20,1,.006,.011971,-.032889,.006078,-.034468,0.0*
1,1,.006,.006078,-.034468*
20,1,.006,.006078,-.034468,0.0,-.035,0.0*
1,1,.006,0.0,-.035*
20,1,.006,0.0,-.035,-.006078,-.034468,0.0*
1,1,.006,-.006078,-.034468*
20,1,.006,-.006078,-.034468,-.011971,-.032889,0.0*
1,1,.006,-.011971,-.032889*
20,1,.006,-.011971,-.032889,-.0175,-.030311,0.0*
1,1,.006,-.0175,-.030311*
20,1,.006,-.0175,-.030311,-.022498,-.026812,0.0*
1,1,.006,-.022498,-.026812*
20,1,.006,-.022498,-.026812,-.026812,-.022498,0.0*
1,1,.006,-.026812,-.022498*
20,1,.006,-.026812,-.022498,-.030311,-.0175,0.0*
1,1,.006,-.030311,-.0175*
20,1,.006,-.030311,-.0175,-.032889,-.011971,0.0*
1,1,.006,-.032889,-.011971*
20,1,.006,-.032889,-.011971,-.034468,-.006078,0.0*
1,1,.006,-.034468,-.006078*
20,1,.006,-.034468,-.006078,-.035,0.0,0.0*
1,1,.006,-.035,0.0*
20,1,.006,-.035,0.0,-.034468,.006078,0.0*
1,1,.006,-.034468,.006078*
20,1,.006,-.034468,.006078,-.032889,.011971,0.0*
1,1,.006,-.032889,.011971*
20,1,.006,-.032889,.011971,-.030311,.0175,0.0*
1,1,.006,-.030311,.0175*
20,1,.006,-.030311,.0175,-.026812,.022498,0.0*
1,1,.006,-.026812,.022498*
20,1,.006,-.026812,.022498,-.022498,.026812,0.0*
1,1,.006,-.022498,.026812*
20,1,.006,-.022498,.026812,-.0175,.030311,0.0*
1,1,.006,-.0175,.030311*
20,1,.006,-.0175,.030311,-.011971,.032889,0.0*
1,1,.006,-.011971,.032889*
20,1,.006,-.011971,.032889,-.006078,.034468,0.0*
1,1,.006,-.006078,.034468*
20,1,.006,-.006078,.034468,0.0,.035,0.0*
1,1,.006,0.0,.035*
20,1,.006,0.0,.035,.006078,.034468,0.0*
1,1,.006,.006078,.034468*
20,1,.006,.006078,.034468,.011971,.032889,0.0*
1,1,.006,.011971,.032889*
20,1,.006,.011971,.032889,.0175,.030311,0.0*
1,1,.006,.0175,.030311*
20,1,.006,.0175,.030311,.022498,.026812,0.0*
1,1,.006,.022498,.026812*
20,1,.006,.022498,.026812,.026812,.022498,0.0*
1,1,.006,.026812,.022498*
20,1,.006,.026812,.022498,.030311,.0175,0.0*
1,1,.006,.030311,.0175*
20,1,.006,.030311,.0175,.032889,.011971,0.0*
1,1,.006,.032889,.011971*
20,1,.006,.032889,.011971,.034468,.006078,0.0*
1,1,.006,.034468,.006078*
20,1,.006,.034468,.006078,.035,0.0,0.0*
1,1,.006,.035,0.0*
1,1,.006,-.0295,.01041*
20,1,.006,-.0295,.01041,-.02082,-.01041,0.0*
1,1,.006,-.02082,-.01041*
20,1,.006,-.02082,-.01041,-.01214,.01041,0.0*
1,1,.006,-.01214,.01041*
1,1,.006,.00001,-.01041*
20,1,.006,.00001,-.01041,.00001,.01041,0.0*
1,1,.006,.00001,.01041*
20,1,.006,.00001,.01041,-.00415,.00625,0.0*
1,1,.006,-.00415,.00625*
1,1,.006,-.00415,-.01041*
20,1,.006,-.00415,-.01041,.00417,-.01041,0.0*
1,1,.006,.00417,-.01041*
1,1,.006,.02084,.01041*
20,1,.006,.02084,.01041,.01806,.00972,0.0*
1,1,.006,.01806,.00972*
20,1,.006,.01806,.00972,.01598,.00798,0.0*
1,1,.006,.01598,.00798*
20,1,.006,.01598,.00798,.01459,.0059,0.0*
1,1,.006,.01459,.0059*
20,1,.006,.01459,.0059,.01355,.00312,0.0*
1,1,.006,.01355,.00312*
20,1,.006,.01355,.00312,.01321,0.0,0.0*
1,1,.006,.01321,0.0*
20,1,.006,.01321,0.0,.01355,-.00312,0.0*
1,1,.006,.01355,-.00312*
20,1,.006,.01355,-.00312,.01459,-.0059,0.0*
1,1,.006,.01459,-.0059*
20,1,.006,.01459,-.0059,.01598,-.00798,0.0*
1,1,.006,.01598,-.00798*
20,1,.006,.01598,-.00798,.01806,-.00972,0.0*
1,1,.006,.01806,-.00972*
20,1,.006,.01806,-.00972,.02084,-.01041,0.0*
1,1,.006,.02084,-.01041*
20,1,.006,.02084,-.01041,.02362,-.00972,0.0*
1,1,.006,.02362,-.00972*
20,1,.006,.02362,-.00972,.0257,-.00798,0.0*
1,1,.006,.0257,-.00798*
20,1,.006,.0257,-.00798,.02709,-.0059,0.0*
1,1,.006,.02709,-.0059*
20,1,.006,.02709,-.0059,.02813,-.00312,0.0*
1,1,.006,.02813,-.00312*
20,1,.006,.02813,-.00312,.02847,0.0,0.0*
1,1,.006,.02847,0.0*
20,1,.006,.02847,0.0,.02813,.00312,0.0*
1,1,.006,.02813,.00312*
20,1,.006,.02813,.00312,.02709,.0059,0.0*
1,1,.006,.02709,.0059*
20,1,.006,.02709,.0059,.0257,.00798,0.0*
1,1,.006,.0257,.00798*
20,1,.006,.0257,.00798,.02362,.00972,0.0*
1,1,.006,.02362,.00972*
20,1,.006,.02362,.00972,.02084,.01041,0.0*
1,1,.006,.02084,.01041*
%
%ADD10MACRO10*%
%ADD12C,.125*%
%AMMACRO19*
1,1,.006,.035,0.0*
20,1,.006,.035,0.0,.034468,-.006078,0.0*
1,1,.006,.034468,-.006078*
20,1,.006,.034468,-.006078,.032889,-.011971,0.0*
1,1,.006,.032889,-.011971*
20,1,.006,.032889,-.011971,.030311,-.0175,0.0*
1,1,.006,.030311,-.0175*
20,1,.006,.030311,-.0175,.026812,-.022498,0.0*
1,1,.006,.026812,-.022498*
20,1,.006,.026812,-.022498,.022498,-.026812,0.0*
1,1,.006,.022498,-.026812*
20,1,.006,.022498,-.026812,.0175,-.030311,0.0*
1,1,.006,.0175,-.030311*
20,1,.006,.0175,-.030311,.011971,-.032889,0.0*
1,1,.006,.011971,-.032889*
20,1,.006,.011971,-.032889,.006078,-.034468,0.0*
1,1,.006,.006078,-.034468*
20,1,.006,.006078,-.034468,0.0,-.035,0.0*
1,1,.006,0.0,-.035*
20,1,.006,0.0,-.035,-.006078,-.034468,0.0*
1,1,.006,-.006078,-.034468*
20,1,.006,-.006078,-.034468,-.011971,-.032889,0.0*
1,1,.006,-.011971,-.032889*
20,1,.006,-.011971,-.032889,-.0175,-.030311,0.0*
1,1,.006,-.0175,-.030311*
20,1,.006,-.0175,-.030311,-.022498,-.026812,0.0*
1,1,.006,-.022498,-.026812*
20,1,.006,-.022498,-.026812,-.026812,-.022498,0.0*
1,1,.006,-.026812,-.022498*
20,1,.006,-.026812,-.022498,-.030311,-.0175,0.0*
1,1,.006,-.030311,-.0175*
20,1,.006,-.030311,-.0175,-.032889,-.011971,0.0*
1,1,.006,-.032889,-.011971*
20,1,.006,-.032889,-.011971,-.034468,-.006078,0.0*
1,1,.006,-.034468,-.006078*
20,1,.006,-.034468,-.006078,-.035,0.0,0.0*
1,1,.006,-.035,0.0*
20,1,.006,-.035,0.0,-.034468,.006078,0.0*
1,1,.006,-.034468,.006078*
20,1,.006,-.034468,.006078,-.032889,.011971,0.0*
1,1,.006,-.032889,.011971*
20,1,.006,-.032889,.011971,-.030311,.0175,0.0*
1,1,.006,-.030311,.0175*
20,1,.006,-.030311,.0175,-.026812,.022498,0.0*
1,1,.006,-.026812,.022498*
20,1,.006,-.026812,.022498,-.022498,.026812,0.0*
1,1,.006,-.022498,.026812*
20,1,.006,-.022498,.026812,-.0175,.030311,0.0*
1,1,.006,-.0175,.030311*
20,1,.006,-.0175,.030311,-.011971,.032889,0.0*
1,1,.006,-.011971,.032889*
20,1,.006,-.011971,.032889,-.006078,.034468,0.0*
1,1,.006,-.006078,.034468*
20,1,.006,-.006078,.034468,0.0,.035,0.0*
1,1,.006,0.0,.035*
20,1,.006,0.0,.035,.006078,.034468,0.0*
1,1,.006,.006078,.034468*
20,1,.006,.006078,.034468,.011971,.032889,0.0*
1,1,.006,.011971,.032889*
20,1,.006,.011971,.032889,.0175,.030311,0.0*
1,1,.006,.0175,.030311*
20,1,.006,.0175,.030311,.022498,.026812,0.0*
1,1,.006,.022498,.026812*
20,1,.006,.022498,.026812,.026812,.022498,0.0*
1,1,.006,.026812,.022498*
20,1,.006,.026812,.022498,.030311,.0175,0.0*
1,1,.006,.030311,.0175*
20,1,.006,.030311,.0175,.032889,.011971,0.0*
1,1,.006,.032889,.011971*
20,1,.006,.032889,.011971,.034468,.006078,0.0*
1,1,.006,.034468,.006078*
20,1,.006,.034468,.006078,.035,0.0,0.0*
1,1,.006,.035,0.0*
1,1,.006,-.0295,.01041*
20,1,.006,-.0295,.01041,-.02082,-.01041,0.0*
1,1,.006,-.02082,-.01041*
20,1,.006,-.02082,-.01041,-.01214,.01041,0.0*
1,1,.006,-.01214,.01041*
1,1,.006,.00001,.01041*
20,1,.006,.00001,.01041,-.00277,.00972,0.0*
1,1,.006,-.00277,.00972*
20,1,.006,-.00277,.00972,-.00485,.00798,0.0*
1,1,.006,-.00485,.00798*
20,1,.006,-.00485,.00798,-.00624,.0059,0.0*
1,1,.006,-.00624,.0059*
20,1,.006,-.00624,.0059,-.00728,.00312,0.0*
1,1,.006,-.00728,.00312*
20,1,.006,-.00728,.00312,-.00762,0.0,0.0*
1,1,.006,-.00762,0.0*
20,1,.006,-.00762,0.0,-.00728,-.00312,0.0*
1,1,.006,-.00728,-.00312*
20,1,.006,-.00728,-.00312,-.00624,-.0059,0.0*
1,1,.006,-.00624,-.0059*
20,1,.006,-.00624,-.0059,-.00485,-.00798,0.0*
1,1,.006,-.00485,-.00798*
20,1,.006,-.00485,-.00798,-.00277,-.00972,0.0*
1,1,.006,-.00277,-.00972*
20,1,.006,-.00277,-.00972,.00001,-.01041,0.0*
1,1,.006,.00001,-.01041*
20,1,.006,.00001,-.01041,.00279,-.00972,0.0*
1,1,.006,.00279,-.00972*
20,1,.006,.00279,-.00972,.00487,-.00798,0.0*
1,1,.006,.00487,-.00798*
20,1,.006,.00487,-.00798,.00626,-.0059,0.0*
1,1,.006,.00626,-.0059*
20,1,.006,.00626,-.0059,.0073,-.00312,0.0*
1,1,.006,.0073,-.00312*
20,1,.006,.0073,-.00312,.00764,0.0,0.0*
1,1,.006,.00764,0.0*
20,1,.006,.00764,0.0,.0073,.00312,0.0*
1,1,.006,.0073,.00312*
20,1,.006,.0073,.00312,.00626,.0059,0.0*
1,1,.006,.00626,.0059*
20,1,.006,.00626,.0059,.00487,.00798,0.0*
1,1,.006,.00487,.00798*
20,1,.006,.00487,.00798,.00279,.00972,0.0*
1,1,.006,.00279,.00972*
20,1,.006,.00279,.00972,.00001,.01041,0.0*
1,1,.006,.00001,.01041*
1,1,.006,.02084,-.01041*
20,1,.006,.02084,-.01041,.02327,-.01006,0.0*
1,1,.006,.02327,-.01006*
20,1,.006,.02327,-.01006,.02604,-.00902,0.0*
1,1,.006,.02604,-.00902*
20,1,.006,.02604,-.00902,.02778,-.00729,0.0*
1,1,.006,.02778,-.00729*
20,1,.006,.02778,-.00729,.02847,-.00486,0.0*
1,1,.006,.02847,-.00486*
20,1,.006,.02847,-.00486,.02778,-.00243,0.0*
1,1,.006,.02778,-.00243*
20,1,.006,.02778,-.00243,.0257,-.00035,0.0*
1,1,.006,.0257,-.00035*
20,1,.006,.0257,-.00035,.02257,.00069,0.0*
1,1,.006,.02257,.00069*
20,1,.006,.02257,.00069,.01911,.00069,0.0*
1,1,.006,.01911,.00069*
20,1,.006,.01911,.00069,.01702,.00139,0.0*
1,1,.006,.01702,.00139*
20,1,.006,.01702,.00139,.01529,.00312,0.0*
1,1,.006,.01529,.00312*
20,1,.006,.01529,.00312,.01459,.00555,0.0*
1,1,.006,.01459,.00555*
20,1,.006,.01459,.00555,.01564,.00798,0.0*
1,1,.006,.01564,.00798*
20,1,.006,.01564,.00798,.01806,.00972,0.0*
1,1,.006,.01806,.00972*
20,1,.006,.01806,.00972,.02084,.01041,0.0*
1,1,.006,.02084,.01041*
20,1,.006,.02084,.01041,.02362,.00972,0.0*
1,1,.006,.02362,.00972*
20,1,.006,.02362,.00972,.02604,.00798,0.0*
1,1,.006,.02604,.00798*
20,1,.006,.02604,.00798,.02709,.00555,0.0*
1,1,.006,.02709,.00555*
20,1,.006,.02709,.00555,.02639,.00312,0.0*
1,1,.006,.02639,.00312*
20,1,.006,.02639,.00312,.02466,.00139,0.0*
1,1,.006,.02466,.00139*
20,1,.006,.02466,.00139,.02257,.00069,0.0*
1,1,.006,.02257,.00069*
20,1,.006,.02257,.00069,.01911,.00069,0.0*
1,1,.006,.01911,.00069*
20,1,.006,.01911,.00069,.01598,-.00035,0.0*
1,1,.006,.01598,-.00035*
20,1,.006,.01598,-.00035,.0139,-.00243,0.0*
1,1,.006,.0139,-.00243*
20,1,.006,.0139,-.00243,.01321,-.00486,0.0*
1,1,.006,.01321,-.00486*
20,1,.006,.01321,-.00486,.0139,-.00729,0.0*
1,1,.006,.0139,-.00729*
20,1,.006,.0139,-.00729,.01564,-.00902,0.0*
1,1,.006,.01564,-.00902*
20,1,.006,.01564,-.00902,.01841,-.01006,0.0*
1,1,.006,.01841,-.01006*
20,1,.006,.01841,-.01006,.02084,-.01041,0.0*
1,1,.006,.02084,-.01041*
%
%ADD19MACRO19*%
%AMMACRO35*
1,1,.006,.061,0.0*
20,1,.006,.061,0.0,.0305,.052828,0.0*
1,1,.006,.0305,.052828*
20,1,.006,.0305,.052828,-.0305,.052828,0.0*
1,1,.006,-.0305,.052828*
20,1,.006,-.0305,.052828,-.061,0.0,0.0*
1,1,.006,-.061,0.0*
20,1,.006,-.061,0.0,-.0305,-.052828,0.0*
1,1,.006,-.0305,-.052828*
20,1,.006,-.0305,-.052828,.0305,-.052828,0.0*
1,1,.006,.0305,-.052828*
20,1,.006,.0305,-.052828,.061,0.0,0.0*
1,1,.006,.061,0.0*
1,1,.006,-.02092,-.0249*
20,1,.006,-.02092,-.0249,-.02092,.00499,0.0*
1,1,.006,-.02092,.00499*
1,1,.006,-.02092,.0005*
20,1,.006,-.02092,.0005,-.02341,.00299,0.0*
1,1,.006,-.02341,.00299*
20,1,.006,-.02341,.00299,-.0264,.00449,0.0*
1,1,.006,-.0264,.00449*
20,1,.006,-.0264,.00449,-.02989,.00499,0.0*
1,1,.006,-.02989,.00499*
20,1,.006,-.02989,.00499,-.03287,.00449,0.0*
1,1,.006,-.03287,.00449*
20,1,.006,-.03287,.00449,-.03636,.002,0.0*
1,1,.006,-.03636,.002*
20,1,.006,-.03636,.002,-.03835,-.00149,0.0*
1,1,.006,-.03835,-.00149*
20,1,.006,-.03835,-.00149,-.03885,-.00498,0.0*
1,1,.006,-.03885,-.00498*
20,1,.006,-.03885,-.00498,-.03835,-.00846,0.0*
1,1,.006,-.03835,-.00846*
20,1,.006,-.03835,-.00846,-.03636,-.01195,0.0*
1,1,.006,-.03636,-.01195*
20,1,.006,-.03636,-.01195,-.03287,-.01444,0.0*
1,1,.006,-.03287,-.01444*
20,1,.006,-.03287,-.01444,-.02989,-.01494,0.0*
1,1,.006,-.02989,-.01494*
20,1,.006,-.02989,-.01494,-.0264,-.01444,0.0*
1,1,.006,-.0264,-.01444*
20,1,.006,-.0264,-.01444,-.02341,-.01295,0.0*
1,1,.006,-.02341,-.01295*
20,1,.006,-.02341,-.01295,-.02092,-.01046,0.0*
1,1,.006,-.02092,-.01046*
1,1,.006,-.01244,.00499*
20,1,.006,-.01244,.00499,-.00646,-.01494,0.0*
1,1,.006,-.00646,-.01494*
20,1,.006,-.00646,-.01494,.00001,.00499,0.0*
1,1,.006,.00001,.00499*
20,1,.006,.00001,.00499,.00649,-.01494,0.0*
1,1,.006,.00649,-.01494*
20,1,.006,.00649,-.01494,.01247,.00499,0.0*
1,1,.006,.01247,.00499*
1,1,.006,.01746,.00499*
20,1,.006,.01746,.00499,.02344,-.01494,0.0*
1,1,.006,.02344,-.01494*
20,1,.006,.02344,-.01494,.02991,.00499,0.0*
1,1,.006,.02991,.00499*
20,1,.006,.02991,.00499,.03639,-.01494,0.0*
1,1,.006,.03639,-.01494*
20,1,.006,.03639,-.01494,.04237,.00499,0.0*
1,1,.006,.04237,.00499*
%
%ADD35MACRO35*%
%AMMACRO25*
1,1,.006,0.0,.035*
20,1,.006,0.0,.035,.030311,-.0175,0.0*
1,1,.006,.030311,-.0175*
20,1,.006,.030311,-.0175,-.030311,-.0175,0.0*
1,1,.006,-.030311,-.0175*
20,1,.006,-.030311,-.0175,0.0,.035,0.0*
1,1,.006,0.0,.035*
1,1,.006,-.01433,-.00918*
20,1,.006,-.01433,-.00918,-.01433,.00184,0.0*
1,1,.006,-.01433,.00184*
1,1,.006,-.01433,.00018*
20,1,.006,-.01433,.00018,-.01341,.0011,0.0*
1,1,.006,-.01341,.0011*
20,1,.006,-.01341,.0011,-.01249,.00165,0.0*
1,1,.006,-.01249,.00165*
20,1,.006,-.01249,.00165,-.01102,.00184,0.0*
1,1,.006,-.01102,.00184*
20,1,.006,-.01102,.00184,-.00973,.00165,0.0*
1,1,.006,-.00973,.00165*
20,1,.006,-.00973,.00165,-.00845,.00073,0.0*
1,1,.006,-.00845,.00073*
20,1,.006,-.00845,.00073,-.0079,-.00055,0.0*
1,1,.006,-.0079,-.00055*
20,1,.006,-.0079,-.00055,-.00771,-.00184,0.0*
1,1,.006,-.00771,-.00184*
20,1,.006,-.00771,-.00184,-.0079,-.00312,0.0*
1,1,.006,-.0079,-.00312*
20,1,.006,-.0079,-.00312,-.00845,-.00441,0.0*
1,1,.006,-.00845,-.00441*
20,1,.006,-.00845,-.00441,-.00955,-.00514,0.0*
1,1,.006,-.00955,-.00514*
20,1,.006,-.00955,-.00514,-.01102,-.00551,0.0*
1,1,.006,-.01102,-.00551*
20,1,.006,-.01102,-.00551,-.01231,-.00533,0.0*
1,1,.006,-.01231,-.00533*
20,1,.006,-.01231,-.00533,-.01359,-.00478,0.0*
1,1,.006,-.01359,-.00478*
20,1,.006,-.01359,-.00478,-.01433,-.00404,0.0*
1,1,.006,-.01433,-.00404*
1,1,.006,-.00256,-.00551*
20,1,.006,-.00256,-.00551,-.00256,.00184,0.0*
1,1,.006,-.00256,.00184*
1,1,.006,-.00256,.00037*
20,1,.006,-.00256,.00037,-.00164,.0011,0.0*
1,1,.006,-.00164,.0011*
20,1,.006,-.00164,.0011,-.00072,.00165,0.0*
1,1,.006,-.00072,.00165*
20,1,.006,-.00072,.00165,.00056,.00184,0.0*
1,1,.006,.00056,.00184*
20,1,.006,.00056,.00184,.00148,.00165,0.0*
1,1,.006,.00148,.00165*
20,1,.006,.00148,.00165,.00258,.0011,0.0*
1,1,.006,.00258,.0011*
1,1,.006,.01435,-.00918*
20,1,.006,.01435,-.00918,.01435,.00184,0.0*
1,1,.006,.01435,.00184*
1,1,.006,.01435,.00018*
20,1,.006,.01435,.00018,.01343,.0011,0.0*
1,1,.006,.01343,.0011*
20,1,.006,.01343,.0011,.01233,.00165,0.0*
1,1,.006,.01233,.00165*
20,1,.006,.01233,.00165,.01104,.00184,0.0*
1,1,.006,.01104,.00184*
20,1,.006,.01104,.00184,.00994,.00165,0.0*
1,1,.006,.00994,.00165*
20,1,.006,.00994,.00165,.00865,.00073,0.0*
1,1,.006,.00865,.00073*
20,1,.006,.00865,.00073,.00792,-.00055,0.0*
1,1,.006,.00792,-.00055*
20,1,.006,.00792,-.00055,.00773,-.00184,0.0*
1,1,.006,.00773,-.00184*
20,1,.006,.00773,-.00184,.00792,-.00312,0.0*
1,1,.006,.00792,-.00312*
20,1,.006,.00792,-.00312,.00865,-.00441,0.0*
1,1,.006,.00865,-.00441*
20,1,.006,.00865,-.00441,.00994,-.00533,0.0*
1,1,.006,.00994,-.00533*
20,1,.006,.00994,-.00533,.01104,-.00551,0.0*
1,1,.006,.01104,-.00551*
20,1,.006,.01104,-.00551,.01233,-.00533,0.0*
1,1,.006,.01233,-.00533*
20,1,.006,.01233,-.00533,.01343,-.00478,0.0*
1,1,.006,.01343,-.00478*
20,1,.006,.01343,-.00478,.01435,-.00386,0.0*
1,1,.006,.01435,-.00386*
%
%ADD25MACRO25*%
%AMMACRO18*
1,1,.006,0.0,.035*
20,1,.006,0.0,.035,.030311,-.0175,0.0*
1,1,.006,.030311,-.0175*
20,1,.006,.030311,-.0175,-.030311,-.0175,0.0*
1,1,.006,-.030311,-.0175*
20,1,.006,-.030311,-.0175,0.0,.035,0.0*
1,1,.006,0.0,.035*
1,1,.006,-.01433,-.00918*
20,1,.006,-.01433,-.00918,-.01433,.00184,0.0*
1,1,.006,-.01433,.00184*
1,1,.006,-.01433,.00018*
20,1,.006,-.01433,.00018,-.01341,.0011,0.0*
1,1,.006,-.01341,.0011*
20,1,.006,-.01341,.0011,-.01249,.00165,0.0*
1,1,.006,-.01249,.00165*
20,1,.006,-.01249,.00165,-.01102,.00184,0.0*
1,1,.006,-.01102,.00184*
20,1,.006,-.01102,.00184,-.00973,.00165,0.0*
1,1,.006,-.00973,.00165*
20,1,.006,-.00973,.00165,-.00845,.00073,0.0*
1,1,.006,-.00845,.00073*
20,1,.006,-.00845,.00073,-.0079,-.00055,0.0*
1,1,.006,-.0079,-.00055*
20,1,.006,-.0079,-.00055,-.00771,-.00184,0.0*
1,1,.006,-.00771,-.00184*
20,1,.006,-.00771,-.00184,-.0079,-.00312,0.0*
1,1,.006,-.0079,-.00312*
20,1,.006,-.0079,-.00312,-.00845,-.00441,0.0*
1,1,.006,-.00845,-.00441*
20,1,.006,-.00845,-.00441,-.00955,-.00514,0.0*
1,1,.006,-.00955,-.00514*
20,1,.006,-.00955,-.00514,-.01102,-.00551,0.0*
1,1,.006,-.01102,-.00551*
20,1,.006,-.01102,-.00551,-.01231,-.00533,0.0*
1,1,.006,-.01231,-.00533*
20,1,.006,-.01231,-.00533,-.01359,-.00478,0.0*
1,1,.006,-.01359,-.00478*
20,1,.006,-.01359,-.00478,-.01433,-.00404,0.0*
1,1,.006,-.01433,-.00404*
1,1,.006,-.00256,-.00551*
20,1,.006,-.00256,-.00551,-.00256,.00184,0.0*
1,1,.006,-.00256,.00184*
1,1,.006,-.00256,.00037*
20,1,.006,-.00256,.00037,-.00164,.0011,0.0*
1,1,.006,-.00164,.0011*
20,1,.006,-.00164,.0011,-.00072,.00165,0.0*
1,1,.006,-.00072,.00165*
20,1,.006,-.00072,.00165,.00056,.00184,0.0*
1,1,.006,.00056,.00184*
20,1,.006,.00056,.00184,.00148,.00165,0.0*
1,1,.006,.00148,.00165*
20,1,.006,.00148,.00165,.00258,.0011,0.0*
1,1,.006,.00258,.0011*
1,1,.006,.00847,-.00551*
20,1,.006,.00847,-.00551,.00847,.00184,0.0*
1,1,.006,.00847,.00184*
1,1,.006,.00847,.00037*
20,1,.006,.00847,.00037,.00939,.0011,0.0*
1,1,.006,.00939,.0011*
20,1,.006,.00939,.0011,.01031,.00165,0.0*
1,1,.006,.01031,.00165*
20,1,.006,.01031,.00165,.01159,.00184,0.0*
1,1,.006,.01159,.00184*
20,1,.006,.01159,.00184,.01251,.00165,0.0*
1,1,.006,.01251,.00165*
20,1,.006,.01251,.00165,.01361,.0011,0.0*
1,1,.006,.01361,.0011*
%
%ADD18MACRO18*%
%AMMACRO14*
1,1,.006,.0625,0.0*
20,1,.006,.0625,0.0,.03125,.054127,0.0*
1,1,.006,.03125,.054127*
20,1,.006,.03125,.054127,-.03125,.054127,0.0*
1,1,.006,-.03125,.054127*
20,1,.006,-.03125,.054127,-.0625,0.0,0.0*
1,1,.006,-.0625,0.0*
20,1,.006,-.0625,0.0,-.03125,-.054127,0.0*
1,1,.006,-.03125,-.054127*
20,1,.006,-.03125,-.054127,.03125,-.054127,0.0*
1,1,.006,.03125,-.054127*
20,1,.006,.03125,-.054127,.0625,0.0,0.0*
1,1,.006,.0625,0.0*
1,1,.006,-.02143,-.02552*
20,1,.006,-.02143,-.02552,-.02143,.0051,0.0*
1,1,.006,-.02143,.0051*
1,1,.006,-.02143,.00051*
20,1,.006,-.02143,.00051,-.02399,.00306,0.0*
1,1,.006,-.02399,.00306*
20,1,.006,-.02399,.00306,-.02705,.00459,0.0*
1,1,.006,-.02705,.00459*
20,1,.006,-.02705,.00459,-.03062,.0051,0.0*
1,1,.006,-.03062,.0051*
20,1,.006,-.03062,.0051,-.03368,.00459,0.0*
1,1,.006,-.03368,.00459*
20,1,.006,-.03368,.00459,-.03725,.00204,0.0*
1,1,.006,-.03725,.00204*
20,1,.006,-.03725,.00204,-.0393,-.00153,0.0*
1,1,.006,-.0393,-.00153*
20,1,.006,-.0393,-.00153,-.03981,-.0051,0.0*
1,1,.006,-.03981,-.0051*
20,1,.006,-.03981,-.0051,-.0393,-.00868,0.0*
1,1,.006,-.0393,-.00868*
20,1,.006,-.0393,-.00868,-.03725,-.01225,0.0*
1,1,.006,-.03725,-.01225*
20,1,.006,-.03725,-.01225,-.03368,-.0148,0.0*
1,1,.006,-.03368,-.0148*
20,1,.006,-.03368,-.0148,-.03062,-.01531,0.0*
1,1,.006,-.03062,-.01531*
20,1,.006,-.03062,-.01531,-.02705,-.0148,0.0*
1,1,.006,-.02705,-.0148*
20,1,.006,-.02705,-.0148,-.02399,-.01327,0.0*
1,1,.006,-.02399,-.01327*
20,1,.006,-.02399,-.01327,-.02143,-.01072,0.0*
1,1,.006,-.02143,-.01072*
1,1,.006,-.01275,.0051*
20,1,.006,-.01275,.0051,-.00662,-.01531,0.0*
1,1,.006,-.00662,-.01531*
20,1,.006,-.00662,-.01531,.00001,.0051,0.0*
1,1,.006,.00001,.0051*
20,1,.006,.00001,.0051,.00664,-.01531,0.0*
1,1,.006,.00664,-.01531*
20,1,.006,.00664,-.01531,.01277,.0051,0.0*
1,1,.006,.01277,.0051*
1,1,.006,.03064,.01531*
20,1,.006,.03064,.01531,.03064,-.01531,0.0*
1,1,.006,.03064,-.01531*
1,1,.006,.0235,.0051*
20,1,.006,.0235,.0051,.03778,.0051,0.0*
1,1,.006,.03778,.0051*
%
%ADD14MACRO14*%
%AMMACRO29*
1,1,.006,0.0,.035*
20,1,.006,0.0,.035,.030311,-.0175,0.0*
1,1,.006,.030311,-.0175*
20,1,.006,.030311,-.0175,-.030311,-.0175,0.0*
1,1,.006,-.030311,-.0175*
20,1,.006,-.030311,-.0175,0.0,.035,0.0*
1,1,.006,0.0,.035*
1,1,.006,-.01433,-.00918*
20,1,.006,-.01433,-.00918,-.01433,.00184,0.0*
1,1,.006,-.01433,.00184*
1,1,.006,-.01433,.00018*
20,1,.006,-.01433,.00018,-.01341,.0011,0.0*
1,1,.006,-.01341,.0011*
20,1,.006,-.01341,.0011,-.01249,.00165,0.0*
1,1,.006,-.01249,.00165*
20,1,.006,-.01249,.00165,-.01102,.00184,0.0*
1,1,.006,-.01102,.00184*
20,1,.006,-.01102,.00184,-.00973,.00165,0.0*
1,1,.006,-.00973,.00165*
20,1,.006,-.00973,.00165,-.00845,.00073,0.0*
1,1,.006,-.00845,.00073*
20,1,.006,-.00845,.00073,-.0079,-.00055,0.0*
1,1,.006,-.0079,-.00055*
20,1,.006,-.0079,-.00055,-.00771,-.00184,0.0*
1,1,.006,-.00771,-.00184*
20,1,.006,-.00771,-.00184,-.0079,-.00312,0.0*
1,1,.006,-.0079,-.00312*
20,1,.006,-.0079,-.00312,-.00845,-.00441,0.0*
1,1,.006,-.00845,-.00441*
20,1,.006,-.00845,-.00441,-.00955,-.00514,0.0*
1,1,.006,-.00955,-.00514*
20,1,.006,-.00955,-.00514,-.01102,-.00551,0.0*
1,1,.006,-.01102,-.00551*
20,1,.006,-.01102,-.00551,-.01231,-.00533,0.0*
1,1,.006,-.01231,-.00533*
20,1,.006,-.01231,-.00533,-.01359,-.00478,0.0*
1,1,.006,-.01359,-.00478*
20,1,.006,-.01359,-.00478,-.01433,-.00404,0.0*
1,1,.006,-.01433,-.00404*
1,1,.006,.00001,.00551*
20,1,.006,.00001,.00551,.00001,-.00551,0.0*
1,1,.006,.00001,-.00551*
1,1,.006,-.00256,.00184*
20,1,.006,-.00256,.00184,.00258,.00184,0.0*
1,1,.006,.00258,.00184*
1,1,.006,.00645,.00184*
20,1,.006,.00645,.00184,.00865,-.00551,0.0*
1,1,.006,.00865,-.00551*
20,1,.006,.00865,-.00551,.01104,.00184,0.0*
1,1,.006,.01104,.00184*
20,1,.006,.01104,.00184,.01343,-.00551,0.0*
1,1,.006,.01343,-.00551*
20,1,.006,.01343,-.00551,.01563,.00184,0.0*
1,1,.006,.01563,.00184*
%
%ADD29MACRO29*%
%AMMACRO31*
1,1,.006,0.0,.035*
20,1,.006,0.0,.035,.030311,-.0175,0.0*
1,1,.006,.030311,-.0175*
20,1,.006,.030311,-.0175,-.030311,-.0175,0.0*
1,1,.006,-.030311,-.0175*
20,1,.006,-.030311,-.0175,0.0,.035,0.0*
1,1,.006,0.0,.035*
1,1,.006,-.01102,.00551*
20,1,.006,-.01102,.00551,-.01249,.00514,0.0*
1,1,.006,-.01249,.00514*
20,1,.006,-.01249,.00514,-.01359,.00422,0.0*
1,1,.006,-.01359,.00422*
20,1,.006,-.01359,.00422,-.01433,.00312,0.0*
1,1,.006,-.01433,.00312*
20,1,.006,-.01433,.00312,-.01488,.00165,0.0*
1,1,.006,-.01488,.00165*
20,1,.006,-.01488,.00165,-.01506,0.0,0.0*
1,1,.006,-.01506,0.0*
20,1,.006,-.01506,0.0,-.01488,-.00165,0.0*
1,1,.006,-.01488,-.00165*
20,1,.006,-.01488,-.00165,-.01433,-.00312,0.0*
1,1,.006,-.01433,-.00312*
20,1,.006,-.01433,-.00312,-.01359,-.00422,0.0*
1,1,.006,-.01359,-.00422*
20,1,.006,-.01359,-.00422,-.01249,-.00514,0.0*
1,1,.006,-.01249,-.00514*
20,1,.006,-.01249,-.00514,-.01102,-.00551,0.0*
1,1,.006,-.01102,-.00551*
20,1,.006,-.01102,-.00551,-.00955,-.00514,0.0*
1,1,.006,-.00955,-.00514*
20,1,.006,-.00955,-.00514,-.00845,-.00422,0.0*
1,1,.006,-.00845,-.00422*
20,1,.006,-.00845,-.00422,-.00771,-.00312,0.0*
1,1,.006,-.00771,-.00312*
20,1,.006,-.00771,-.00312,-.00716,-.00165,0.0*
1,1,.006,-.00716,-.00165*
20,1,.006,-.00716,-.00165,-.00698,0.0,0.0*
1,1,.006,-.00698,0.0*
20,1,.006,-.00698,0.0,-.00716,.00165,0.0*
1,1,.006,-.00716,.00165*
20,1,.006,-.00716,.00165,-.00771,.00312,0.0*
1,1,.006,-.00771,.00312*
20,1,.006,-.00771,.00312,-.00845,.00422,0.0*
1,1,.006,-.00845,.00422*
20,1,.006,-.00845,.00422,-.00955,.00514,0.0*
1,1,.006,-.00955,.00514*
20,1,.006,-.00955,.00514,-.01102,.00551,0.0*
1,1,.006,-.01102,.00551*
1,1,.006,.00221,-.00551*
20,1,.006,.00221,-.00551,.00221,.00551,0.0*
1,1,.006,.00221,.00551*
20,1,.006,.00221,.00551,-.00458,-.00239,0.0*
1,1,.006,-.00458,-.00239*
20,1,.006,-.00458,-.00239,.0046,-.00239,0.0*
1,1,.006,.0046,-.00239*
1,1,.006,.01104,-.00551*
20,1,.006,.01104,-.00551,.01104,.00551,0.0*
1,1,.006,.01104,.00551*
20,1,.006,.01104,.00551,.00884,.00331,0.0*
1,1,.006,.00884,.00331*
1,1,.006,.00884,-.00551*
20,1,.006,.00884,-.00551,.01324,-.00551,0.0*
1,1,.006,.01324,-.00551*
%
%ADD31MACRO31*%
%AMMACRO11*
1,1,.006,.063,0.0*
20,1,.006,.063,0.0,.0315,.05456,0.0*
1,1,.006,.0315,.05456*
20,1,.006,.0315,.05456,-.0315,.05456,0.0*
1,1,.006,-.0315,.05456*
20,1,.006,-.0315,.05456,-.063,0.0,0.0*
1,1,.006,-.063,0.0*
20,1,.006,-.063,0.0,-.0315,-.05456,0.0*
1,1,.006,-.0315,-.05456*
20,1,.006,-.0315,-.05456,.0315,-.05456,0.0*
1,1,.006,.0315,-.05456*
20,1,.006,.0315,-.05456,.063,0.0,0.0*
1,1,.006,.063,0.0*
1,1,.006,-.03087,-.01543*
20,1,.006,-.03087,-.01543,-.03087,.01544,0.0*
1,1,.006,-.03087,.01544*
20,1,.006,-.03087,.01544,-.03704,.00927,0.0*
1,1,.006,-.03704,.00927*
1,1,.006,-.03704,-.01543*
20,1,.006,-.03704,-.01543,-.02469,-.01543,0.0*
1,1,.006,-.02469,-.01543*
1,1,.006,-.00976,.0103*
20,1,.006,-.00976,.0103,-.00667,.01338,0.0*
1,1,.006,-.00667,.01338*
20,1,.006,-.00667,.01338,-.00307,.01493,0.0*
1,1,.006,-.00307,.01493*
20,1,.006,-.00307,.01493,.00104,.01544,0.0*
1,1,.006,.00104,.01544*
20,1,.006,.00104,.01544,.00619,.01441,0.0*
1,1,.006,.00619,.01441*
20,1,.006,.00619,.01441,.00979,.01184,0.0*
1,1,.006,.00979,.01184*
20,1,.006,.00979,.01184,.01082,.00875,0.0*
1,1,.006,.01082,.00875*
20,1,.006,.01082,.00875,.01031,.00566,0.0*
1,1,.006,.01031,.00566*
20,1,.006,.01031,.00566,.00825,.00309,0.0*
1,1,.006,.00825,.00309*
20,1,.006,.00825,.00309,-.00204,-.00205,0.0*
1,1,.006,-.00204,-.00205*
20,1,.006,-.00204,-.00205,-.00667,-.00565,0.0*
1,1,.006,-.00667,-.00565*
20,1,.006,-.00667,-.00565,-.00976,-.0108,0.0*
1,1,.006,-.00976,-.0108*
20,1,.006,-.00976,-.0108,-.01079,-.01543,0.0*
1,1,.006,-.01079,-.01543*
20,1,.006,-.01079,-.01543,.01082,-.01543,0.0*
1,1,.006,.01082,-.01543*
1,1,.006,.02112,-.00257*
20,1,.006,.02112,-.00257,.02472,.00103,0.0*
1,1,.006,.02472,.00103*
20,1,.006,.02472,.00103,.02781,.00309,0.0*
1,1,.006,.02781,.00309*
20,1,.006,.02781,.00309,.03192,.00412,0.0*
1,1,.006,.03192,.00412*
20,1,.006,.03192,.00412,.03553,.00309,0.0*
1,1,.006,.03553,.00309*
20,1,.006,.03553,.00309,.0381,.00103,0.0*
1,1,.006,.0381,.00103*
20,1,.006,.0381,.00103,.04016,-.00205,0.0*
1,1,.006,.04016,-.00205*
20,1,.006,.04016,-.00205,.04067,-.00565,0.0*
1,1,.006,.04067,-.00565*
20,1,.006,.04067,-.00565,.04016,-.00874,0.0*
1,1,.006,.04016,-.00874*
20,1,.006,.04016,-.00874,.0381,-.01183,0.0*
1,1,.006,.0381,-.01183*
20,1,.006,.0381,-.01183,.03501,-.0144,0.0*
1,1,.006,.03501,-.0144*
20,1,.006,.03501,-.0144,.03141,-.01543,0.0*
1,1,.006,.03141,-.01543*
20,1,.006,.03141,-.01543,.02729,-.0144,0.0*
1,1,.006,.02729,-.0144*
20,1,.006,.02729,-.0144,.02369,-.01131,0.0*
1,1,.006,.02369,-.01131*
20,1,.006,.02369,-.01131,.02163,-.00668,0.0*
1,1,.006,.02163,-.00668*
20,1,.006,.02163,-.00668,.02112,-.00154,0.0*
1,1,.006,.02112,-.00154*
20,1,.006,.02112,-.00154,.02215,.00515,0.0*
1,1,.006,.02215,.00515*
20,1,.006,.02215,.00515,.02369,.00875,0.0*
1,1,.006,.02369,.00875*
20,1,.006,.02369,.00875,.02626,.01235,0.0*
1,1,.006,.02626,.01235*
20,1,.006,.02626,.01235,.02987,.01493,0.0*
1,1,.006,.02987,.01493*
20,1,.006,.02987,.01493,.03347,.01544,0.0*
1,1,.006,.03347,.01544*
20,1,.006,.03347,.01544,.03707,.01441,0.0*
1,1,.006,.03707,.01441*
20,1,.006,.03707,.01441,.03964,.01184,0.0*
1,1,.006,.03964,.01184*
%
%ADD11MACRO11*%
%AMMACRO33*
1,1,.006,-.01,-.014*
20,1,.006,-.01,-.014,-.01,.014,0.0*
1,1,.006,-.01,.014*
20,1,.006,-.01,.014,-.009848,.015736,0.0*
1,1,.006,-.009848,.015736*
20,1,.006,-.009848,.015736,-.009397,.01742,0.0*
1,1,.006,-.009397,.01742*
20,1,.006,-.009397,.01742,-.00866,.019,0.0*
1,1,.006,-.00866,.019*
20,1,.006,-.00866,.019,-.00766,.020428,0.0*
1,1,.006,-.00766,.020428*
20,1,.006,-.00766,.020428,-.006428,.02166,0.0*
1,1,.006,-.006428,.02166*
20,1,.006,-.006428,.02166,-.005,.02266,0.0*
1,1,.006,-.005,.02266*
20,1,.006,-.005,.02266,-.00342,.023397,0.0*
1,1,.006,-.00342,.023397*
20,1,.006,-.00342,.023397,-.001736,.023848,0.0*
1,1,.006,-.001736,.023848*
20,1,.006,-.001736,.023848,0.0,.024,0.0*
1,1,.006,0.0,.024*
20,1,.006,0.0,.024,.001736,.023848,0.0*
1,1,.006,.001736,.023848*
20,1,.006,.001736,.023848,.00342,.023397,0.0*
1,1,.006,.00342,.023397*
20,1,.006,.00342,.023397,.005,.02266,0.0*
1,1,.006,.005,.02266*
20,1,.006,.005,.02266,.006428,.02166,0.0*
1,1,.006,.006428,.02166*
20,1,.006,.006428,.02166,.00766,.020428,0.0*
1,1,.006,.00766,.020428*
20,1,.006,.00766,.020428,.00866,.019,0.0*
1,1,.006,.00866,.019*
20,1,.006,.00866,.019,.009397,.01742,0.0*
1,1,.006,.009397,.01742*
20,1,.006,.009397,.01742,.009848,.015736,0.0*
1,1,.006,.009848,.015736*
20,1,.006,.009848,.015736,.01,.014,0.0*
1,1,.006,.01,.014*
20,1,.006,.01,.014,.01,-.014,0.0*
1,1,.006,.01,-.014*
20,1,.006,.01,-.014,.009848,-.015736,0.0*
1,1,.006,.009848,-.015736*
20,1,.006,.009848,-.015736,.009397,-.01742,0.0*
1,1,.006,.009397,-.01742*
20,1,.006,.009397,-.01742,.00866,-.019,0.0*
1,1,.006,.00866,-.019*
20,1,.006,.00866,-.019,.00766,-.020428,0.0*
1,1,.006,.00766,-.020428*
20,1,.006,.00766,-.020428,.006428,-.02166,0.0*
1,1,.006,.006428,-.02166*
20,1,.006,.006428,-.02166,.005,-.02266,0.0*
1,1,.006,.005,-.02266*
20,1,.006,.005,-.02266,.00342,-.023397,0.0*
1,1,.006,.00342,-.023397*
20,1,.006,.00342,-.023397,.001736,-.023848,0.0*
1,1,.006,.001736,-.023848*
20,1,.006,.001736,-.023848,0.0,-.024,0.0*
1,1,.006,0.0,-.024*
20,1,.006,0.0,-.024,-.001736,-.023848,0.0*
1,1,.006,-.001736,-.023848*
20,1,.006,-.001736,-.023848,-.00342,-.023397,0.0*
1,1,.006,-.00342,-.023397*
20,1,.006,-.00342,-.023397,-.005,-.02266,0.0*
1,1,.006,-.005,-.02266*
20,1,.006,-.005,-.02266,-.006428,-.02166,0.0*
1,1,.006,-.006428,-.02166*
20,1,.006,-.006428,-.02166,-.00766,-.020428,0.0*
1,1,.006,-.00766,-.020428*
20,1,.006,-.00766,-.020428,-.00866,-.019,0.0*
1,1,.006,-.00866,-.019*
20,1,.006,-.00866,-.019,-.009397,-.01742,0.0*
1,1,.006,-.009397,-.01742*
20,1,.006,-.009397,-.01742,-.009848,-.015736,0.0*
1,1,.006,-.009848,-.015736*
20,1,.006,-.009848,-.015736,-.01,-.014,0.0*
1,1,.006,-.01,-.014*
1,1,.006,-.00887,-.00525*
20,1,.006,-.00887,-.00525,-.00805,-.00572,0.0*
1,1,.006,-.00805,-.00572*
20,1,.006,-.00805,-.00572,-.00735,-.00583,0.0*
1,1,.006,-.00735,-.00583*
20,1,.006,-.00735,-.00583,-.00642,-.0056,0.0*
1,1,.006,-.00642,-.0056*
20,1,.006,-.00642,-.0056,-.00572,-.00502,0.0*
1,1,.006,-.00572,-.00502*
20,1,.006,-.00572,-.00502,-.00537,-.00397,0.0*
1,1,.006,-.00537,-.00397*
20,1,.006,-.00537,-.00397,-.00537,.00117,0.0*
1,1,.006,-.00537,.00117*
1,1,.006,-.00537,.00303*
20,1,.006,-.00537,.00303,-.0056,.00315,0.0*
1,1,.006,-.0056,.00315*
20,1,.006,-.0056,.00315,-.0056,.00338,0.0*
1,1,.006,-.0056,.00338*
20,1,.006,-.0056,.00338,-.00537,.0035,0.0*
1,1,.006,-.00537,.0035*
20,1,.006,-.00537,.0035,-.00513,.00338,0.0*
1,1,.006,-.00513,.00338*
20,1,.006,-.00513,.00338,-.00513,.00315,0.0*
1,1,.006,-.00513,.00315*
20,1,.006,-.00513,.00315,-.00537,.00303,0.0*
1,1,.006,-.00537,.00303*
1,1,.006,.00211,-.0035*
20,1,.006,.00211,-.0035,.00211,.00117,0.0*
1,1,.006,.00211,.00117*
1,1,.006,.00211,.00035*
20,1,.006,.00211,.00035,.00164,.00082,0.0*
1,1,.006,.00164,.00082*
20,1,.006,.00164,.00082,.00094,.00105,0.0*
1,1,.006,.00094,.00105*
20,1,.006,.00094,.00105,.00013,.00117,0.0*
1,1,.006,.00013,.00117*
20,1,.006,.00013,.00117,-.00069,.00093,0.0*
1,1,.006,-.00069,.00093*
20,1,.006,-.00069,.00093,-.00139,.00047,0.0*
1,1,.006,-.00139,.00047*
20,1,.006,-.00139,.00047,-.00186,-.00023,0.0*
1,1,.006,-.00186,-.00023*
20,1,.006,-.00186,-.00023,-.00209,-.00117,0.0*
1,1,.006,-.00209,-.00117*
20,1,.006,-.00209,-.00117,-.00186,-.0021,0.0*
1,1,.006,-.00186,-.0021*
20,1,.006,-.00186,-.0021,-.00139,-.0028,0.0*
1,1,.006,-.00139,-.0028*
20,1,.006,-.00139,-.0028,-.00069,-.00327,0.0*
1,1,.006,-.00069,-.00327*
20,1,.006,-.00069,-.00327,.00013,-.0035,0.0*
1,1,.006,.00013,-.0035*
20,1,.006,.00013,-.0035,.00094,-.00338,0.0*
1,1,.006,.00094,-.00338*
20,1,.006,.00094,-.00338,.00164,-.00303,0.0*
1,1,.006,.00164,-.00303*
20,1,.006,.00164,-.00303,.00211,-.00257,0.0*
1,1,.006,.00211,-.00257*
1,1,.006,.00702,-.0035*
20,1,.006,.00702,-.0035,.00784,-.00338,0.0*
1,1,.006,.00784,-.00338*
20,1,.006,.00784,-.00338,.00877,-.00303,0.0*
1,1,.006,.00877,-.00303*
20,1,.006,.00877,-.00303,.00935,-.00245,0.0*
1,1,.006,.00935,-.00245*
20,1,.006,.00935,-.00245,.00959,-.00163,0.0*
1,1,.006,.00959,-.00163*
20,1,.006,.00959,-.00163,.00935,-.00082,0.0*
1,1,.006,.00935,-.00082*
20,1,.006,.00935,-.00082,.00865,-.00012,0.0*
1,1,.006,.00865,-.00012*
20,1,.006,.00865,-.00012,.0076,.00023,0.0*
1,1,.006,.0076,.00023*
20,1,.006,.0076,.00023,.00644,.00023,0.0*
1,1,.006,.00644,.00023*
20,1,.006,.00644,.00023,.00574,.00047,0.0*
1,1,.006,.00574,.00047*
20,1,.006,.00574,.00047,.00515,.00105,0.0*
1,1,.006,.00515,.00105*
20,1,.006,.00515,.00105,.00492,.00187,0.0*
1,1,.006,.00492,.00187*
20,1,.006,.00492,.00187,.00527,.00268,0.0*
1,1,.006,.00527,.00268*
20,1,.006,.00527,.00268,.00609,.00327,0.0*
1,1,.006,.00609,.00327*
20,1,.006,.00609,.00327,.00702,.0035,0.0*
1,1,.006,.00702,.0035*
20,1,.006,.00702,.0035,.00795,.00327,0.0*
1,1,.006,.00795,.00327*
20,1,.006,.00795,.00327,.00877,.00268,0.0*
1,1,.006,.00877,.00268*
20,1,.006,.00877,.00268,.00912,.00187,0.0*
1,1,.006,.00912,.00187*
20,1,.006,.00912,.00187,.00889,.00105,0.0*
1,1,.006,.00889,.00105*
20,1,.006,.00889,.00105,.0083,.00047,0.0*
1,1,.006,.0083,.00047*
20,1,.006,.0083,.00047,.0076,.00023,0.0*
1,1,.006,.0076,.00023*
20,1,.006,.0076,.00023,.00644,.00023,0.0*
1,1,.006,.00644,.00023*
20,1,.006,.00644,.00023,.00539,-.00012,0.0*
1,1,.006,.00539,-.00012*
20,1,.006,.00539,-.00012,.00469,-.00082,0.0*
1,1,.006,.00469,-.00082*
20,1,.006,.00469,-.00082,.00445,-.00163,0.0*
1,1,.006,.00445,-.00163*
20,1,.006,.00445,-.00163,.00469,-.00245,0.0*
1,1,.006,.00469,-.00245*
20,1,.006,.00469,-.00245,.00527,-.00303,0.0*
1,1,.006,.00527,-.00303*
20,1,.006,.00527,-.00303,.0062,-.00338,0.0*
1,1,.006,.0062,-.00338*
20,1,.006,.0062,-.00338,.00702,-.0035,0.0*
1,1,.006,.00702,-.0035*
%
%ADD33MACRO33*%
%AMMACRO24*
1,1,.006,0.0,.035*
20,1,.006,0.0,.035,.030311,-.0175,0.0*
1,1,.006,.030311,-.0175*
20,1,.006,.030311,-.0175,-.030311,-.0175,0.0*
1,1,.006,-.030311,-.0175*
20,1,.006,-.030311,-.0175,0.0,.035,0.0*
1,1,.006,0.0,.035*
1,1,.006,-.01102,.00551*
20,1,.006,-.01102,.00551,-.01249,.00514,0.0*
1,1,.006,-.01249,.00514*
20,1,.006,-.01249,.00514,-.01359,.00422,0.0*
1,1,.006,-.01359,.00422*
20,1,.006,-.01359,.00422,-.01433,.00312,0.0*
1,1,.006,-.01433,.00312*
20,1,.006,-.01433,.00312,-.01488,.00165,0.0*
1,1,.006,-.01488,.00165*
20,1,.006,-.01488,.00165,-.01506,0.0,0.0*
1,1,.006,-.01506,0.0*
20,1,.006,-.01506,0.0,-.01488,-.00165,0.0*
1,1,.006,-.01488,-.00165*
20,1,.006,-.01488,-.00165,-.01433,-.00312,0.0*
1,1,.006,-.01433,-.00312*
20,1,.006,-.01433,-.00312,-.01359,-.00422,0.0*
1,1,.006,-.01359,-.00422*
20,1,.006,-.01359,-.00422,-.01249,-.00514,0.0*
1,1,.006,-.01249,-.00514*
20,1,.006,-.01249,-.00514,-.01102,-.00551,0.0*
1,1,.006,-.01102,-.00551*
20,1,.006,-.01102,-.00551,-.00955,-.00514,0.0*
1,1,.006,-.00955,-.00514*
20,1,.006,-.00955,-.00514,-.00845,-.00422,0.0*
1,1,.006,-.00845,-.00422*
20,1,.006,-.00845,-.00422,-.00771,-.00312,0.0*
1,1,.006,-.00771,-.00312*
20,1,.006,-.00771,-.00312,-.00716,-.00165,0.0*
1,1,.006,-.00716,-.00165*
20,1,.006,-.00716,-.00165,-.00698,0.0,0.0*
1,1,.006,-.00698,0.0*
20,1,.006,-.00698,0.0,-.00716,.00165,0.0*
1,1,.006,-.00716,.00165*
20,1,.006,-.00716,.00165,-.00771,.00312,0.0*
1,1,.006,-.00771,.00312*
20,1,.006,-.00771,.00312,-.00845,.00422,0.0*
1,1,.006,-.00845,.00422*
20,1,.006,-.00845,.00422,-.00955,.00514,0.0*
1,1,.006,-.00955,.00514*
20,1,.006,-.00955,.00514,-.01102,.00551,0.0*
1,1,.006,-.01102,.00551*
1,1,.006,.00221,-.00551*
20,1,.006,.00221,-.00551,.00221,.00551,0.0*
1,1,.006,.00221,.00551*
20,1,.006,.00221,.00551,-.00458,-.00239,0.0*
1,1,.006,-.00458,-.00239*
20,1,.006,-.00458,-.00239,.0046,-.00239,0.0*
1,1,.006,.0046,-.00239*
1,1,.006,.01324,-.00551*
20,1,.006,.01324,-.00551,.01324,.00551,0.0*
1,1,.006,.01324,.00551*
20,1,.006,.01324,.00551,.00645,-.00239,0.0*
1,1,.006,.00645,-.00239*
20,1,.006,.00645,-.00239,.01563,-.00239,0.0*
1,1,.006,.01563,-.00239*
%
%ADD24MACRO24*%
%AMMACRO17*
1,1,.006,-.0265,.022*
20,1,.006,-.0265,.022,.0265,.022,0.0*
1,1,.006,.0265,.022*
20,1,.006,.0265,.022,.03032,.021666,0.0*
1,1,.006,.03032,.021666*
20,1,.006,.03032,.021666,.034024,.020673,0.0*
1,1,.006,.034024,.020673*
20,1,.006,.034024,.020673,.0375,.019053,0.0*
1,1,.006,.0375,.019053*
20,1,.006,.0375,.019053,.040641,.016853,0.0*
1,1,.006,.040641,.016853*
20,1,.006,.040641,.016853,.043353,.014141,0.0*
1,1,.006,.043353,.014141*
20,1,.006,.043353,.014141,.045553,.011,0.0*
1,1,.006,.045553,.011*
20,1,.006,.045553,.011,.047173,.007524,0.0*
1,1,.006,.047173,.007524*
20,1,.006,.047173,.007524,.048166,.00382,0.0*
1,1,.006,.048166,.00382*
20,1,.006,.048166,.00382,.0485,0.0,0.0*
1,1,.006,.0485,0.0*
20,1,.006,.0485,0.0,.048166,-.00382,0.0*
1,1,.006,.048166,-.00382*
20,1,.006,.048166,-.00382,.047173,-.007524,0.0*
1,1,.006,.047173,-.007524*
20,1,.006,.047173,-.007524,.045553,-.011,0.0*
1,1,.006,.045553,-.011*
20,1,.006,.045553,-.011,.043353,-.014141,0.0*
1,1,.006,.043353,-.014141*
20,1,.006,.043353,-.014141,.040641,-.016853,0.0*
1,1,.006,.040641,-.016853*
20,1,.006,.040641,-.016853,.0375,-.019053,0.0*
1,1,.006,.0375,-.019053*
20,1,.006,.0375,-.019053,.034024,-.020673,0.0*
1,1,.006,.034024,-.020673*
20,1,.006,.034024,-.020673,.03032,-.021666,0.0*
1,1,.006,.03032,-.021666*
20,1,.006,.03032,-.021666,.0265,-.022,0.0*
1,1,.006,.0265,-.022*
20,1,.006,.0265,-.022,-.0265,-.022,0.0*
1,1,.006,-.0265,-.022*
20,1,.006,-.0265,-.022,-.03032,-.021666,0.0*
1,1,.006,-.03032,-.021666*
20,1,.006,-.03032,-.021666,-.034024,-.020673,0.0*
1,1,.006,-.034024,-.020673*
20,1,.006,-.034024,-.020673,-.0375,-.019053,0.0*
1,1,.006,-.0375,-.019053*
20,1,.006,-.0375,-.019053,-.040641,-.016853,0.0*
1,1,.006,-.040641,-.016853*
20,1,.006,-.040641,-.016853,-.043353,-.014141,0.0*
1,1,.006,-.043353,-.014141*
20,1,.006,-.043353,-.014141,-.045553,-.011,0.0*
1,1,.006,-.045553,-.011*
20,1,.006,-.045553,-.011,-.047173,-.007524,0.0*
1,1,.006,-.047173,-.007524*
20,1,.006,-.047173,-.007524,-.048166,-.00382,0.0*
1,1,.006,-.048166,-.00382*
20,1,.006,-.048166,-.00382,-.0485,0.0,0.0*
1,1,.006,-.0485,0.0*
20,1,.006,-.0485,0.0,-.048166,.00382,0.0*
1,1,.006,-.048166,.00382*
20,1,.006,-.048166,.00382,-.047173,.007524,0.0*
1,1,.006,-.047173,.007524*
20,1,.006,-.047173,.007524,-.045553,.011,0.0*
1,1,.006,-.045553,.011*
20,1,.006,-.045553,.011,-.043353,.014141,0.0*
1,1,.006,-.043353,.014141*
20,1,.006,-.043353,.014141,-.040641,.016853,0.0*
1,1,.006,-.040641,.016853*
20,1,.006,-.040641,.016853,-.0375,.019053,0.0*
1,1,.006,-.0375,.019053*
20,1,.006,-.0375,.019053,-.034024,.020673,0.0*
1,1,.006,-.034024,.020673*
20,1,.006,-.034024,.020673,-.03032,.021666,0.0*
1,1,.006,-.03032,.021666*
20,1,.006,-.03032,.021666,-.0265,.022,0.0*
1,1,.006,-.0265,.022*
1,1,.006,-.01232,-.0077*
20,1,.006,-.01232,-.0077,-.01232,.0077,0.0*
1,1,.006,-.01232,.0077*
20,1,.006,-.01232,.0077,-.02182,-.00334,0.0*
1,1,.006,-.02182,-.00334*
20,1,.006,-.02182,-.00334,-.00898,-.00334,0.0*
1,1,.006,-.00898,-.00334*
1,1,.006,-.00461,-.0077*
20,1,.006,-.00461,-.0077,-.00461,.0077,0.0*
1,1,.006,-.00461,.0077*
1,1,.006,-.00461,0.0*
20,1,.006,-.00461,0.0,-.00333,.00154,0.0*
1,1,.006,-.00333,.00154*
20,1,.006,-.00333,.00154,-.00179,.00231,0.0*
1,1,.006,-.00179,.00231*
20,1,.006,-.00179,.00231,-.00025,.00257,0.0*
1,1,.006,-.00025,.00257*
20,1,.006,-.00025,.00257,.00206,.00205,0.0*
1,1,.006,.00206,.00205*
20,1,.006,.00206,.00205,.0036,.00103,0.0*
1,1,.006,.0036,.00103*
20,1,.006,.0036,.00103,.00463,-.00077,0.0*
1,1,.006,.00463,-.00077*
20,1,.006,.00463,-.00077,.00463,-.00282,0.0*
1,1,.006,.00463,-.00282*
20,1,.006,.00463,-.00282,.00412,-.00488,0.0*
1,1,.006,.00412,-.00488*
20,1,.006,.00412,-.00488,.00309,-.00642,0.0*
1,1,.006,.00309,-.00642*
20,1,.006,.00309,-.00642,.00129,-.00744,0.0*
1,1,.006,.00129,-.00744*
20,1,.006,.00129,-.00744,-.00025,-.0077,0.0*
1,1,.006,-.00025,-.0077*
20,1,.006,-.00025,-.0077,-.00179,-.00744,0.0*
1,1,.006,-.00179,-.00744*
20,1,.006,-.00179,-.00744,-.00333,-.00667,0.0*
1,1,.006,-.00333,-.00667*
20,1,.006,-.00333,-.00667,-.00461,-.00539,0.0*
1,1,.006,-.00461,-.00539*
1,1,.006,.01183,-.01155*
20,1,.006,.01183,-.01155,.01362,-.01258,0.0*
1,1,.006,.01362,-.01258*
20,1,.006,.01362,-.01258,.01568,-.01283,0.0*
1,1,.006,.01568,-.01283*
20,1,.006,.01568,-.01283,.01747,-.01258,0.0*
1,1,.006,.01747,-.01258*
20,1,.006,.01747,-.01258,.01901,-.01129,0.0*
1,1,.006,.01901,-.01129*
20,1,.006,.01901,-.01129,.02004,-.0095,0.0*
1,1,.006,.02004,-.0095*
20,1,.006,.02004,-.0095,.02004,.00257,0.0*
1,1,.006,.02004,.00257*
1,1,.006,.02004,.00051*
20,1,.006,.02004,.00051,.01901,.00154,0.0*
1,1,.006,.01901,.00154*
20,1,.006,.01901,.00154,.01747,.00231,0.0*
1,1,.006,.01747,.00231*
20,1,.006,.01747,.00231,.01568,.00257,0.0*
1,1,.006,.01568,.00257*
20,1,.006,.01568,.00257,.01362,.00205,0.0*
1,1,.006,.01362,.00205*
20,1,.006,.01362,.00205,.01234,.00103,0.0*
1,1,.006,.01234,.00103*
20,1,.006,.01234,.00103,.01131,-.00077,0.0*
1,1,.006,.01131,-.00077*
20,1,.006,.01131,-.00077,.0108,-.00257,0.0*
1,1,.006,.0108,-.00257*
20,1,.006,.0108,-.00257,.01106,-.00411,0.0*
1,1,.006,.01106,-.00411*
20,1,.006,.01106,-.00411,.01208,-.0059,0.0*
1,1,.006,.01208,-.0059*
20,1,.006,.01208,-.0059,.01362,-.00719,0.0*
1,1,.006,.01362,-.00719*
20,1,.006,.01362,-.00719,.01568,-.0077,0.0*
1,1,.006,.01568,-.0077*
20,1,.006,.01568,-.0077,.01722,-.00744,0.0*
1,1,.006,.01722,-.00744*
20,1,.006,.01722,-.00744,.01901,-.00642,0.0*
1,1,.006,.01901,-.00642*
20,1,.006,.01901,-.00642,.02004,-.00539,0.0*
1,1,.006,.02004,-.00539*
%
%ADD17MACRO17*%
%AMMACRO32*
1,1,.006,0.0,.035*
20,1,.006,0.0,.035,.030311,-.0175,0.0*
1,1,.006,.030311,-.0175*
20,1,.006,.030311,-.0175,-.030311,-.0175,0.0*
1,1,.006,-.030311,-.0175*
20,1,.006,-.030311,-.0175,0.0,.035,0.0*
1,1,.006,0.0,.035*
1,1,.006,-.01102,.00551*
20,1,.006,-.01102,.00551,-.01249,.00514,0.0*
1,1,.006,-.01249,.00514*
20,1,.006,-.01249,.00514,-.01359,.00422,0.0*
1,1,.006,-.01359,.00422*
20,1,.006,-.01359,.00422,-.01433,.00312,0.0*
1,1,.006,-.01433,.00312*
20,1,.006,-.01433,.00312,-.01488,.00165,0.0*
1,1,.006,-.01488,.00165*
20,1,.006,-.01488,.00165,-.01506,0.0,0.0*
1,1,.006,-.01506,0.0*
20,1,.006,-.01506,0.0,-.01488,-.00165,0.0*
1,1,.006,-.01488,-.00165*
20,1,.006,-.01488,-.00165,-.01433,-.00312,0.0*
1,1,.006,-.01433,-.00312*
20,1,.006,-.01433,-.00312,-.01359,-.00422,0.0*
1,1,.006,-.01359,-.00422*
20,1,.006,-.01359,-.00422,-.01249,-.00514,0.0*
1,1,.006,-.01249,-.00514*
20,1,.006,-.01249,-.00514,-.01102,-.00551,0.0*
1,1,.006,-.01102,-.00551*
20,1,.006,-.01102,-.00551,-.00955,-.00514,0.0*
1,1,.006,-.00955,-.00514*
20,1,.006,-.00955,-.00514,-.00845,-.00422,0.0*
1,1,.006,-.00845,-.00422*
20,1,.006,-.00845,-.00422,-.00771,-.00312,0.0*
1,1,.006,-.00771,-.00312*
20,1,.006,-.00771,-.00312,-.00716,-.00165,0.0*
1,1,.006,-.00716,-.00165*
20,1,.006,-.00716,-.00165,-.00698,0.0,0.0*
1,1,.006,-.00698,0.0*
20,1,.006,-.00698,0.0,-.00716,.00165,0.0*
1,1,.006,-.00716,.00165*
20,1,.006,-.00716,.00165,-.00771,.00312,0.0*
1,1,.006,-.00771,.00312*
20,1,.006,-.00771,.00312,-.00845,.00422,0.0*
1,1,.006,-.00845,.00422*
20,1,.006,-.00845,.00422,-.00955,.00514,0.0*
1,1,.006,-.00955,.00514*
20,1,.006,-.00955,.00514,-.01102,.00551,0.0*
1,1,.006,-.01102,.00551*
1,1,.006,-.00348,-.00092*
20,1,.006,-.00348,-.00092,-.00219,.00037,0.0*
1,1,.006,-.00219,.00037*
20,1,.006,-.00219,.00037,-.00109,.0011,0.0*
1,1,.006,-.00109,.0011*
20,1,.006,-.00109,.0011,.00038,.00147,0.0*
1,1,.006,.00038,.00147*
20,1,.006,.00038,.00147,.00166,.0011,0.0*
1,1,.006,.00166,.0011*
20,1,.006,.00166,.0011,.00258,.00037,0.0*
1,1,.006,.00258,.00037*
20,1,.006,.00258,.00037,.00332,-.00073,0.0*
1,1,.006,.00332,-.00073*
20,1,.006,.00332,-.00073,.0035,-.00202,0.0*
1,1,.006,.0035,-.00202*
20,1,.006,.0035,-.00202,.00332,-.00312,0.0*
1,1,.006,.00332,-.00312*
20,1,.006,.00332,-.00312,.00258,-.00422,0.0*
1,1,.006,.00258,-.00422*
20,1,.006,.00258,-.00422,.00148,-.00514,0.0*
1,1,.006,.00148,-.00514*
20,1,.006,.00148,-.00514,.00019,-.00551,0.0*
1,1,.006,.00019,-.00551*
20,1,.006,.00019,-.00551,-.00128,-.00514,0.0*
1,1,.006,-.00128,-.00514*
20,1,.006,-.00128,-.00514,-.00256,-.00404,0.0*
1,1,.006,-.00256,-.00404*
20,1,.006,-.00256,-.00404,-.0033,-.00239,0.0*
1,1,.006,-.0033,-.00239*
20,1,.006,-.0033,-.00239,-.00348,-.00055,0.0*
1,1,.006,-.00348,-.00055*
20,1,.006,-.00348,-.00055,-.00311,.00184,0.0*
1,1,.006,-.00311,.00184*
20,1,.006,-.00311,.00184,-.00256,.00312,0.0*
1,1,.006,-.00256,.00312*
20,1,.006,-.00256,.00312,-.00164,.00441,0.0*
1,1,.006,-.00164,.00441*
20,1,.006,-.00164,.00441,-.00036,.00533,0.0*
1,1,.006,-.00036,.00533*
20,1,.006,-.00036,.00533,.00093,.00551,0.0*
1,1,.006,.00093,.00551*
20,1,.006,.00093,.00551,.00221,.00514,0.0*
1,1,.006,.00221,.00514*
20,1,.006,.00221,.00514,.00313,.00422,0.0*
1,1,.006,.00313,.00422*
1,1,.006,.01067,-.00551*
20,1,.006,.01067,-.00551,.01104,-.00312,0.0*
1,1,.006,.01104,-.00312*
20,1,.006,.01104,-.00312,.01159,-.0011,0.0*
1,1,.006,.01159,-.0011*
20,1,.006,.01159,-.0011,.01233,.00073,0.0*
1,1,.006,.01233,.00073*
20,1,.006,.01233,.00073,.01324,.00275,0.0*
1,1,.006,.01324,.00275*
20,1,.006,.01324,.00275,.01471,.00551,0.0*
1,1,.006,.01471,.00551*
20,1,.006,.01471,.00551,.00737,.00551,0.0*
1,1,.006,.00737,.00551*
%
%ADD32MACRO32*%
%ADD36C,.006*%
G75*
%LPD*%
G75*
G54D10*
X3704Y5374D03*
X3017Y24773D03*
Y44773D03*
Y64773D03*
Y84773D03*
Y104773D03*
Y124773D03*
Y144773D03*
Y164773D03*
Y184773D03*
Y204773D03*
Y224773D03*
Y244773D03*
Y264773D03*
Y284773D03*
Y304773D03*
X3221Y324773D03*
X3035Y978036D03*
Y998036D03*
Y1018036D03*
Y1038036D03*
Y1058036D03*
Y1078036D03*
Y1098036D03*
Y1118036D03*
Y1138036D03*
Y1158036D03*
Y1178036D03*
Y1198036D03*
Y1238036D03*
Y1258036D03*
Y1278036D03*
Y1298036D03*
Y1318036D03*
Y1338036D03*
Y1358036D03*
Y1378036D03*
Y1398036D03*
Y1418036D03*
Y1438036D03*
Y1458036D03*
Y1478036D03*
Y1498036D03*
Y1538036D03*
Y1558036D03*
Y1578036D03*
X3017Y1639466D03*
X15972Y3000D03*
X20408Y51296D03*
Y55296D03*
X14751Y62381D03*
X7271Y70981D03*
X12601Y92110D03*
X8786Y88425D03*
X14264Y94236D03*
X18000Y90000D03*
X9364Y107501D03*
X16728Y107910D03*
X12652Y116894D03*
X18298Y102141D03*
X8000Y102500D03*
X15143Y115581D03*
X14996Y133034D03*
X11442Y132719D03*
X9057Y138939D03*
X19184Y144728D03*
X15184D03*
X9082Y135789D03*
X19855Y141362D03*
X11999Y141415D03*
X13615Y153263D03*
X10966Y155873D03*
Y152873D03*
Y162073D03*
Y159073D03*
X12709Y175777D03*
X16709Y175943D03*
X15139Y198883D03*
X15520Y195176D03*
X13020D03*
X10520D03*
X12880Y203393D03*
X10380D03*
X19068Y206838D03*
X16568D03*
X19572Y219470D03*
Y221970D03*
X10259Y218085D03*
X13059D03*
X19638Y226320D03*
X16859Y216385D03*
X19572Y216970D03*
X18564Y238589D03*
X9745Y245784D03*
X13715Y259381D03*
X8970Y254871D03*
X19075Y278429D03*
X7036Y268371D03*
Y272371D03*
X10971Y333342D03*
X17964Y349298D03*
Y369298D03*
Y389298D03*
Y409298D03*
Y429298D03*
Y449298D03*
Y469298D03*
Y489298D03*
Y509298D03*
Y529298D03*
Y549298D03*
Y569298D03*
Y589298D03*
Y609298D03*
Y629298D03*
Y649298D03*
Y669298D03*
Y689298D03*
Y709298D03*
Y729298D03*
Y749298D03*
Y769298D03*
Y789298D03*
Y809298D03*
Y829298D03*
Y849298D03*
Y869298D03*
Y889298D03*
Y909298D03*
Y929298D03*
X9554Y961954D03*
X17964Y949298D03*
X17033Y1006819D03*
X14357Y1009906D03*
X20216Y1009748D03*
X14197Y1017759D03*
X20197Y1014205D03*
Y1017759D03*
X6161Y1075991D03*
X6108Y1070611D03*
Y1065318D03*
X6059Y1091964D03*
X6055Y1086546D03*
X6053Y1081305D03*
X14252Y1121333D03*
X11552D03*
X16752D03*
X8952D03*
X14152Y1111633D03*
X11452D03*
X8852D03*
X16652D03*
X14252Y1130333D03*
X16752D03*
X14306Y1138705D03*
X16806D03*
X20079Y1429347D03*
X13606Y1476707D03*
X6690Y1496782D03*
X19365Y1494298D03*
X6489Y1501334D03*
X19745Y1508846D03*
X7983Y1529035D03*
Y1525635D03*
X8042Y1522199D03*
X12327Y1519202D03*
X7983Y1529035D03*
Y1525635D03*
X19735Y1530499D03*
X7922Y1532494D03*
X11995Y1535134D03*
X6951Y1538547D03*
X6567Y1554215D03*
X14375Y1553121D03*
X18409Y1554202D03*
X10367Y1553080D03*
X12000Y1644980D03*
X26956Y4469D03*
X28317Y24773D03*
Y44773D03*
X24316Y67527D03*
Y63527D03*
Y59527D03*
X35638Y53597D03*
X32350Y67562D03*
X28442Y55340D03*
X32350Y59562D03*
Y63562D03*
X35688Y114655D03*
Y111255D03*
X28388Y118342D03*
X33288Y109410D03*
Y116497D03*
X30788D03*
X25988D03*
X22439Y106495D03*
X35688Y111255D03*
Y114655D03*
X22439Y102495D03*
X35207Y106561D03*
X35688Y125428D03*
Y128828D03*
X28388Y121742D03*
Y132515D03*
Y135915D03*
X30788Y123584D03*
X33288Y123583D03*
X25988Y123584D03*
X33288Y130670D03*
X30788D03*
X25988D03*
X28388Y121742D03*
X35688Y125428D03*
X28388Y132515D03*
Y118342D03*
X35688Y128828D03*
X30788Y137757D03*
X25988D03*
X23184Y144728D03*
X28388Y135915D03*
X29201Y151651D03*
X26201D03*
X22935Y162073D03*
Y159073D03*
X20709Y175777D03*
X30567Y195176D03*
X28067D03*
X25567D03*
X33067D03*
X29585Y199248D03*
X34520Y213539D03*
X29921Y206806D03*
X32585Y202048D03*
X25648Y210509D03*
X28148D03*
X29585Y201748D03*
X27421Y206806D03*
X36201Y238714D03*
X21530Y236121D03*
X27966Y238689D03*
X28740Y247292D03*
X32201Y238714D03*
X23844Y239299D03*
X21556Y232971D03*
X31682Y246874D03*
X33902Y244297D03*
X21449Y253198D03*
X26325Y262078D03*
X28740Y267292D03*
X21386Y273198D03*
X31682Y266874D03*
X23479Y295619D03*
X34845Y291756D03*
X26629Y295619D03*
X35650Y487982D03*
Y478982D03*
Y483982D03*
Y499982D03*
Y491982D03*
Y495982D03*
X25819Y531726D03*
Y536726D03*
X30177Y534211D03*
X25819Y527726D03*
Y552726D03*
Y540726D03*
Y548726D03*
Y544726D03*
X32452Y581222D03*
X29652D03*
X35252D03*
Y591215D03*
X29652D03*
X32452D03*
X34254Y611091D03*
X30123Y611071D03*
X27686Y621311D03*
X29451Y633560D03*
X27686Y629311D03*
X36692Y641817D03*
X30369Y663048D03*
X27625Y663094D03*
X35293Y662952D03*
X25818Y682139D03*
X27854Y671553D03*
X30414Y671508D03*
X35250D03*
X34565Y699082D03*
X26596Y874520D03*
X26844Y920354D03*
X24132Y958151D03*
X25371Y980696D03*
X36529Y1006321D03*
X24456Y1006401D03*
X32093Y1009748D03*
X26155Y1009985D03*
X29197Y1014205D03*
X32197Y1017759D03*
X26197D03*
X35197Y1014205D03*
X21196Y1065529D03*
Y1063029D03*
X36089Y1062601D03*
Y1065101D03*
X35925Y1075663D03*
X33425D03*
X28996Y1065529D03*
X23796D03*
X26396D03*
Y1063029D03*
X23796D03*
X28996D03*
X28606Y1082678D03*
X23406D03*
X26006D03*
Y1080178D03*
X23406D03*
X28606D03*
X20806Y1082678D03*
Y1080178D03*
X21321Y1098769D03*
X26521D03*
X29121D03*
X23921D03*
Y1101335D03*
X29121D03*
X26521D03*
X21321D03*
X32574Y1111633D03*
X29874D03*
X27274D03*
X24674D03*
Y1121333D03*
X27274D03*
X29874D03*
X32574D03*
X24674Y1130333D03*
X21974D03*
X21209Y1138705D03*
X23709D03*
X27934Y1204311D03*
X30934D03*
X30410Y1218497D03*
Y1220997D03*
X27934Y1215511D03*
X30934D03*
X34314Y1215403D03*
X27934Y1212711D03*
Y1209911D03*
Y1207111D03*
X30934Y1212711D03*
Y1209911D03*
Y1207111D03*
X30410Y1234797D03*
Y1232297D03*
Y1227897D03*
Y1225397D03*
Y1241697D03*
Y1239197D03*
X29860Y1438552D03*
X23603Y1449735D03*
X35825Y1464845D03*
X22284Y1464612D03*
X35825Y1464845D03*
X21544Y1479662D03*
X33536Y1467485D03*
X21544Y1489648D03*
X32195Y1511279D03*
X33189Y1501373D03*
X32079Y1525641D03*
Y1521641D03*
Y1517641D03*
X35237Y1532096D03*
X31237D03*
X35850Y1556096D03*
X22381Y1554152D03*
X26231Y1554167D03*
X32000Y1644980D03*
X46450Y82984D03*
Y77784D03*
Y75184D03*
Y80384D03*
X48364Y92473D03*
X46450Y85584D03*
X51550Y90615D03*
X37988Y109410D03*
X46240D03*
X45988Y102323D03*
X46240Y116496D03*
X37988Y102323D03*
Y116496D03*
X46931Y130670D03*
X49236Y121658D03*
X37988Y130670D03*
Y123583D03*
X46932Y137756D03*
X52437D03*
X37988D03*
X45984Y163264D03*
X48476Y180812D03*
X37284Y285272D03*
X42690Y451466D03*
X48596Y458466D03*
X48643Y442919D03*
X45643Y472905D03*
X41643Y473419D03*
X49643Y472905D03*
X48390Y485128D03*
X51239Y485138D03*
X40009Y481467D03*
X39801Y504825D03*
X42301D03*
X44801D03*
X45293Y522569D03*
X39742Y517401D03*
X42242D03*
X44742D03*
X46993Y529169D03*
X41408Y531882D03*
X43908D03*
X45293Y525369D03*
X46408Y531882D03*
X38358Y531948D03*
X52869Y537958D03*
X39643Y555194D03*
X36843D03*
X49839Y546830D03*
X46643Y555194D03*
X52869Y540458D03*
X43843Y555194D03*
X39643Y563194D03*
X36843D03*
X39643Y571194D03*
X36843D03*
X46643D03*
X43843D03*
Y563194D03*
X46643D03*
X51000Y581222D03*
X45400D03*
X48200D03*
X51000Y591215D03*
X45400D03*
X48200D03*
X51172Y607762D03*
X48372D03*
X45572D03*
Y610562D03*
X48372D03*
X51172D03*
X37847Y662910D03*
X39549Y682108D03*
X36910D03*
X37804Y671508D03*
X40165Y699082D03*
X37365D03*
X51449Y822718D03*
X49249Y837718D03*
X52349D03*
X46049D03*
X49265Y886660D03*
X52922Y900295D03*
X48429Y916430D03*
X47264Y919649D03*
X47916Y947622D03*
X48683Y1006510D03*
X50541Y1009589D03*
X44999Y1009510D03*
X38823Y1009273D03*
X47197Y1014205D03*
X41197D03*
X44197Y1017759D03*
X38197D03*
X48704Y1017982D03*
X43889Y1062601D03*
X38689D03*
X41289D03*
Y1065101D03*
X38689D03*
X43889D03*
X50366Y1086981D03*
Y1082388D03*
X38200Y1089721D03*
X44365Y1086404D03*
X38216Y1093757D03*
X46166D03*
X39659Y1105100D03*
X42259D03*
X44859D03*
X47559D03*
X48585Y1123867D03*
X47559Y1114800D03*
X44859D03*
X42259D03*
X39659D03*
X48547Y1133688D03*
X51047D03*
X44960Y1190619D03*
X49500Y1199066D03*
X49638Y1203884D03*
X51197Y1218206D03*
X43198Y1254055D03*
X45698D03*
X48198D03*
X45698Y1251555D03*
X43198D03*
X48198D03*
X47621Y1343672D03*
X39225Y1464845D03*
D03*
X40996Y1467703D03*
X44195Y1511279D03*
X48195D03*
X40195D03*
X48089Y1501387D03*
X39095Y1501361D03*
X48079Y1525641D03*
Y1529641D03*
Y1521641D03*
X39237Y1532096D03*
X52048Y1556062D03*
X47074Y1555923D03*
X40951Y1555932D03*
X52000Y1644980D03*
X55638Y53597D03*
X64785Y79993D03*
Y82593D03*
Y85193D03*
Y74793D03*
Y77393D03*
X55921Y95236D03*
X56098Y109410D03*
Y116496D03*
X55964Y103037D03*
X64098Y102323D03*
Y109410D03*
Y116496D03*
X66856Y104249D03*
Y107649D03*
X56098Y123583D03*
Y130670D03*
X64098Y123583D03*
Y130670D03*
Y137756D03*
X66478Y162368D03*
X63878D03*
X69261Y211695D03*
Y208695D03*
X65189Y210713D03*
Y213213D03*
Y208213D03*
X54733Y212978D03*
Y215478D03*
Y207978D03*
Y210478D03*
X65189Y228961D03*
Y231461D03*
Y226461D03*
X68896Y226141D03*
X54733Y231226D03*
Y228726D03*
Y223726D03*
Y226226D03*
X65189Y215713D03*
X69139Y236611D03*
X68841Y248891D03*
X57987Y258880D03*
X60562Y264180D03*
X58062D03*
X66956Y267526D03*
Y270026D03*
X58279Y293796D03*
X66293Y285690D03*
X68793D03*
X66293Y288190D03*
X68793D03*
X60779Y293796D03*
X65759Y437508D03*
X61759D03*
X57759D03*
X54936Y449352D03*
X59522Y448874D03*
X68619Y447269D03*
X68497Y450201D03*
X54167Y457339D03*
X56667D03*
X66224Y473045D03*
X58224D03*
X53643Y472905D03*
X56667Y459839D03*
X54167D03*
Y462339D03*
X56667D03*
X62224Y473045D03*
X66371Y482134D03*
Y484634D03*
X55124Y478625D03*
X53739Y485138D03*
X56239D03*
X56824Y482425D03*
X55124Y475825D03*
X62700Y491214D03*
X59670Y500086D03*
X64550Y504699D03*
X62050D03*
X59550D03*
X66403Y495487D03*
X62700Y493714D03*
X66403Y492987D03*
X68236Y519458D03*
X61752Y516979D03*
X64252D03*
X59252D03*
X60233Y521804D03*
X68202Y522129D03*
X64495Y527449D03*
X60233Y524304D03*
X56540Y531378D03*
Y528878D03*
X61695Y527449D03*
X68202Y527129D03*
Y524629D03*
Y529629D03*
Y537877D03*
X56572Y539731D03*
X68202Y542877D03*
Y545377D03*
Y540377D03*
X56572Y542231D03*
X64130Y541895D03*
Y544895D03*
X61630Y541895D03*
X68188Y548358D03*
X67622Y572842D03*
X64408Y572975D03*
Y582747D03*
X67684Y597232D03*
X62789Y608311D03*
X61854Y617853D03*
Y620653D03*
X53972Y607762D03*
Y610562D03*
X59684Y605443D03*
X63684D03*
X55318Y629362D03*
X53129Y627948D03*
X66530Y625013D03*
X64692Y642184D03*
X55307Y688473D03*
X60849Y826818D03*
X64649D03*
X58949Y821018D03*
X56049Y827218D03*
X68649D03*
X64849Y840418D03*
X60249D03*
X65549Y850718D03*
X66342Y880067D03*
X67316Y865869D03*
X68778Y873821D03*
X64175Y897500D03*
X67461Y912983D03*
X63303Y912835D03*
X68100Y910122D03*
X64632Y901500D03*
X57178Y981386D03*
X53197Y1014205D03*
Y1017759D03*
X69263Y1053152D03*
X55049Y1082343D03*
X55004Y1086937D03*
X62109Y1087656D03*
X58981Y1105100D03*
X56381D03*
X61581D03*
X64281D03*
X61681Y1114800D03*
X56481D03*
X59081D03*
X64381D03*
X57218Y1123867D03*
X55397Y1133688D03*
X57897D03*
X58250Y1220896D03*
X65940Y1209382D03*
X68245Y1212054D03*
X58250Y1227796D03*
Y1230296D03*
Y1237196D03*
Y1234696D03*
Y1223396D03*
X58443Y1272257D03*
X57185Y1480808D03*
X57144Y1491047D03*
X54843Y1501625D03*
X60227Y1514751D03*
X60277Y1528395D03*
X55862Y1541791D03*
X60303Y1534436D03*
X56114Y1556061D03*
X60747Y1555890D03*
X68743Y1583498D03*
X60864Y1583484D03*
X58064D03*
X55264D03*
X60554Y1615152D03*
X74432Y5374D03*
X73745Y24773D03*
Y44773D03*
X73381Y94017D03*
X69381D03*
X73110Y101701D03*
Y98551D03*
X77804Y95879D03*
X76005Y114623D03*
Y111223D03*
X86407Y118335D03*
X76005Y114623D03*
X73509Y110445D03*
X78501D03*
X73509Y115401D03*
X78501D03*
X83911Y117557D03*
X80660Y103783D03*
X76005Y111223D03*
X76660Y103783D03*
X86407Y121735D03*
Y132509D03*
X76005Y128796D03*
Y125396D03*
X86407Y135909D03*
X73509Y129574D03*
Y124618D03*
X78501Y129574D03*
Y124618D03*
X83911Y122513D03*
Y131731D03*
X76005Y125396D03*
Y128796D03*
X83911Y136687D03*
X75194Y141247D03*
X71422Y147540D03*
Y151540D03*
X73578Y165393D03*
Y162793D03*
Y170493D03*
Y167993D03*
X72575Y181426D03*
X75786Y181366D03*
X78581Y181009D03*
X83756Y168697D03*
X75072Y191941D03*
X81572Y184619D03*
X84844Y191941D03*
X75400Y184012D03*
X72783Y184221D03*
X83552Y206760D03*
X71761Y211695D03*
X76819Y213859D03*
Y211359D03*
X80522Y213132D03*
X73158Y229286D03*
X76851Y222212D03*
Y224712D03*
X80522Y215632D03*
X74139Y236611D03*
X71639D03*
X73158Y231786D03*
X71341Y248891D03*
X73841D03*
X76766Y256535D03*
X84766D03*
X80766Y256303D03*
X72256Y267526D03*
X69756D03*
Y270026D03*
X72256D03*
X71593Y285690D03*
Y288190D03*
X75819Y290755D03*
X79819D03*
X71130Y462152D03*
Y459652D03*
Y464652D03*
X73630Y459652D03*
Y462152D03*
Y464652D03*
X71826Y480705D03*
X74326D03*
X69816Y475946D03*
Y478446D03*
X78033Y478586D03*
Y481086D03*
Y476086D03*
Y483586D03*
Y491133D03*
X71461Y498151D03*
Y495151D03*
X73961D03*
X78033Y498633D03*
Y496133D03*
Y493633D03*
X73961Y498151D03*
X75736Y519458D03*
X73236D03*
X70736D03*
X71995Y532749D03*
X74795D03*
X78133Y553297D03*
Y555897D03*
X75688Y548358D03*
X73188D03*
X70688D03*
X78133Y558497D03*
Y563697D03*
Y561097D03*
X72128Y570686D03*
X74923Y570478D03*
X75777Y585507D03*
X71184D03*
X71730Y579475D03*
X75340Y576484D03*
X74983Y573689D03*
X72337Y573303D03*
X71228Y590145D03*
X75822Y590190D03*
X75684Y605443D03*
X83684D03*
X81740Y619758D03*
Y616958D03*
Y614158D03*
X69670Y619513D03*
Y616713D03*
Y613913D03*
X79684Y605443D03*
X81740Y636250D03*
X69670Y633205D03*
Y636005D03*
X81740Y633450D03*
X69670Y638805D03*
X81740Y639050D03*
X79043Y667391D03*
X72314Y680207D03*
Y683407D03*
X82714Y674707D03*
X74414Y681907D03*
X84314Y686107D03*
X72149Y827318D03*
X74349Y824718D03*
Y821918D03*
X72549Y838818D03*
X71928Y873683D03*
X84367Y878286D03*
X76528Y878533D03*
X74028Y889065D03*
X83079Y888515D03*
X72035Y898346D03*
X80339Y897943D03*
X76203Y897910D03*
X76991Y946134D03*
X78167Y949261D03*
X76332Y953421D03*
X84679Y1018368D03*
X70059Y1071656D03*
X69373Y1063389D03*
X70059Y1075656D03*
X70302Y1067656D03*
X70059Y1079656D03*
X77734Y1095676D03*
X70947Y1201565D03*
Y1205835D03*
X71006Y1228684D03*
X71020Y1224323D03*
X76112Y1348187D03*
X79512D03*
X80290Y1345691D03*
Y1350683D03*
X75334Y1345691D03*
Y1350683D03*
X76112Y1348187D03*
X79512D03*
Y1360099D03*
X76112D03*
X80290Y1357603D03*
Y1362595D03*
X75334Y1357603D03*
Y1362595D03*
X76112Y1360099D03*
X79512D03*
X76112Y1384297D03*
Y1372385D03*
X79512D03*
Y1384297D03*
X80290Y1381801D03*
Y1369889D03*
Y1374881D03*
X75334Y1381801D03*
Y1374881D03*
Y1369889D03*
X79512Y1372385D03*
X76112D03*
Y1384297D03*
X79512D03*
X80290Y1386793D03*
X75334D03*
X76005Y1580680D03*
X82433Y1580590D03*
X74291Y1633801D03*
X82291D03*
X78291D03*
X70291D03*
X72000Y1644980D03*
X93334Y3000D03*
X88080Y103603D03*
X88903Y117557D03*
X86407Y132509D03*
Y118335D03*
X88903Y122513D03*
Y131731D03*
X86407Y121735D03*
X87002Y146461D03*
X88903Y136687D03*
X86407Y135909D03*
X92337Y144172D03*
X85904Y152367D03*
X97961Y152562D03*
X87604Y180572D03*
X92287Y180527D03*
X96010Y192421D03*
X92242Y185121D03*
X87604Y185165D03*
X99639Y186629D03*
X89353Y206767D03*
X86853D03*
X91853D03*
X89483Y221708D03*
X86983D03*
X86398Y224421D03*
X88098Y228221D03*
X96333Y221642D03*
X91983Y221708D03*
X93649Y236189D03*
X91149D03*
X88649D03*
X91090Y248765D03*
X88590D03*
X93590D03*
X85796Y279208D03*
X97747Y265897D03*
X100247D03*
X94087Y270695D03*
X91287D03*
X88787D03*
Y268195D03*
X91287D03*
X94087D03*
X94390Y293645D03*
Y290845D03*
Y288345D03*
X91890Y293645D03*
Y290845D03*
Y288345D03*
X98255Y374510D03*
X100120Y377898D03*
X100066Y381976D03*
X90257Y445506D03*
X86788Y581659D03*
X87684Y605443D03*
X93456Y649838D03*
X89432Y668293D03*
X92134D03*
X95973Y655660D03*
X92897Y658359D03*
X95917Y658374D03*
X95539Y664443D03*
X85614Y674707D03*
X87714Y684607D03*
X86289Y822088D03*
X86367Y848086D03*
X91581Y877859D03*
Y874859D03*
X87853Y899220D03*
X100058Y977651D03*
X99836Y980330D03*
X100200Y988800D03*
X91128Y1006487D03*
X99836Y997860D03*
X95836D03*
X85706Y998507D03*
X101025Y1009655D03*
X94586Y1023900D03*
X88287Y1026537D03*
X97609Y1018469D03*
X97247Y1030568D03*
X90450Y1033542D03*
X91752Y1348187D03*
X100592D03*
X88352D03*
X87574Y1345691D03*
Y1350683D03*
X99814D03*
Y1345691D03*
X92530D03*
Y1350683D03*
X88352Y1348187D03*
X91752D03*
X100592D03*
Y1360099D03*
X88352D03*
X91752D03*
X87574Y1362595D03*
Y1357603D03*
X99814Y1362595D03*
Y1357603D03*
X92530Y1362595D03*
Y1357603D03*
X91752Y1360099D03*
X88352D03*
X100592D03*
X91752Y1372385D03*
X88352D03*
X91752Y1384297D03*
X100592D03*
Y1372385D03*
X88352Y1384297D03*
X87574Y1374881D03*
Y1369795D03*
Y1381801D03*
X99814D03*
Y1374881D03*
Y1369889D03*
X92530Y1374881D03*
Y1369795D03*
Y1381801D03*
X100592Y1384297D03*
Y1372385D03*
X91752D03*
X88352D03*
Y1384297D03*
X91752D03*
X100592Y1396583D03*
X88352D03*
X91752D03*
X87574Y1399079D03*
Y1393993D03*
Y1386793D03*
X99814Y1399079D03*
Y1394087D03*
Y1386793D03*
X92530Y1393993D03*
Y1399079D03*
Y1386793D03*
X91752Y1396583D03*
X88352D03*
X100592D03*
X91752Y1408495D03*
X100592D03*
X88352D03*
X87574Y1410991D03*
Y1405999D03*
X99814Y1410991D03*
Y1405999D03*
X92530Y1410991D03*
Y1405999D03*
X91752Y1408495D03*
X88352D03*
X100592D03*
X93496Y1547768D03*
X86291Y1633801D03*
X92000Y1644980D03*
X113334Y3000D03*
X107364Y113394D03*
Y110394D03*
X111582Y102249D03*
X110013Y110784D03*
X115582Y102249D03*
X107364Y116594D03*
X110152Y130898D03*
X117607Y133298D03*
X107364Y119594D03*
X111754Y134579D03*
X106205Y161306D03*
X107540Y172665D03*
Y180665D03*
Y176665D03*
Y168665D03*
X117501Y198883D03*
X115382Y195176D03*
X112882D03*
X117882D03*
X107540Y196665D03*
X107653Y186778D03*
X115242Y203393D03*
X112742D03*
X107572Y200864D03*
Y212864D03*
Y204864D03*
Y216864D03*
Y221864D03*
X112621Y218085D03*
X115421D03*
X103213Y219379D03*
X109329Y252371D03*
Y248371D03*
X112474Y716315D03*
X111993Y710102D03*
X114397Y727974D03*
X113505Y796856D03*
X113601Y881266D03*
X107641Y865224D03*
X102355Y874267D03*
X102947Y877196D03*
X102320Y891043D03*
X103972Y977609D03*
X103836Y980330D03*
X115836Y988813D03*
X107836D03*
X103836Y997860D03*
X111836D03*
X111275Y1008262D03*
X114770Y1009354D03*
X107836Y997860D03*
X115836D03*
X103825Y1009655D03*
X111275Y1011762D03*
X105971Y1025745D03*
X114770Y1016827D03*
Y1029427D03*
X110970Y1030672D03*
X101970D03*
X104970D03*
X107970D03*
X108933Y1102091D03*
X112433D03*
X103124D03*
X102761Y1096233D03*
X112433Y1114691D03*
X103124D03*
X108933D03*
X103124Y1109564D03*
Y1122164D03*
X108971D03*
X108933Y1127291D03*
X112433D03*
X103124D03*
X112433Y1139891D03*
X103124Y1134764D03*
X108971D03*
X103124Y1152491D03*
X108933D03*
X112433D03*
X103124Y1147364D03*
X108933Y1165091D03*
X112433D03*
X103124Y1172564D03*
X108971D03*
X103124Y1159964D03*
X108971D03*
X103184Y1177691D03*
X108933D03*
X112433D03*
X103861Y1182703D03*
X106586Y1204932D03*
X112795Y1223749D03*
X103992Y1348187D03*
X112832D03*
X116232D03*
X104770Y1350683D03*
Y1345691D03*
X112054D03*
Y1350683D03*
X117010Y1345691D03*
Y1350683D03*
X116232Y1348187D03*
X112832D03*
X103992D03*
X116232Y1360099D03*
X103992D03*
X112832D03*
X104770Y1362595D03*
Y1357603D03*
X112054Y1362595D03*
Y1357603D03*
X117010Y1362595D03*
Y1357603D03*
X112832Y1360099D03*
X116232D03*
X103992D03*
X116232Y1384297D03*
X112832Y1372385D03*
X103992Y1384297D03*
X116232Y1372385D03*
X103992D03*
X112832Y1384297D03*
X117010Y1369889D03*
Y1374881D03*
Y1381801D03*
X104770D03*
Y1374881D03*
Y1369889D03*
X112054D03*
Y1374881D03*
Y1381801D03*
X103992Y1372385D03*
Y1384297D03*
X112832D03*
X116232Y1372385D03*
Y1384297D03*
X112832Y1372385D03*
X116232Y1396583D03*
X112832D03*
X103992D03*
X104770Y1399079D03*
Y1394087D03*
Y1386793D03*
X112054Y1399079D03*
Y1394087D03*
Y1386793D03*
X117010Y1394087D03*
Y1399079D03*
Y1386793D03*
X116232Y1396583D03*
X112832D03*
X103992D03*
X116232Y1408495D03*
X112832D03*
X103992D03*
X104770Y1410991D03*
Y1405999D03*
X112054Y1410991D03*
Y1405999D03*
X117010Y1410991D03*
Y1405999D03*
X112832Y1408495D03*
X116232D03*
X103992D03*
X107669Y1456451D03*
Y1465913D03*
X116330Y1465513D03*
X107669Y1461182D03*
X116330Y1460782D03*
X107669Y1481267D03*
X116330Y1480867D03*
X107669Y1476536D03*
X116330Y1476136D03*
Y1470244D03*
X107669Y1471805D03*
X116330Y1491490D03*
Y1485598D03*
X107669Y1487159D03*
Y1496621D03*
X116330Y1496221D03*
X107669Y1491890D03*
X116330Y1506845D03*
Y1500952D03*
X107669Y1502514D03*
X116330Y1511576D03*
X107669Y1511976D03*
Y1507245D03*
X116330Y1516307D03*
X107669Y1563544D03*
X116330Y1563144D03*
X107669Y1558813D03*
Y1568275D03*
X116330Y1567875D03*
X107669Y1578898D03*
X116330Y1578498D03*
Y1572606D03*
X107669Y1574167D03*
Y1583629D03*
X116330Y1583229D03*
X107669Y1594253D03*
X116330Y1593853D03*
Y1587960D03*
X107669Y1589522D03*
Y1609607D03*
X116330Y1609207D03*
X107669Y1598984D03*
X116330Y1598584D03*
Y1603315D03*
X107669Y1604876D03*
X116330Y1613938D03*
Y1618669D03*
X107669Y1614338D03*
X112000Y1644980D03*
X129318Y4469D03*
X130679Y24773D03*
Y44773D03*
X133200Y95111D03*
X130750Y118342D03*
X128350Y116497D03*
X133150D03*
X124606Y106495D03*
X125599Y109172D03*
X122599D03*
X124606Y102495D03*
X119333Y116594D03*
X130750Y121742D03*
Y132515D03*
Y135915D03*
X133150Y123584D03*
X128350D03*
X133150Y130670D03*
X128350D03*
X130750Y132515D03*
Y121742D03*
Y118342D03*
X119333Y119594D03*
X128350Y137757D03*
X133150D03*
X126246Y141228D03*
X124340Y146012D03*
X130750Y135915D03*
X124340Y142862D03*
X129134Y150847D03*
X131947Y199248D03*
X127929Y195176D03*
X130429D03*
X132929D03*
X118930Y206838D03*
X121430D03*
X128010Y210509D03*
X130510D03*
X132283Y206806D03*
X129783D03*
X131947Y201748D03*
X122000Y226320D03*
X119221Y216385D03*
X121934Y216970D03*
Y219470D03*
Y221970D03*
X124961Y228646D03*
X131102Y247292D03*
X130328Y238689D03*
X123892Y236121D03*
X120926Y238589D03*
X128687Y242078D03*
X123918Y232971D03*
X134044Y246874D03*
X123811Y253198D03*
X125125Y362403D03*
X118122Y747565D03*
X119099Y755052D03*
X118467Y796785D03*
X125698Y857515D03*
X122432Y857540D03*
X129666Y857514D03*
X133424Y857303D03*
X122887Y884000D03*
X127067Y891495D03*
X122887Y888000D03*
X131836Y988813D03*
X123836D03*
X124079Y1009354D03*
X119836Y997860D03*
X131836D03*
X127836D03*
X123836D03*
X120579Y1009354D03*
Y1021954D03*
X120617Y1016827D03*
X133870Y1105091D03*
X133579Y1097469D03*
X124880Y1105091D03*
X133870Y1117691D03*
X124880D03*
X133870Y1130291D03*
X124880D03*
X133870Y1142891D03*
Y1155491D03*
X124474Y1142997D03*
X124880Y1155491D03*
X133870Y1168091D03*
X124474Y1168197D03*
X124765Y1180691D03*
X121211Y1215195D03*
X126937Y1209607D03*
X129250Y1227650D03*
X128472Y1348187D03*
X125072D03*
X124294Y1350683D03*
Y1345691D03*
X129250Y1350683D03*
Y1345691D03*
X125072Y1348187D03*
X128472D03*
Y1360099D03*
X125072D03*
X124294Y1362595D03*
Y1357603D03*
X129250D03*
Y1362595D03*
X128472Y1360099D03*
X125072D03*
X128472Y1372385D03*
X125072D03*
X128472Y1384297D03*
X125072D03*
X124294Y1374881D03*
Y1369889D03*
Y1381801D03*
X129250Y1374881D03*
Y1369889D03*
Y1381801D03*
X125072Y1384297D03*
X128472D03*
X125072Y1372385D03*
X128472D03*
Y1396583D03*
X125072D03*
X124294Y1394087D03*
Y1399079D03*
Y1386793D03*
X129250Y1394087D03*
Y1399079D03*
Y1386793D03*
X125072Y1396583D03*
X128472D03*
Y1408495D03*
X125072D03*
X124294Y1405999D03*
Y1410991D03*
X129250Y1405999D03*
Y1410991D03*
X125072Y1408495D03*
X128472D03*
X124992Y1465913D03*
Y1456451D03*
Y1461182D03*
X133653Y1465513D03*
Y1460782D03*
X124992Y1471805D03*
Y1476536D03*
Y1481267D03*
X133653Y1476136D03*
Y1470244D03*
Y1480867D03*
Y1496221D03*
X124992Y1487159D03*
Y1491890D03*
Y1496621D03*
X133653Y1491490D03*
Y1485598D03*
Y1506845D03*
Y1500952D03*
Y1511576D03*
X124992Y1511976D03*
Y1507245D03*
Y1502514D03*
X133653Y1516307D03*
X124992Y1558813D03*
Y1563544D03*
X133653Y1563144D03*
Y1567875D03*
X124992Y1574167D03*
Y1578898D03*
X133653Y1578498D03*
Y1572606D03*
X124992Y1568275D03*
Y1589522D03*
Y1594253D03*
X133653Y1593853D03*
Y1587960D03*
X124992Y1583629D03*
X133653Y1583229D03*
X124992Y1609607D03*
Y1604876D03*
Y1598984D03*
X133653Y1609207D03*
Y1598584D03*
Y1603315D03*
X124992Y1614338D03*
X133653Y1613938D03*
Y1618669D03*
X132000Y1644980D03*
X138000Y53597D03*
X148812Y80384D03*
Y82984D03*
Y75184D03*
Y77784D03*
Y85584D03*
X148350Y95236D03*
X138050Y114655D03*
Y111255D03*
X135650Y109410D03*
X148602D03*
Y116496D03*
X148350Y102323D03*
X140350Y116496D03*
Y109410D03*
Y102323D03*
X135650Y116497D03*
X138050Y111255D03*
Y114655D03*
X137569Y106561D03*
X138050Y125428D03*
Y128828D03*
X148774Y124576D03*
X149827Y130670D03*
X135650Y123583D03*
Y130670D03*
X140350D03*
Y123583D03*
X138050Y128828D03*
Y125428D03*
X149822Y137756D03*
X140350D03*
X135429Y195176D03*
X136882Y213539D03*
X134947Y202048D03*
X138563Y238714D03*
X134563D03*
X138664Y241699D03*
X148692Y391001D03*
Y394401D03*
X146196Y390223D03*
X148692Y391001D03*
X148061Y382600D03*
X148692Y408574D03*
X140690Y401513D03*
Y398113D03*
X148692Y405174D03*
X138290Y412287D03*
X143186Y402291D03*
X138194Y397335D03*
X143186D03*
X146196Y395179D03*
Y404396D03*
Y409352D03*
X138194Y402291D03*
X148692Y394401D03*
Y405174D03*
X140690Y401513D03*
Y398113D03*
X148692Y408574D03*
Y422747D03*
Y419347D03*
X138290Y426460D03*
Y415687D03*
X140786Y416465D03*
Y411509D03*
X135794Y416465D03*
Y411509D03*
X146196Y418569D03*
Y423525D03*
X140786Y425682D03*
X135794D03*
X138290Y412287D03*
X148692Y419347D03*
Y422747D03*
X138290Y415687D03*
Y426460D03*
Y440633D03*
X148692Y436921D03*
X138290Y429860D03*
X148692Y433521D03*
X138290Y444033D03*
X140786Y430638D03*
X135794D03*
X146196Y432743D03*
Y437699D03*
X140786Y439855D03*
X135794D03*
X148692Y433521D03*
X138290Y429860D03*
X148692Y436921D03*
X138290Y440633D03*
X148176Y458711D03*
X140786Y444811D03*
X135794D03*
X136604Y450750D03*
X138290Y444033D03*
X148940Y455921D03*
X145376Y458711D03*
X138290Y472787D03*
Y469387D03*
X148692Y476499D03*
X135794Y468609D03*
X140786D03*
X135794Y473565D03*
X140786D03*
X138290Y469387D03*
Y472787D03*
X147520Y463600D03*
X148692Y479899D03*
Y490673D03*
X138290Y486960D03*
Y483560D03*
X146196Y489895D03*
X135794Y487738D03*
X140786D03*
X146196Y480677D03*
Y475721D03*
X135794Y482782D03*
X140786D03*
X148692Y476499D03*
X138290Y483560D03*
X148692Y490673D03*
X138290Y486960D03*
X148692Y479899D03*
Y494073D03*
X146196Y494851D03*
X148692Y494073D03*
Y520633D03*
Y524033D03*
X138290Y516921D03*
Y513521D03*
X135794Y512743D03*
X140786D03*
X135794Y517699D03*
X140786D03*
X146196Y519855D03*
X148692Y524033D03*
Y520633D03*
X138290Y516921D03*
Y513521D03*
X148692Y534806D03*
Y538206D03*
X138290Y527694D03*
Y531094D03*
X135794Y526916D03*
X140786Y531872D03*
X135794D03*
X146196Y524811D03*
Y538984D03*
Y534028D03*
X140786Y526916D03*
X140703Y536382D03*
X138290Y531094D03*
X148692Y538206D03*
Y534806D03*
X138290Y527694D03*
X142024Y552466D03*
X145670Y597580D03*
X147893Y599588D03*
X147155Y589556D03*
X147094Y592354D03*
X145609Y594668D03*
X147896Y596095D03*
X147925Y603600D03*
X147893Y607588D03*
X147925Y619600D03*
Y623600D03*
X147836Y988813D03*
X139836D03*
Y997860D03*
X147836D03*
X143836D03*
X135836D03*
X145516Y1024954D03*
Y1012354D03*
X136526D03*
Y1024954D03*
X148534Y1046476D03*
X146595Y1053457D03*
X134457Y1180654D03*
X136432Y1224472D03*
X149552Y1348187D03*
X137312D03*
X140712D03*
X141490Y1345691D03*
Y1350683D03*
X136534D03*
Y1345691D03*
X148774Y1350683D03*
Y1345691D03*
X140712Y1348187D03*
X137312D03*
X149552D03*
Y1360099D03*
X140712D03*
X137312D03*
X141490Y1357603D03*
Y1362595D03*
X136534D03*
Y1357603D03*
X148774D03*
Y1362595D03*
X137312Y1360099D03*
X140712D03*
X149552D03*
X140712Y1384297D03*
X137312Y1372385D03*
Y1384297D03*
X140712Y1372385D03*
X149552D03*
Y1384297D03*
D03*
X141490Y1369889D03*
Y1374881D03*
Y1381801D03*
X136534Y1369889D03*
Y1381801D03*
Y1374881D03*
X148774Y1369889D03*
Y1381801D03*
Y1374881D03*
X149552Y1372385D03*
X140712D03*
Y1384297D03*
X137312D03*
Y1372385D03*
X149552Y1396583D03*
X137312D03*
X140712D03*
X141490Y1386793D03*
Y1394087D03*
Y1399079D03*
X136534D03*
Y1394087D03*
Y1386793D03*
X148774Y1394087D03*
Y1399079D03*
Y1386793D03*
X140712Y1396583D03*
X137312D03*
X149552D03*
X137312Y1408495D03*
X149552D03*
X140712D03*
D03*
X137312D03*
X141490Y1405999D03*
Y1410991D03*
X136534D03*
Y1405999D03*
X148774D03*
Y1410991D03*
X149552Y1408495D03*
X142315Y1456451D03*
Y1461182D03*
Y1465913D03*
Y1471805D03*
Y1476536D03*
Y1481267D03*
Y1487159D03*
Y1491890D03*
Y1496621D03*
Y1507245D03*
Y1502514D03*
Y1511976D03*
Y1558813D03*
Y1563544D03*
Y1574167D03*
Y1578898D03*
Y1568275D03*
Y1589522D03*
Y1594253D03*
Y1583629D03*
Y1609607D03*
Y1604876D03*
Y1598984D03*
Y1614338D03*
X158000Y53597D03*
X151366Y92849D03*
X158283Y95236D03*
X158233Y99961D03*
X158460Y116496D03*
X158326Y103037D03*
X158460Y109410D03*
X166460Y116496D03*
Y109410D03*
Y102323D03*
X158460Y130670D03*
Y123583D03*
X166460D03*
Y130670D03*
X155051Y137756D03*
X166460D03*
X166240Y162368D03*
X157095Y210478D03*
Y207978D03*
Y215478D03*
Y212978D03*
Y228726D03*
Y231226D03*
Y226226D03*
Y223726D03*
X160424Y264180D03*
X162924D03*
X160349Y258880D03*
X163141Y293796D03*
X160641D03*
X166528Y312392D03*
X151188Y390223D03*
Y395179D03*
Y404396D03*
Y409352D03*
Y423525D03*
Y418569D03*
Y432743D03*
Y437699D03*
X150703Y453682D03*
X151188Y489895D03*
Y480677D03*
Y475721D03*
Y494851D03*
Y519855D03*
Y538984D03*
Y534028D03*
Y524811D03*
X157375Y555234D03*
X157090Y562003D03*
X152386Y634946D03*
X151836Y997860D03*
X159836D03*
X164028Y1041468D03*
X160733Y1056594D03*
X160547Y1049283D03*
X160627Y1053561D03*
X160807Y1043955D03*
X155513Y1065148D03*
X166188Y1066551D03*
X163191Y1065313D03*
X159228Y1065613D03*
X161792Y1348187D03*
X165192D03*
X152952D03*
X161014Y1345691D03*
Y1350683D03*
X153730Y1345691D03*
Y1350683D03*
X165970Y1345691D03*
Y1350683D03*
X165192Y1348187D03*
X161792D03*
X152952D03*
X165192Y1360099D03*
X161792D03*
X152952D03*
X165192D03*
X161792D03*
X161014Y1362595D03*
Y1357603D03*
X153730Y1362595D03*
Y1357603D03*
X165970Y1362595D03*
Y1357603D03*
X152952Y1360099D03*
X161792Y1372385D03*
X165192Y1384297D03*
Y1372385D03*
X161792Y1384297D03*
X152952Y1372385D03*
Y1384297D03*
D03*
X161014Y1381801D03*
Y1369889D03*
Y1374881D03*
X153730Y1369889D03*
Y1381801D03*
Y1374881D03*
X165970D03*
Y1381801D03*
Y1369889D03*
X152952Y1372385D03*
X161792Y1384297D03*
X165192Y1372385D03*
Y1384297D03*
X161792Y1372385D03*
X165192Y1396583D03*
X152952D03*
X161792D03*
X161014Y1394087D03*
Y1386793D03*
X153730Y1394087D03*
Y1386793D03*
X165970Y1394087D03*
Y1386793D03*
X161014Y1399079D03*
X153730D03*
X165970D03*
X165192Y1396583D03*
X161792D03*
X152952D03*
Y1408495D03*
X165192D03*
X161792D03*
X165192D03*
X161792D03*
X161014Y1410991D03*
Y1405999D03*
X153730D03*
Y1410991D03*
X165970D03*
Y1405999D03*
X152952Y1408495D03*
X159637Y1461182D03*
X150976Y1465513D03*
Y1460782D03*
X159637Y1465913D03*
Y1456451D03*
X150976Y1476136D03*
Y1470244D03*
Y1480867D03*
X159637Y1471805D03*
Y1476536D03*
Y1481267D03*
Y1496621D03*
X150976Y1491490D03*
Y1485598D03*
Y1496221D03*
X159637Y1487159D03*
Y1491890D03*
X150976Y1500952D03*
Y1511576D03*
X159637Y1507245D03*
Y1502514D03*
Y1511976D03*
X150976Y1506845D03*
Y1516307D03*
X159637Y1558813D03*
Y1563544D03*
X150976Y1563144D03*
X159637Y1578898D03*
X150976Y1567875D03*
Y1578498D03*
Y1572606D03*
X159637Y1568275D03*
Y1574167D03*
X150976Y1583229D03*
Y1593853D03*
Y1587960D03*
X159637Y1583629D03*
Y1589522D03*
Y1594253D03*
X150976Y1609207D03*
Y1598584D03*
Y1603315D03*
X159637Y1609607D03*
Y1604876D03*
Y1598984D03*
X150976Y1613938D03*
Y1618669D03*
X159637Y1614338D03*
X152000Y1644980D03*
X176794Y5374D03*
X176107Y24773D03*
Y44773D03*
X167147Y77393D03*
Y74793D03*
Y85193D03*
Y82593D03*
Y79993D03*
X179743Y94017D03*
X175743D03*
X171743D03*
X175472Y101701D03*
Y98551D03*
X178367Y114623D03*
Y111223D03*
X175871Y110445D03*
X180863Y115401D03*
Y110445D03*
X175871Y115401D03*
X178367Y111223D03*
Y114623D03*
X179022Y103783D03*
X169218Y107649D03*
Y104249D03*
X178367Y125396D03*
Y128796D03*
D03*
X180863Y129574D03*
Y124618D03*
X175871Y129574D03*
Y124618D03*
X178367Y125396D03*
X173784Y147540D03*
X177556Y141247D03*
X173784Y151540D03*
X175940Y162793D03*
Y165393D03*
X168840Y162368D03*
X175940Y167993D03*
Y170493D03*
X178148Y181366D03*
X180943Y181009D03*
X174937Y181426D03*
X177434Y191941D03*
X175145Y184221D03*
X177762Y184012D03*
X171623Y211695D03*
X182884Y213132D03*
X179181Y211359D03*
Y213859D03*
X174123Y211695D03*
X167551Y208213D03*
Y213213D03*
Y210713D03*
X171623Y208695D03*
X175520Y229286D03*
X179213Y224712D03*
Y222212D03*
X171258Y226141D03*
X167551Y231461D03*
Y228961D03*
Y226461D03*
Y215713D03*
X182884Y215632D03*
X174001Y236611D03*
X176501D03*
X175520Y231786D03*
X171501Y236611D03*
X176203Y248891D03*
X173703D03*
X171203D03*
X179128Y256535D03*
X174618Y267526D03*
Y270026D03*
X169318Y267526D03*
X172118D03*
Y270026D03*
X169318D03*
X173955Y285690D03*
Y288190D03*
X171155Y285690D03*
X168655Y288190D03*
X171155D03*
X168655Y285690D03*
X182181Y290755D03*
X178181D03*
X170215Y311671D03*
X177369Y389154D03*
Y396240D03*
Y403327D03*
Y410413D03*
Y417500D03*
Y424587D03*
Y431673D03*
Y438760D03*
Y445847D03*
Y467539D03*
Y474626D03*
Y488799D03*
Y481713D03*
Y495886D03*
Y511673D03*
Y518760D03*
Y525847D03*
Y532933D03*
Y540020D03*
Y547106D03*
X175615Y550907D03*
X173115D03*
X175615Y553407D03*
X173115D03*
X174923Y545263D03*
Y541863D03*
X177385Y566929D03*
X171339Y572070D03*
X172686Y569928D03*
X175033Y570962D03*
X174776Y568475D03*
X177099Y569426D03*
X176650Y602197D03*
X177114Y595108D03*
X174032Y1348187D03*
X177432D03*
X173254Y1345691D03*
Y1350683D03*
X178210Y1345691D03*
Y1350683D03*
X177432Y1348187D03*
X174032D03*
X177432Y1360099D03*
X174032D03*
X173254Y1362595D03*
Y1357603D03*
X178210D03*
Y1362595D03*
X174032Y1360099D03*
X177432D03*
Y1384297D03*
X174032Y1372385D03*
Y1384297D03*
X177432Y1372385D03*
Y1384297D03*
X174032D03*
X173254Y1374881D03*
Y1369889D03*
Y1381801D03*
X178210Y1374881D03*
Y1369889D03*
Y1381801D03*
X174032Y1372385D03*
X177432D03*
X174032Y1396583D03*
X177432D03*
X173254Y1394087D03*
Y1386793D03*
X178210Y1394087D03*
Y1386793D03*
X173254Y1399079D03*
X178210D03*
X177432Y1396583D03*
X174032D03*
Y1408495D03*
X177432D03*
X173254Y1405999D03*
Y1410991D03*
X178210Y1405999D03*
Y1410991D03*
X177432Y1408495D03*
X174032D03*
X168299Y1465513D03*
Y1460782D03*
X176960Y1465914D03*
Y1456452D03*
Y1461183D03*
X168299Y1476136D03*
Y1470244D03*
Y1480867D03*
X176960Y1476537D03*
Y1471806D03*
Y1481268D03*
X168299Y1491490D03*
Y1485598D03*
Y1496221D03*
X176960Y1491891D03*
Y1487160D03*
Y1496622D03*
Y1507246D03*
Y1502515D03*
X168299Y1506845D03*
Y1500952D03*
Y1511576D03*
X176960Y1511977D03*
X168299Y1516307D03*
Y1563144D03*
X176960Y1563544D03*
Y1558813D03*
Y1568275D03*
X168299Y1578498D03*
Y1572606D03*
Y1567875D03*
Y1583229D03*
X176960Y1583629D03*
X168299Y1593853D03*
Y1587960D03*
X176960Y1594253D03*
Y1589522D03*
X168299Y1609207D03*
Y1598584D03*
Y1603315D03*
X176960Y1609607D03*
Y1598984D03*
Y1604876D03*
X168299Y1613938D03*
Y1618669D03*
X176960Y1614338D03*
X172000Y1644980D03*
X195697Y3000D03*
X188820Y80140D03*
Y84140D03*
Y76140D03*
X191568Y76587D03*
Y72615D03*
X183752Y94017D03*
X188769Y118335D03*
X186273Y117557D03*
X191265D03*
X183022Y103783D03*
X194189Y103621D03*
X185957Y106186D03*
X197380Y112083D03*
X188769Y132509D03*
Y121735D03*
Y135909D03*
Y118335D03*
Y121735D03*
X186273Y131731D03*
Y122513D03*
X191265D03*
Y131731D03*
X188769Y132509D03*
Y135909D03*
X189364Y146461D03*
X186273Y136687D03*
X191265D03*
X188266Y152367D03*
X194649Y180527D03*
X189966Y180572D03*
X186118Y168697D03*
X198372Y192421D03*
X189966Y185165D03*
X194604Y185121D03*
X183934Y184619D03*
X187206Y191941D03*
X185914Y206760D03*
X189215Y206767D03*
X191715D03*
X194215D03*
X194345Y221708D03*
X198695Y221642D03*
X190460Y228221D03*
Y231021D03*
X191845Y221708D03*
X188760Y224421D03*
X189345Y221708D03*
X191011Y236189D03*
X193511D03*
X196011D03*
X187128Y256535D03*
X190952Y248765D03*
X193452D03*
X195952D03*
X183128Y256303D03*
X188158Y279208D03*
X196449Y268195D03*
X193649D03*
X196449Y270695D03*
X193649D03*
X191149D03*
Y268195D03*
X196752Y293645D03*
Y290845D03*
Y288345D03*
X194252Y293645D03*
Y290845D03*
Y288345D03*
X191988Y389154D03*
X185169D03*
Y396240D03*
X186448Y404911D03*
X190518Y396240D03*
X194603Y422864D03*
X186589Y426299D03*
X185402Y412571D03*
X195295Y414823D03*
X194673Y429832D03*
X194278Y436447D03*
X186900Y445847D03*
X196313Y447953D03*
X185169Y467539D03*
X195480D03*
X185169Y474626D03*
X194222Y472772D03*
X194956Y487711D03*
X195069Y479104D03*
X185430Y480828D03*
X187380Y498834D03*
X195480Y495886D03*
X190829Y516841D03*
X194080Y510565D03*
X185169Y518760D03*
Y511673D03*
Y525847D03*
X185654Y552872D03*
X185776Y550123D03*
X185099Y562443D03*
X186867Y560675D03*
X187408Y572334D03*
X185640Y574102D03*
X194063Y577716D03*
X191125Y602400D03*
Y598400D03*
Y594400D03*
Y606400D03*
Y614400D03*
Y610400D03*
X193723Y656942D03*
X186272Y1348187D03*
X189672D03*
X198512D03*
X185494Y1345597D03*
Y1350683D03*
X190450Y1345597D03*
Y1350683D03*
X197734Y1345691D03*
Y1350683D03*
X189672Y1348187D03*
X186272D03*
X198512D03*
Y1360099D03*
X189672D03*
X186272D03*
X189672D03*
X186272D03*
X185494Y1362595D03*
Y1357603D03*
X197734Y1362595D03*
Y1357603D03*
X190450Y1362595D03*
Y1357603D03*
X198512Y1360099D03*
X189672Y1384297D03*
Y1372385D03*
X186272Y1384297D03*
Y1372385D03*
X198512Y1384297D03*
Y1372385D03*
Y1384297D03*
X185494Y1374881D03*
Y1381801D03*
Y1369889D03*
X197734D03*
Y1381801D03*
Y1374881D03*
X190450Y1369889D03*
Y1374881D03*
Y1381801D03*
X198512Y1372385D03*
X186272Y1384297D03*
X189672D03*
Y1372385D03*
X186272D03*
X198512Y1396583D03*
X189672D03*
X186272D03*
X185494Y1393993D03*
Y1386793D03*
X190450Y1393993D03*
Y1386793D03*
X197734Y1394087D03*
Y1386793D03*
X185494Y1399079D03*
X190450D03*
X197734D03*
X186272Y1396583D03*
X189672D03*
X198512D03*
Y1408495D03*
X189672D03*
X186272D03*
X189672D03*
X186272D03*
X185494Y1410991D03*
Y1405999D03*
X190450Y1410991D03*
Y1405999D03*
X197734D03*
Y1410991D03*
X198512Y1408495D03*
X185622Y1465513D03*
Y1460782D03*
Y1480868D03*
Y1476137D03*
Y1470244D03*
Y1485599D03*
X192000Y1644980D03*
X211262Y60922D03*
X206398Y55513D03*
X203248D03*
X199473Y68581D03*
X208645Y60369D03*
X199486Y80581D03*
X208463Y96472D03*
X203591Y91951D03*
X203616Y88801D03*
X214389Y94374D03*
X206533Y94351D03*
X209530Y86046D03*
X205976Y85731D03*
X202195Y117261D03*
X209726Y113394D03*
Y110394D03*
X213944Y102249D03*
X212375Y110784D03*
X209726Y116594D03*
X201669Y103621D03*
X211969Y133298D03*
X209726Y119594D03*
X214116Y134579D03*
X208567Y161306D03*
X200323Y152562D03*
X205818Y157370D03*
X209902Y172665D03*
Y180665D03*
Y176665D03*
Y168665D03*
X215244Y195176D03*
X202001Y186629D03*
X209902Y192665D03*
X210015Y186778D03*
X209934Y200864D03*
X215104Y203393D03*
X209934Y212864D03*
Y204864D03*
Y216864D03*
Y221864D03*
X205575Y219379D03*
X211691Y252371D03*
Y248371D03*
X200109Y265897D03*
X202609D03*
X212980Y390995D03*
Y394395D03*
X215380Y389153D03*
X210580D03*
X203280Y389154D03*
X212980Y390995D03*
Y408568D03*
X205680Y398082D03*
Y401482D03*
X212980Y405168D03*
X205680Y412255D03*
X215380Y396240D03*
X208080Y403327D03*
X215380Y403326D03*
X210580D03*
X208080Y410413D03*
X210580D03*
X215380D03*
X203280Y396240D03*
Y403327D03*
Y410413D03*
X208080Y396240D03*
X210580D03*
X212980Y405168D03*
Y394395D03*
X205680Y401482D03*
Y398082D03*
X212980Y408568D03*
Y422741D03*
Y419341D03*
X205680Y426428D03*
Y415655D03*
X208080Y417500D03*
X215380Y417499D03*
X210580D03*
X208080Y424586D03*
X210580D03*
X215380D03*
X203280Y417500D03*
Y424586D03*
X212980Y419341D03*
Y422741D03*
X205680Y415655D03*
Y412255D03*
Y426428D03*
X212980Y436915D03*
Y433515D03*
X205680Y429828D03*
Y440602D03*
Y444002D03*
X208080Y431673D03*
Y438760D03*
X210580D03*
X215380D03*
Y431673D03*
X210580D03*
X203280D03*
Y438760D03*
X205680Y440602D03*
Y429828D03*
X212980Y433515D03*
Y436915D03*
X203280Y445847D03*
X208080D03*
X205680Y444002D03*
X212980Y472781D03*
Y469381D03*
X205680Y476468D03*
X215380Y467539D03*
X210580D03*
X203280D03*
X208080Y474626D03*
X210580D03*
X215380D03*
X203280D03*
X212980Y469381D03*
Y472781D03*
Y486954D03*
Y483554D03*
X205680Y479868D03*
Y490641D03*
X215380Y488799D03*
X203280D03*
X208080D03*
X210580D03*
X203280Y481713D03*
X210580Y481712D03*
X208080D03*
X215380D03*
X205680Y490641D03*
Y479868D03*
X212980Y483554D03*
X205680Y476468D03*
X212980Y486954D03*
X205680Y494041D03*
X208080Y495886D03*
X203280D03*
X205680Y494041D03*
X212980Y516915D03*
Y513515D03*
X205680Y524002D03*
Y520602D03*
X215380Y518760D03*
X210580D03*
X208080D03*
X210580Y511673D03*
X215380D03*
X203280D03*
Y518760D03*
X205680Y524002D03*
X212980Y516915D03*
Y513515D03*
X205680Y520602D03*
Y534775D03*
X212980Y527688D03*
X205680Y538175D03*
X212980Y531088D03*
X210580Y532933D03*
X208080D03*
Y540020D03*
Y525846D03*
X210580D03*
X215380D03*
Y532933D03*
X203280Y525847D03*
Y532933D03*
Y540020D03*
X205680Y534775D03*
X212980Y527688D03*
X205680Y538175D03*
X212980Y531088D03*
X203280Y547106D03*
Y554193D03*
X212460Y560500D03*
X203740Y567914D03*
Y565414D03*
Y570414D03*
X204674Y558917D03*
Y561420D03*
X203740Y575414D03*
Y572914D03*
X200495Y577937D03*
X203280Y602205D03*
Y595118D03*
X209429Y625300D03*
X208540Y621591D03*
X205941Y668934D03*
X201115Y695581D03*
X203046Y693716D03*
X201912Y1348187D03*
X202690Y1345597D03*
Y1350683D03*
X201912Y1348187D03*
Y1360099D03*
X202690Y1362595D03*
Y1357603D03*
X201912Y1360099D03*
Y1384297D03*
Y1372385D03*
Y1384297D03*
X202690Y1369889D03*
Y1381801D03*
Y1374881D03*
X201912Y1372385D03*
Y1396583D03*
X202690Y1394087D03*
Y1386793D03*
Y1399079D03*
X201912Y1396583D03*
Y1408495D03*
X202690Y1405999D03*
Y1410991D03*
X201912Y1408495D03*
X213969Y1447453D03*
Y1450853D03*
X211473Y1446675D03*
X213296Y1438215D03*
X213969Y1447453D03*
Y1458453D03*
Y1461853D03*
X211473Y1451631D03*
Y1462631D03*
Y1457675D03*
X213969Y1461853D03*
Y1458453D03*
Y1450853D03*
X215697Y3000D03*
X231681Y4469D03*
X233112Y118342D03*
X224961Y109172D03*
X226968Y106495D03*
X230712Y116497D03*
X217944Y102249D03*
X227961Y109172D03*
X221695Y116594D03*
X226968Y102495D03*
X233112Y121742D03*
Y132515D03*
Y135915D03*
X230712Y123584D03*
Y130670D03*
X219969Y133298D03*
X221695Y119594D03*
X228608Y141228D03*
X230712Y137757D03*
X226702Y146012D03*
Y142862D03*
X231496Y150847D03*
X220244Y195176D03*
X219863Y198883D03*
X217744Y195176D03*
X230291D03*
X223792Y206838D03*
X221292D03*
X217604Y203393D03*
X230372Y210509D03*
X224362Y226320D03*
X224296Y216970D03*
Y219470D03*
Y221970D03*
X221583Y216385D03*
X217783Y218085D03*
X226254Y236121D03*
X223288Y238589D03*
X231049Y242078D03*
X226280Y232971D03*
X226173Y253198D03*
X228760Y316122D03*
X230842Y313888D03*
X228267Y392718D03*
Y408718D03*
Y400718D03*
Y396718D03*
X221375Y455024D03*
X220349Y465622D03*
X225500Y530000D03*
X225000Y540500D03*
X223925Y543925D03*
X224500Y555000D03*
X224000Y547075D03*
X224200Y549800D03*
X224104Y562800D03*
X224040Y558800D03*
X222289Y590895D03*
X222646Y607542D03*
X220255Y629749D03*
X217945Y1423924D03*
X217799Y1433684D03*
X217906Y1430452D03*
Y1427052D03*
X227249Y1447453D03*
Y1450853D03*
X216465Y1446675D03*
X229745D03*
X224753D03*
X222253Y1438483D03*
X219525Y1440028D03*
X216125D03*
X227249Y1447453D03*
Y1461853D03*
Y1458453D03*
X216465Y1451631D03*
Y1462631D03*
Y1457675D03*
X224753Y1462631D03*
X229745Y1457675D03*
X224753D03*
X229745Y1451631D03*
Y1462631D03*
X224753Y1451631D03*
X227249Y1450853D03*
Y1458453D03*
Y1461853D03*
X229260Y1469587D03*
X218171Y1474460D03*
X224176Y1492816D03*
X217614Y1489671D03*
X223235Y1506770D03*
X222908Y1502028D03*
X226957Y1510442D03*
X216342Y1515642D03*
X217519Y1537172D03*
X233042Y24773D03*
Y44773D03*
X240363Y53597D03*
X235562Y95111D03*
X240412Y111255D03*
Y114655D03*
X242712Y116496D03*
Y109410D03*
Y102323D03*
X238012Y116497D03*
X235512D03*
X238012Y109410D03*
X240412Y114655D03*
Y111255D03*
X239931Y106561D03*
X240412Y128828D03*
Y125428D03*
X238012Y123583D03*
Y130670D03*
X235512D03*
X242712D03*
Y123583D03*
X235512Y123584D03*
X233112Y132515D03*
Y121742D03*
X240412Y125428D03*
X233112Y118342D03*
X240412Y128828D03*
X235512Y137757D03*
X242712Y137756D03*
X233112Y135915D03*
X233843Y143762D03*
X232791Y195176D03*
X235291D03*
X234309Y199248D03*
X237791Y195176D03*
X239244Y213539D03*
X237309Y202048D03*
X232872Y210509D03*
X234645Y206806D03*
X232145D03*
X234309Y201748D03*
X232690Y238689D03*
X240925Y238714D03*
X233464Y247292D03*
X236925Y238714D03*
X236406Y246874D03*
X238626Y244297D03*
X236349Y339428D03*
X245362Y542712D03*
X247333Y599506D03*
X247536Y602689D03*
X241967Y616063D03*
X247278Y618288D03*
X243278D03*
X243078Y636486D03*
X240249Y628328D03*
X241084Y638243D03*
X240194Y643113D03*
X246583Y665140D03*
X242102Y656321D03*
X246102D03*
X241850Y678462D03*
X245000D03*
X244267Y696911D03*
X241204Y814841D03*
X237591Y815266D03*
X247600Y848500D03*
X241623Y1348187D03*
X245023D03*
X241623D03*
X245023D03*
X240845Y1345691D03*
Y1350683D03*
X245801Y1345691D03*
Y1350683D03*
X241623Y1360099D03*
X245023D03*
X240845Y1357603D03*
Y1362595D03*
X245801Y1357603D03*
Y1362595D03*
X245023Y1360099D03*
X241623D03*
Y1372385D03*
X245023D03*
Y1384297D03*
X241623D03*
X245023Y1372385D03*
X241623D03*
X240845Y1381801D03*
Y1374881D03*
Y1369889D03*
X245801Y1381801D03*
Y1374881D03*
Y1369889D03*
X241623Y1384297D03*
X245023D03*
X240845Y1386793D03*
X245801D03*
X232675Y1466801D03*
X240466Y1503857D03*
X243268Y1501903D03*
X237700Y1531600D03*
X260363Y53597D03*
X251174Y77784D03*
Y80384D03*
Y82984D03*
Y75184D03*
Y85584D03*
X253728Y92849D03*
X260645Y95236D03*
X250712D03*
X260688Y103037D03*
X250964Y109410D03*
X250712Y102323D03*
X250964Y116496D03*
X260822D03*
Y109410D03*
X251136Y124576D03*
X260822Y130670D03*
Y123583D03*
X252189Y130670D03*
X257413Y137756D03*
X252184D03*
X259457Y210478D03*
Y207978D03*
Y215478D03*
Y212978D03*
Y228726D03*
Y231226D03*
Y226226D03*
Y223726D03*
X262786Y264180D03*
X262711Y258880D03*
X263003Y293796D03*
X257226Y312081D03*
X257993Y307994D03*
X256475Y422088D03*
X255000Y427017D03*
X254692Y431029D03*
X253758Y435029D03*
X254512Y438323D03*
X254678Y449873D03*
X250336Y456386D03*
X254678Y445873D03*
X263301Y444232D03*
X256705Y474424D03*
X264005Y470737D03*
Y467337D03*
X261605Y465492D03*
Y472579D03*
X259105D03*
X254305D03*
X249125Y465874D03*
X264005Y467337D03*
Y470737D03*
X256705Y474424D03*
X264005Y481510D03*
Y484910D03*
X256705Y477824D03*
Y488597D03*
Y491997D03*
X261605Y486752D03*
X254305D03*
X259105Y479666D03*
X261605D03*
X254305D03*
X259105Y486752D03*
X264005Y484910D03*
X256705Y488597D03*
X264005Y481510D03*
X256705Y477824D03*
X254305Y493839D03*
X259105D03*
X256705Y491997D03*
X264005Y514871D03*
Y511471D03*
X256705Y518558D03*
Y521958D03*
X264005Y525644D03*
X261605Y516713D03*
X259105D03*
Y523800D03*
X261605D03*
X254305D03*
Y516713D03*
X261605Y509626D03*
X264005Y514871D03*
X256705Y518558D03*
X264005Y511471D03*
X256705Y521958D03*
Y532731D03*
Y536131D03*
X264005Y529044D03*
X261605Y530886D03*
X259105D03*
Y537973D03*
X254305Y530886D03*
Y537973D03*
X256705Y532731D03*
Y536131D03*
X264005Y525644D03*
Y529044D03*
Y561510D03*
X256705Y571997D03*
Y568597D03*
X264005Y564910D03*
X254305Y566752D03*
X261605Y559665D03*
Y566752D03*
X259105D03*
X264005Y561510D03*
X256705Y571997D03*
Y568597D03*
X264005Y564910D03*
Y575684D03*
Y579084D03*
X256705Y586171D03*
Y582771D03*
X264005Y589857D03*
X261605Y588012D03*
X259105Y588013D03*
X254305Y573839D03*
X261605D03*
X259105D03*
X261605Y580926D03*
X259105D03*
X254305D03*
Y588013D03*
X256705Y586171D03*
X264005Y575684D03*
Y579084D03*
X256705Y582771D03*
Y600344D03*
X264005Y593257D03*
Y604030D03*
X256705Y596944D03*
X259105Y602186D03*
X254305D03*
Y595099D03*
X259105D03*
X261605D03*
Y602185D03*
X264005Y589857D03*
X256705Y600344D03*
X264005Y593257D03*
Y604030D03*
X256705Y596944D03*
X264005Y607430D03*
X256705Y611117D03*
Y614517D03*
X254305Y609272D03*
X259105D03*
X261605D03*
X259105Y616359D03*
X254305D03*
X256705Y611117D03*
Y614517D03*
X264005Y607430D03*
X248984Y638125D03*
X258867Y680499D03*
X248690Y678519D03*
X248090Y691114D03*
X254634Y698241D03*
X248506Y812042D03*
X251802Y824128D03*
X250700Y819900D03*
X254058Y819851D03*
X252100Y836800D03*
X257263Y1348187D03*
X253863D03*
X266103D03*
X253863D03*
X258041Y1350683D03*
Y1345691D03*
X253085Y1350683D03*
Y1345691D03*
X257263Y1348187D03*
X266103Y1360099D03*
X257263D03*
X253863D03*
X258041Y1362595D03*
X253085D03*
X258041Y1357603D03*
X253085D03*
X253863Y1360099D03*
X257263D03*
X253863Y1384297D03*
X257263D03*
Y1372385D03*
X253863D03*
X266103D03*
Y1384297D03*
X253863Y1372385D03*
X258041Y1381801D03*
Y1369795D03*
Y1374881D03*
X253085Y1381801D03*
Y1369795D03*
Y1374881D03*
X257263Y1372385D03*
X253863Y1384297D03*
X257263D03*
X266103Y1396583D03*
X257263D03*
X253863D03*
D03*
X257263D03*
X253085Y1393993D03*
Y1399079D03*
X258041Y1386793D03*
Y1399079D03*
Y1393993D03*
X253085Y1386793D03*
X253863Y1408495D03*
X257263D03*
X266103D03*
X257263D03*
X253863D03*
X258041Y1405999D03*
Y1410991D03*
X253085Y1405999D03*
Y1410991D03*
X248042Y1532900D03*
X279156Y5374D03*
X278469Y24773D03*
Y44773D03*
X269509Y77393D03*
Y74793D03*
Y85193D03*
Y82593D03*
Y79993D03*
X274105Y94017D03*
X278105D03*
X277834Y101701D03*
Y98551D03*
X280729Y114623D03*
Y111223D03*
X268822Y116496D03*
Y109410D03*
X278233Y115401D03*
Y110445D03*
X268822Y102323D03*
X271580Y107649D03*
Y104249D03*
X280729Y128796D03*
Y125396D03*
X268822Y130670D03*
Y123583D03*
X278233Y129574D03*
Y124618D03*
X268822Y137756D03*
X276146Y147540D03*
X279918Y141247D03*
X276146Y151540D03*
X268602Y162368D03*
X271202D03*
X278302Y162793D03*
Y165393D03*
Y167993D03*
Y170493D03*
X277299Y181426D03*
X279796Y191941D03*
X280124Y184012D03*
X277507Y184221D03*
X269913Y210713D03*
X273985Y208695D03*
Y211695D03*
X276485D03*
X269913Y208213D03*
Y213213D03*
Y228961D03*
Y226461D03*
X277882Y229286D03*
X273620Y226141D03*
X269913Y231461D03*
Y215713D03*
X276363Y236611D03*
X278863D03*
X277882Y231786D03*
X273863Y236611D03*
X276065Y248891D03*
X273565D03*
X278565D03*
X265286Y264180D03*
X276980Y267526D03*
Y270026D03*
X271680Y267526D03*
X274480D03*
Y270026D03*
X271680D03*
X276317Y288190D03*
X273517Y285690D03*
X271017Y288190D03*
X273517D03*
X271017Y285690D03*
X265503Y293796D03*
X276317Y285690D03*
X274425Y390500D03*
Y381500D03*
X265011Y410394D03*
X265945Y440098D03*
Y437598D03*
Y435098D03*
Y432598D03*
Y430098D03*
X274949Y442606D03*
X266405Y451319D03*
Y458406D03*
X278827Y444841D03*
X265011Y453881D03*
X280220Y448493D03*
X274866Y446606D03*
X265011Y446595D03*
X274205Y466027D03*
X266405Y465492D03*
X266229Y462264D03*
X274347Y475262D03*
X266405Y472579D03*
X275873Y463479D03*
X276344Y467367D03*
X274347Y489435D03*
Y482666D03*
X266405Y479665D03*
Y486752D03*
Y493839D03*
X274163Y495088D03*
X266405Y523799D03*
Y516713D03*
Y509626D03*
X274205D03*
X274820Y522134D03*
X274898Y514608D03*
X266405Y530886D03*
Y537973D03*
X275463Y529136D03*
X275302Y535677D03*
X266405Y566752D03*
Y559665D03*
X274586Y565574D03*
X274205Y559665D03*
X266405Y580926D03*
Y588012D03*
Y573839D03*
X274233Y574338D03*
X266405Y602185D03*
Y595099D03*
Y609272D03*
Y616358D03*
X274332D03*
X274096Y820725D03*
X274697Y830951D03*
X269700Y853100D03*
X275400Y864400D03*
X269700Y884600D03*
X278400Y890839D03*
X275400Y899400D03*
X269900Y914200D03*
X279261Y926339D03*
X278739Y936439D03*
X270100Y946500D03*
X269503Y1348187D03*
X278343D03*
X281743D03*
X269503D03*
X278343D03*
X266103D03*
X277565Y1350683D03*
Y1345691D03*
X265325D03*
Y1350683D03*
X270281Y1345691D03*
Y1350683D03*
X281743Y1360099D03*
X278343D03*
X269503D03*
X277565Y1362595D03*
X265325D03*
X270281D03*
X277565Y1357603D03*
X265325D03*
X270281D03*
X278343Y1360099D03*
X266103D03*
X269503D03*
Y1372385D03*
Y1384297D03*
X278343Y1372385D03*
Y1384297D03*
X281743Y1372385D03*
Y1384297D03*
X269503Y1372385D03*
X266103D03*
X278343D03*
X277565Y1381801D03*
Y1374881D03*
Y1369889D03*
X265325D03*
Y1374881D03*
Y1381801D03*
X270281Y1369889D03*
Y1374881D03*
Y1381801D03*
X266103Y1384297D03*
X269503D03*
X278343D03*
X281743Y1396583D03*
X278343D03*
X269503D03*
X278343D03*
X269503D03*
X266103D03*
X277565Y1386793D03*
Y1394087D03*
Y1399079D03*
X265325Y1394087D03*
Y1399079D03*
Y1386793D03*
X270281Y1399079D03*
Y1394087D03*
Y1386793D03*
X269503Y1408495D03*
X278343D03*
X281743D03*
X265325Y1405999D03*
Y1410991D03*
X270281Y1405999D03*
Y1410991D03*
X277565Y1405999D03*
Y1410991D03*
X278343Y1408495D03*
X269503D03*
X266103D03*
X272000Y1644980D03*
X294959Y11097D03*
X289797Y36735D03*
X284666Y34068D03*
X286129Y36971D03*
X291182Y84140D03*
Y80140D03*
Y76140D03*
X293930Y76587D03*
Y72615D03*
X282105Y94017D03*
X286114D03*
X291131Y118335D03*
X280729Y111223D03*
X288635Y117557D03*
X283225Y115401D03*
Y110445D03*
X285384Y103783D03*
X296551Y103621D03*
X293627Y117557D03*
X280729Y114623D03*
X281384Y103783D03*
X288319Y106186D03*
X291131Y132509D03*
Y121735D03*
Y135909D03*
X280729Y125396D03*
X291131Y121735D03*
X288635Y131731D03*
Y122513D03*
X283225Y129574D03*
Y124618D03*
X293627Y122513D03*
Y131731D03*
X280729Y128796D03*
X291131Y118335D03*
Y132509D03*
Y135909D03*
X291726Y146461D03*
X293627Y136687D03*
X288635D03*
X295948Y141247D03*
X290628Y152367D03*
X292328Y180572D03*
X280510Y181366D03*
X283305Y181009D03*
X288480Y168697D03*
X292328Y185165D03*
X286296Y184619D03*
X289568Y191941D03*
X288276Y206760D03*
X291577Y206767D03*
X294077D03*
X296577D03*
X285246Y213132D03*
X281543Y211359D03*
Y213859D03*
X281575Y224712D03*
Y222212D03*
X296707Y221708D03*
X292822Y228221D03*
Y231021D03*
X294207Y221708D03*
X291122Y224421D03*
X291707Y221708D03*
X285246Y215632D03*
X293373Y236189D03*
X295873D03*
X281490Y256535D03*
X289490D03*
X293314Y248765D03*
X295814D03*
X285490Y256303D03*
X290520Y279208D03*
X296011Y270695D03*
X293511D03*
Y268195D03*
X296011D03*
X296614Y293645D03*
Y290845D03*
Y288345D03*
X284543Y290755D03*
X280543D03*
X286940Y315039D03*
X284075Y381500D03*
X292520Y384410D03*
X292500Y410394D03*
Y403307D03*
X284295Y430760D03*
X284316Y433570D03*
X284132Y437072D03*
X284173Y439963D03*
X295253Y440869D03*
Y438269D03*
X292453D03*
Y440869D03*
Y435669D03*
Y430469D03*
Y433069D03*
X295253D03*
Y430469D03*
Y435669D03*
X284417Y443180D03*
X284437Y454744D03*
X284379Y452018D03*
X292316Y458406D03*
X293307Y451677D03*
X295807D03*
X293307Y454177D03*
X295807D03*
X284482Y460250D03*
X284516Y465492D03*
X282247Y470136D03*
X292316Y465492D03*
X284516Y472579D03*
X292316D03*
X295011Y460218D03*
Y463618D03*
X284516Y479665D03*
Y486752D03*
X292316Y479665D03*
Y486752D03*
Y493839D03*
X284516D03*
X292316Y523799D03*
Y516713D03*
Y509626D03*
X284516Y516713D03*
Y509626D03*
X292316Y537973D03*
Y530886D03*
X283377Y532756D03*
X283456Y525483D03*
X280976Y537973D03*
X284516Y559665D03*
Y566752D03*
X292316Y559665D03*
Y566752D03*
X284366Y579978D03*
X292316Y573839D03*
Y588012D03*
Y580925D03*
X284516Y573839D03*
X292316Y595099D03*
Y602185D03*
X284580Y608117D03*
X292316Y616358D03*
Y609272D03*
X281980Y953926D03*
X290583Y1348187D03*
X293983D03*
X281743D03*
X282521Y1345691D03*
X289805Y1350683D03*
Y1345691D03*
X294761Y1350683D03*
Y1345691D03*
X282521Y1350683D03*
X293983Y1348187D03*
X290583D03*
X293983Y1360099D03*
X290583D03*
X289805Y1362595D03*
X294761D03*
X282521D03*
X289805Y1357603D03*
X294761D03*
X282521D03*
X281743Y1360099D03*
X293983D03*
X290583D03*
Y1384297D03*
X293983D03*
X290583Y1372385D03*
X293983D03*
D03*
X289805Y1374881D03*
Y1369889D03*
Y1381801D03*
X294761Y1374881D03*
Y1369889D03*
Y1381801D03*
X282521D03*
Y1374881D03*
Y1369889D03*
X281743Y1372385D03*
X290583Y1384297D03*
X293983D03*
X290583Y1372385D03*
X281743Y1384297D03*
X293983Y1396583D03*
X290583D03*
X293983D03*
X289805Y1394087D03*
Y1399079D03*
Y1386793D03*
X294761Y1394087D03*
Y1399079D03*
Y1386793D03*
X282521D03*
Y1399079D03*
Y1394087D03*
X290583Y1396583D03*
X281743D03*
X290583Y1408495D03*
X293983D03*
X289805Y1405999D03*
Y1410991D03*
X294761Y1405999D03*
Y1410991D03*
X282521Y1405999D03*
Y1410991D03*
X281743Y1408495D03*
X293983D03*
X290583D03*
X280897Y1465913D03*
X289558Y1465513D03*
X280897Y1461182D03*
X289558Y1460782D03*
X280897Y1456451D03*
X289558Y1480867D03*
X280897Y1476536D03*
X289558Y1476136D03*
Y1470244D03*
X280897Y1471805D03*
Y1481267D03*
Y1491890D03*
X289558Y1491490D03*
Y1485598D03*
X280897Y1487159D03*
Y1496621D03*
X289558Y1496221D03*
X280897Y1507245D03*
X289558Y1506845D03*
Y1500952D03*
X280897Y1502514D03*
X289558Y1511576D03*
X280897Y1511976D03*
X289558Y1516307D03*
X280897Y1563544D03*
X289558Y1563144D03*
X280897Y1558813D03*
Y1574167D03*
Y1568275D03*
X289558Y1567875D03*
X280897Y1578898D03*
X289558Y1578498D03*
Y1572606D03*
Y1593853D03*
Y1587960D03*
X280897Y1589522D03*
Y1583629D03*
X289558Y1583229D03*
X280897Y1594253D03*
Y1609607D03*
X289558Y1609207D03*
X280897Y1598984D03*
X289558Y1598584D03*
Y1603315D03*
X280897Y1604876D03*
Y1614338D03*
X289558Y1613938D03*
Y1618669D03*
X292000Y1644980D03*
X298059Y3000D03*
X309106Y37543D03*
X312256D03*
X308760Y55513D03*
X305610D03*
X301835Y68581D03*
X310817Y60393D03*
X301848Y80581D03*
X310882Y96613D03*
X305953Y91951D03*
X305978Y88801D03*
X308895Y94351D03*
X308338Y85731D03*
X311892Y86046D03*
X312088Y113394D03*
X304557Y117261D03*
X312088Y116594D03*
X299742Y112083D03*
X304031Y103621D03*
X312088Y119594D03*
X310929Y161306D03*
X302685Y152562D03*
X308180Y157370D03*
X297011Y180527D03*
X312264Y172665D03*
Y180665D03*
Y176665D03*
Y168665D03*
X299759Y190285D03*
X296966Y185121D03*
X304363Y186629D03*
X312264Y196665D03*
Y192665D03*
X312377Y186778D03*
X300814Y192859D03*
X312296Y212864D03*
Y200864D03*
Y204864D03*
Y221864D03*
Y216864D03*
X301057Y221642D03*
X307937Y219379D03*
X298373Y236189D03*
X298314Y248765D03*
X302471Y265897D03*
X304971D03*
X298811Y270695D03*
Y268195D03*
X299114Y290845D03*
Y288345D03*
Y293645D03*
X302966Y324139D03*
X310013Y316731D03*
X301943Y328867D03*
X306812Y342319D03*
X301943Y332017D03*
X308952Y356875D03*
X312316Y356747D03*
X301158Y380307D03*
X309258Y389912D03*
Y393924D03*
Y385912D03*
X301308Y395346D03*
X301393Y400039D03*
X309258Y409924D03*
Y405924D03*
Y401924D03*
X306673Y418838D03*
X298507Y445908D03*
X302457Y445787D03*
X302823Y1348187D03*
X306223D03*
X302823D03*
X306223D03*
X302045Y1345691D03*
Y1350683D03*
X307001D03*
Y1345691D03*
X306223Y1360099D03*
X302823D03*
X302045Y1362595D03*
X307001D03*
X302045Y1357603D03*
X307001D03*
X306223Y1360099D03*
X302823D03*
X306223Y1372385D03*
Y1384297D03*
X302823Y1372385D03*
Y1384297D03*
X306223Y1372385D03*
X302823D03*
X302045Y1374881D03*
Y1381801D03*
Y1369889D03*
X307001Y1374881D03*
Y1369889D03*
Y1381801D03*
X306223Y1384297D03*
X302823D03*
Y1396583D03*
X306223D03*
X302823D03*
X302045Y1386793D03*
Y1394087D03*
Y1399079D03*
X307001Y1386793D03*
Y1399079D03*
Y1394087D03*
X306223Y1396583D03*
X302823Y1408495D03*
X306223D03*
X302823D03*
X306223D03*
X302045Y1405999D03*
Y1410991D03*
X307001Y1405999D03*
Y1410991D03*
X298220Y1465913D03*
Y1456451D03*
Y1461182D03*
X306881Y1465513D03*
Y1460782D03*
Y1470244D03*
Y1480867D03*
X298220Y1471805D03*
Y1476536D03*
Y1481267D03*
X306881Y1476136D03*
X298220Y1487159D03*
Y1491890D03*
Y1496621D03*
X306881Y1491490D03*
Y1485598D03*
Y1496221D03*
X298220Y1507245D03*
Y1502514D03*
X306881Y1506845D03*
Y1500952D03*
Y1511576D03*
X298220Y1511976D03*
X306881Y1516307D03*
X298220Y1558813D03*
Y1563544D03*
X306881Y1563144D03*
X298220Y1568275D03*
X306881Y1567875D03*
X298220Y1574167D03*
Y1578898D03*
X306881Y1578498D03*
Y1572606D03*
X298220Y1583629D03*
X306881Y1583229D03*
X298220Y1589522D03*
Y1594253D03*
X306881Y1593853D03*
Y1587960D03*
Y1598584D03*
Y1603315D03*
X298220Y1609607D03*
Y1604876D03*
Y1598984D03*
X306881Y1609207D03*
X298220Y1614338D03*
X306881Y1613938D03*
Y1618669D03*
X312000Y1644980D03*
X318059Y3000D03*
X313624Y60922D03*
X316751Y94374D03*
X320306Y102249D03*
X327323Y109172D03*
X316306Y102249D03*
X314737Y110784D03*
X324057Y116594D03*
X314854Y130898D03*
X322331Y133298D03*
X324057Y119594D03*
X329064Y146012D03*
X316478Y134579D03*
X329064Y142862D03*
X322225Y198883D03*
X322606Y195176D03*
X320106D03*
X317606D03*
X323654Y206838D03*
X319966Y203393D03*
X317466D03*
X326154Y206838D03*
X317345Y218085D03*
X320145D03*
X323945Y216385D03*
X326658Y216970D03*
Y219470D03*
X326724Y226320D03*
X326658Y221970D03*
X325650Y238589D03*
X328616Y236121D03*
X328642Y232971D03*
X328535Y253198D03*
X314053Y252371D03*
Y248371D03*
X323882Y303839D03*
X327032Y303962D03*
X314855Y311740D03*
X319857Y321649D03*
X315904Y336324D03*
X320483Y353506D03*
X317333Y353470D03*
X315310Y356712D03*
X321549Y445315D03*
Y448115D03*
X320993Y470706D03*
Y467306D03*
X323489Y471484D03*
X318497Y466528D03*
X323489D03*
X318497Y471484D03*
X328899Y473640D03*
X320993Y467306D03*
Y470706D03*
Y484879D03*
Y481479D03*
X328899Y487813D03*
X323489Y480701D03*
X328899Y478596D03*
X318497Y480701D03*
Y485657D03*
X323489D03*
X320993Y481479D03*
Y484879D03*
X328899Y492769D03*
X320993Y514839D03*
Y511439D03*
Y525613D03*
X323489Y515617D03*
X328899Y517774D03*
X318497Y510661D03*
X323489D03*
X318497Y515617D03*
X328899Y522730D03*
X320993Y514839D03*
Y511439D03*
Y529013D03*
X318497Y524835D03*
X328899Y536903D03*
Y531947D03*
X323489Y529791D03*
Y524835D03*
X318497Y529791D03*
X320993Y525613D03*
Y529013D03*
X318660Y539315D03*
X320785Y553287D03*
X320993Y561479D03*
Y564879D03*
X324291Y556775D03*
X328899Y572769D03*
X318497Y565657D03*
Y560701D03*
X328899Y567813D03*
X323489Y565657D03*
Y560701D03*
X320993Y564879D03*
Y561479D03*
Y579052D03*
Y575652D03*
Y589825D03*
X318497Y579830D03*
X323489Y574874D03*
X318497D03*
X323489Y579830D03*
X328899Y581987D03*
X323489Y589047D03*
X318497D03*
X328899Y586943D03*
X320993Y575652D03*
Y579052D03*
Y593225D03*
Y603999D03*
X318497Y594003D03*
X328899Y596160D03*
X323489Y594003D03*
Y603221D03*
X318497D03*
X328899Y601116D03*
X320993Y603999D03*
Y593225D03*
Y589825D03*
Y607399D03*
X328899Y610333D03*
X323489Y608177D03*
X318497D03*
X328899Y615289D03*
X320993Y607399D03*
X321119Y622912D03*
X318463Y1348187D03*
X327303D03*
X315063D03*
X330703D03*
X327303D03*
X315063D03*
X319241Y1350683D03*
Y1345691D03*
X314285D03*
Y1350683D03*
X326525Y1345691D03*
Y1350683D03*
X318463Y1348187D03*
X330703Y1360099D03*
X327303D03*
X315063D03*
X318463D03*
X327303D03*
X319241Y1362595D03*
X314285D03*
X326525D03*
X319241Y1357603D03*
X314285D03*
X326525D03*
X315063Y1360099D03*
X318463D03*
X327303Y1372385D03*
Y1384297D03*
X315063D03*
X318463D03*
X315063Y1372385D03*
X318463D03*
X330703D03*
Y1384297D03*
X315063Y1372385D03*
X318463Y1384297D03*
X315063D03*
X319241Y1374881D03*
Y1381801D03*
Y1369889D03*
X314285Y1374881D03*
Y1381801D03*
Y1369889D03*
X326525Y1381801D03*
Y1369889D03*
Y1374881D03*
X327303Y1372385D03*
X318463D03*
X327303Y1384297D03*
Y1396583D03*
X330703D03*
X315063D03*
X318463D03*
X327303D03*
X315063D03*
X319241Y1386793D03*
Y1399079D03*
Y1394087D03*
X314285Y1386793D03*
Y1399079D03*
Y1394087D03*
X326525Y1399079D03*
Y1394087D03*
Y1386793D03*
X318463Y1396583D03*
X315063Y1408495D03*
X327303D03*
X318463D03*
X330703D03*
X327303D03*
X319241Y1410991D03*
Y1405999D03*
X314285Y1410991D03*
Y1405999D03*
X326525Y1410991D03*
Y1405999D03*
X318463Y1408495D03*
X315063D03*
X315543Y1465913D03*
Y1456451D03*
Y1461182D03*
X324204Y1465513D03*
Y1460782D03*
Y1480867D03*
X315543Y1471805D03*
Y1476536D03*
Y1481267D03*
X324204Y1476136D03*
Y1470244D03*
X315543Y1487159D03*
Y1491890D03*
Y1496621D03*
X324204Y1491490D03*
Y1485598D03*
Y1496221D03*
Y1500952D03*
Y1511576D03*
X315543Y1507245D03*
Y1502514D03*
Y1511976D03*
X324204Y1506845D03*
Y1516307D03*
X315543Y1558813D03*
Y1563544D03*
X324204Y1563144D03*
X315543Y1574167D03*
Y1578898D03*
X324204Y1567875D03*
Y1578498D03*
Y1572606D03*
X315543Y1568275D03*
Y1583629D03*
Y1589522D03*
Y1594253D03*
X324204Y1583229D03*
Y1593853D03*
Y1587960D03*
X315543Y1609607D03*
Y1604876D03*
Y1598984D03*
X324204Y1609207D03*
Y1598584D03*
Y1603315D03*
X315543Y1614338D03*
X324204Y1613938D03*
Y1618669D03*
X334043Y4469D03*
X330905Y11806D03*
Y15806D03*
Y19806D03*
X335404Y24773D03*
X330905Y23806D03*
Y31806D03*
Y27806D03*
X335404Y44773D03*
X342725Y53597D03*
X337924Y95111D03*
X342774Y114655D03*
Y111255D03*
X335474Y118342D03*
X329330Y106495D03*
X345074Y116496D03*
X337874Y116497D03*
X340374D03*
X345074Y109410D03*
Y102323D03*
X340374Y109410D03*
X333074Y116497D03*
X330323Y109172D03*
X342774Y111255D03*
Y114655D03*
X329330Y102495D03*
X342293Y106561D03*
X342774Y128828D03*
Y125428D03*
X335474Y121742D03*
Y132515D03*
Y135915D03*
X337874Y130670D03*
X345074D03*
Y123583D03*
X340374D03*
X337874Y123584D03*
X333074D03*
Y130670D03*
X340374D03*
X335474Y118342D03*
Y132515D03*
X342774Y125428D03*
X335474Y121742D03*
X342774Y128828D03*
X333074Y137757D03*
X337874D03*
X330970Y141228D03*
X345074Y137756D03*
X335474Y135915D03*
X333858Y150847D03*
X335153Y195176D03*
X332653D03*
X336671Y199248D03*
X337653Y195176D03*
X340153D03*
X341606Y213539D03*
X336671Y201748D03*
X334507Y206806D03*
X337007D03*
X335234Y210509D03*
X332734D03*
X339671Y202048D03*
X335052Y238689D03*
X335826Y247292D03*
X343287Y238714D03*
X339287D03*
X333411Y242078D03*
X338768Y246874D03*
X339072Y416888D03*
Y419488D03*
Y422088D03*
X345050Y458334D03*
Y454334D03*
X331395Y474418D03*
X333891Y473640D03*
X331395Y474418D03*
Y477818D03*
Y488591D03*
Y491991D03*
X333891Y487813D03*
Y478596D03*
X331395Y488591D03*
Y477818D03*
X333891Y492769D03*
X331395Y491991D03*
Y521952D03*
Y518552D03*
X333891Y522730D03*
Y517774D03*
X331395Y518552D03*
Y521952D03*
Y532725D03*
Y536125D03*
X333891Y531947D03*
Y536903D03*
X331395Y536125D03*
Y532725D03*
X338358Y554861D03*
X337078Y551381D03*
X335399Y544718D03*
X331395Y571991D03*
Y568591D03*
X333891Y572769D03*
Y567813D03*
X331395Y568591D03*
Y571991D03*
Y582765D03*
Y586165D03*
X333891Y586943D03*
Y581987D03*
X331395Y586165D03*
Y582765D03*
Y596938D03*
Y600338D03*
X333891Y596160D03*
Y601116D03*
X331395Y600338D03*
Y596938D03*
Y614511D03*
Y611111D03*
X333891Y610333D03*
Y615289D03*
X331395Y611111D03*
Y614511D03*
X337564Y1018294D03*
X339251Y1138130D03*
X337629Y1186071D03*
X330800Y1174500D03*
X343121Y1188412D03*
X335502Y1188222D03*
X336901Y1196407D03*
X339540Y1196894D03*
X342943Y1348187D03*
X339543D03*
D03*
X338765Y1350683D03*
Y1345691D03*
X331481D03*
Y1350683D03*
X343721Y1345691D03*
Y1350683D03*
X342943Y1348187D03*
X330703D03*
X342943Y1360099D03*
X339543D03*
X330703D03*
X331481Y1362595D03*
X343721D03*
X338765D03*
X331481Y1357603D03*
X343721D03*
X338765D03*
X342943Y1360099D03*
X339543D03*
Y1384297D03*
X342943D03*
X339543Y1372385D03*
X342943D03*
X339543D03*
X342943D03*
X330703D03*
X331481Y1374881D03*
Y1381801D03*
Y1369889D03*
X343721Y1381801D03*
Y1369889D03*
Y1374881D03*
X338765Y1381801D03*
Y1369889D03*
Y1374881D03*
X342943Y1384297D03*
X339543D03*
X330703D03*
X342943Y1396583D03*
X339543D03*
X330703D03*
X331481Y1399079D03*
Y1394087D03*
Y1386793D03*
X343721D03*
Y1394087D03*
Y1399079D03*
X338765Y1386793D03*
Y1394087D03*
Y1399079D03*
X339543Y1396583D03*
X342943D03*
Y1408495D03*
X339543D03*
X330703D03*
X331481Y1410991D03*
Y1405999D03*
X343721Y1410991D03*
Y1405999D03*
X338765Y1410991D03*
Y1405999D03*
X342943Y1408495D03*
X339543D03*
X341527Y1460782D03*
X332865Y1465913D03*
Y1456451D03*
Y1461182D03*
X341527Y1465513D03*
Y1476136D03*
Y1470244D03*
Y1480867D03*
X332865Y1471805D03*
Y1476536D03*
Y1481267D03*
X341527Y1491490D03*
Y1485598D03*
Y1496221D03*
X332865Y1487159D03*
Y1491890D03*
Y1496621D03*
Y1511976D03*
X341527Y1506845D03*
Y1500952D03*
Y1511576D03*
X332865Y1507245D03*
Y1502514D03*
X341527Y1516307D03*
X332865Y1558813D03*
Y1563544D03*
X341527Y1563144D03*
X332865Y1578898D03*
X341527Y1567875D03*
Y1578498D03*
Y1572606D03*
X332865Y1568275D03*
Y1574167D03*
Y1583629D03*
Y1589522D03*
Y1594253D03*
X341527Y1583229D03*
Y1593853D03*
Y1587960D03*
X332865Y1598984D03*
X341527Y1609207D03*
Y1598584D03*
Y1603315D03*
X332865Y1609607D03*
Y1604876D03*
X341527Y1613938D03*
Y1618669D03*
X332865Y1614338D03*
X332000Y1644980D03*
X353536Y82984D03*
Y80384D03*
Y77784D03*
Y75184D03*
X356090Y92849D03*
X353536Y85584D03*
X353074Y95236D03*
Y102323D03*
X353326Y109410D03*
Y116496D03*
X353498Y124576D03*
X354551Y130670D03*
X359525Y137756D03*
X354546D03*
X359376Y290592D03*
X356423Y301288D03*
X348375Y322284D03*
X348351Y319372D03*
X348806Y315427D03*
X351132Y322202D03*
X348968Y333138D03*
X349120Y336100D03*
X348737Y375386D03*
X354486Y377173D03*
X351136Y372334D03*
X350486Y377173D03*
X358491D03*
X357173Y392183D03*
X347591Y391533D03*
X357218Y396866D03*
X361234Y402867D03*
X357655Y405889D03*
Y408489D03*
X358248Y403300D03*
X354155Y421489D03*
Y418889D03*
Y416289D03*
X350163Y412106D03*
X357655Y413689D03*
Y416289D03*
Y421489D03*
Y418889D03*
Y424089D03*
Y411089D03*
X358042Y442518D03*
Y439718D03*
Y432718D03*
X357655Y426689D03*
X358042Y435518D03*
X347450Y447486D03*
X358754Y450091D03*
X356241Y447001D03*
X359241D03*
X353670Y473571D03*
Y488618D03*
Y491118D03*
Y481071D03*
Y478571D03*
Y476071D03*
X360242Y477053D03*
X357742D03*
X353670Y493618D03*
X359278Y491870D03*
X356778D03*
X353670Y496118D03*
X358096Y867459D03*
X358086Y884616D03*
X357962Y898800D03*
X358024Y912085D03*
X358085Y923327D03*
X355929Y1132042D03*
X351563Y1132410D03*
X346366Y1134729D03*
X361621D03*
X349748D03*
X357748D03*
X353748D03*
X349700Y1148000D03*
X357947Y1159455D03*
X352536Y1160168D03*
X357057Y1179542D03*
X357796Y1188058D03*
X357297Y1192709D03*
X358368Y1201043D03*
X354398D03*
X350402D03*
X346387Y1199256D03*
X360523Y1192282D03*
X349276Y1217228D03*
X351940Y1219895D03*
X355215Y1223170D03*
X360273Y1228226D03*
X358062Y1226016D03*
X355183Y1348187D03*
X351783D03*
D03*
X355183D03*
X355961Y1350683D03*
X351005Y1345597D03*
Y1350683D03*
X355961Y1345597D03*
X355183Y1360099D03*
X351783D03*
X351005Y1362595D03*
X355961D03*
X351005Y1357603D03*
X355961D03*
X355183Y1360099D03*
X351783D03*
X355183Y1384297D03*
Y1372385D03*
X351783Y1384297D03*
Y1372385D03*
D03*
X355183D03*
X351005Y1374881D03*
Y1381801D03*
Y1369889D03*
X355961Y1381801D03*
Y1374881D03*
Y1369889D03*
X355183Y1384297D03*
X351783D03*
X355183Y1396583D03*
X351783D03*
D03*
X351005Y1399079D03*
Y1393993D03*
Y1386793D03*
X355961D03*
Y1399079D03*
Y1393993D03*
X355183Y1396583D03*
Y1408495D03*
X351783D03*
X351005Y1410991D03*
Y1405999D03*
X355961D03*
Y1410991D03*
X351783Y1408495D03*
X355183D03*
X350188Y1491891D03*
Y1487160D03*
Y1496622D03*
Y1507246D03*
Y1502515D03*
Y1511977D03*
X358850Y1511576D03*
Y1506845D03*
Y1516307D03*
X350188Y1563544D03*
Y1558813D03*
Y1568275D03*
Y1578898D03*
Y1574167D03*
Y1583629D03*
Y1594253D03*
Y1589522D03*
Y1604876D03*
Y1609607D03*
Y1598984D03*
Y1614338D03*
X352000Y1644980D03*
X362725Y53597D03*
X371871Y85193D03*
Y82593D03*
Y79993D03*
Y77393D03*
Y74793D03*
X376467Y94017D03*
X363007Y95236D03*
X363050Y103037D03*
X363184Y116496D03*
Y109410D03*
X371184Y116496D03*
Y109410D03*
Y102323D03*
X373942Y104249D03*
Y107649D03*
X363184Y130670D03*
Y123583D03*
X371184Y130670D03*
Y123583D03*
Y137756D03*
X370964Y162368D03*
X373564D03*
X372275Y208213D03*
X376347Y208695D03*
Y211695D03*
X372275Y210713D03*
Y213213D03*
X361819Y207978D03*
Y212978D03*
Y215478D03*
Y210478D03*
X372275Y226461D03*
X375982Y226141D03*
X361819Y231226D03*
Y228726D03*
Y223726D03*
Y226226D03*
X372275Y228961D03*
Y231461D03*
Y215713D03*
X376225Y236611D03*
X375927Y248891D03*
X367648Y264180D03*
X365148D03*
X365073Y258880D03*
X374042Y270026D03*
X376842D03*
X374042Y267526D03*
X376842D03*
X365365Y293796D03*
X367865D03*
X373379Y288190D03*
X375879Y285690D03*
X373379D03*
X375879Y288190D03*
X368057Y354184D03*
X371417Y353820D03*
X365559Y354300D03*
X364933Y374232D03*
X373264Y370010D03*
X377237Y371060D03*
X366526Y377173D03*
X370486D03*
X361767Y392228D03*
X362486Y385123D03*
X376992Y395248D03*
X364551Y409032D03*
X361811Y396866D03*
X368587Y401066D03*
X367919Y439318D03*
X375919Y442118D03*
Y439318D03*
X367919Y442118D03*
X375919Y449118D03*
Y446318D03*
X364954Y450091D03*
X367919Y449118D03*
Y446318D03*
X376099Y458309D03*
Y454309D03*
X367564Y452740D03*
X361754Y450091D03*
X376099Y462309D03*
X369282Y468088D03*
Y465288D03*
X366443Y472189D03*
X373546Y470001D03*
X376046D03*
X361754Y462060D03*
X365332Y490070D03*
Y487570D03*
X373971Y489036D03*
X371832Y485580D03*
X374332D03*
X376832D03*
X366420Y479986D03*
Y477486D03*
X363686Y478668D03*
Y476168D03*
X361887Y493758D03*
Y496258D03*
X376207Y492836D03*
Y495636D03*
X373504Y517954D03*
X376881Y518564D03*
X363015Y710365D03*
X365887Y710329D03*
X372400Y746300D03*
X372300Y750000D03*
X373500Y767300D03*
X376300D03*
X370415Y766108D03*
X377020Y782535D03*
X373101Y779608D03*
X376300Y779800D03*
X365850Y773950D03*
X371436Y791188D03*
X368491Y815092D03*
X362042Y814772D03*
X368273Y928100D03*
X368067Y925136D03*
X375040Y932959D03*
X371424Y937185D03*
X367944Y946082D03*
X368626Y931346D03*
X368964Y937738D03*
X372858Y935136D03*
X366761Y934550D03*
X370214Y959812D03*
X363893Y946863D03*
X370214Y947812D03*
X370101Y953699D03*
X370214Y967812D03*
Y963812D03*
Y971812D03*
X372501Y1123695D03*
X365748Y1134325D03*
X368657Y1146937D03*
Y1150087D03*
X366133Y1162817D03*
Y1170767D03*
X368661Y1182649D03*
X368917Y1195419D03*
X362402Y1201039D03*
X366402Y1200969D03*
X365029Y1214158D03*
X362735Y1211864D03*
X369839Y1218940D03*
X366521Y1208993D03*
X367816Y1310586D03*
Y1315542D03*
X370202Y1314764D03*
Y1311364D03*
X367423Y1348187D03*
X364023D03*
X363245Y1345691D03*
Y1350683D03*
X368201Y1345691D03*
Y1350683D03*
X364023Y1348187D03*
X367423D03*
Y1360099D03*
X364023D03*
X363245Y1362595D03*
X368201D03*
X363245Y1357603D03*
X368201D03*
X367423Y1360099D03*
X364023D03*
X367423Y1372385D03*
Y1384297D03*
X364023D03*
Y1372385D03*
D03*
X363245Y1369889D03*
Y1381801D03*
Y1374881D03*
X368201D03*
Y1381801D03*
Y1369889D03*
X367423Y1384297D03*
X364023D03*
X367423Y1372385D03*
X364023Y1396583D03*
X367423D03*
X363245Y1399079D03*
Y1394087D03*
Y1386793D03*
X368201D03*
Y1394087D03*
Y1399079D03*
X364023Y1396583D03*
X367423D03*
Y1408495D03*
X364023D03*
X363245Y1405999D03*
Y1410991D03*
X368201D03*
Y1405999D03*
X364023Y1408495D03*
X367423D03*
X372000Y1644980D03*
X388059Y3000D03*
X381518Y5374D03*
X388487Y24069D03*
X380831Y24773D03*
X383612Y30618D03*
Y33768D03*
X388612Y31168D03*
X380831Y44773D03*
X393544Y76140D03*
Y84140D03*
Y80140D03*
X384467Y94017D03*
X388476D03*
X380467D03*
X380196Y101701D03*
Y98551D03*
X383091Y114623D03*
Y111223D03*
X393493Y118335D03*
X383091Y111223D03*
X390997Y117557D03*
X385587Y115401D03*
X380595D03*
X385587Y110445D03*
X380595D03*
X387746Y103783D03*
X383091Y114623D03*
X383746Y103783D03*
X390681Y106186D03*
X393493Y121735D03*
Y132509D03*
X383091Y128796D03*
Y125396D03*
X393493Y135909D03*
Y118335D03*
X383091Y125396D03*
Y128796D03*
X390997Y131731D03*
Y122513D03*
X385587Y129574D03*
X380595D03*
X385587Y124618D03*
X380595D03*
X393493Y132509D03*
Y121735D03*
Y135909D03*
X390997Y136687D03*
X380664Y165393D03*
Y162793D03*
Y167993D03*
Y170493D03*
X382872Y181366D03*
X379661Y181426D03*
X385667Y181009D03*
X390842Y168697D03*
X382158Y191941D03*
X388658Y184619D03*
X391930Y191941D03*
X382486Y184012D03*
X379869Y184221D03*
X390638Y206760D03*
X393939Y206767D03*
X383905Y211359D03*
X387608Y213132D03*
X378847Y211695D03*
X383905Y213859D03*
X380244Y229286D03*
X383937Y222212D03*
Y224712D03*
X394069Y221708D03*
X393484Y224421D03*
X387608Y215632D03*
X381225Y236611D03*
X378725D03*
X380244Y231786D03*
X378427Y248891D03*
X380927D03*
X391852Y256535D03*
X383852D03*
X387852Y256303D03*
X392882Y279208D03*
X379342Y270026D03*
Y267526D03*
X378679Y285690D03*
Y288190D03*
X386905Y290755D03*
X382905D03*
X392387Y337599D03*
Y342555D03*
X389237Y371070D03*
X385237Y370976D03*
X391737Y377581D03*
X391940Y383817D03*
Y388817D03*
Y386317D03*
X392444Y401949D03*
X385864Y398278D03*
X383364D03*
X378927Y409539D03*
X381927D03*
Y407039D03*
X381591Y401981D03*
X384091D03*
X378210Y424067D03*
X380710D03*
X385710D03*
X383210D03*
X378445Y413611D03*
X380945D03*
X385945D03*
X383445D03*
X385584Y438293D03*
Y441093D03*
Y450041D03*
Y452841D03*
Y455641D03*
Y443893D03*
X393837Y466409D03*
X393662Y470382D03*
X393823Y487382D03*
X393652Y482382D03*
X393746Y478382D03*
X387141Y484882D03*
X388593Y664232D03*
X386350Y693559D03*
X391478Y690675D03*
X391470Y732865D03*
X380963Y731000D03*
X379800Y778000D03*
Y769200D03*
X392415Y792725D03*
X389015D03*
X387692Y790056D03*
X393547D03*
X380607Y786932D03*
X392415Y792725D03*
X389015D03*
X387958Y813700D03*
X381631Y814147D03*
X384666Y814103D03*
X383391Y804000D03*
X386589Y864408D03*
X383462Y860535D03*
X386614Y868286D03*
X382675Y870151D03*
X391614Y938651D03*
Y930676D03*
X385512Y955356D03*
X390150Y955312D03*
Y959905D03*
X385467Y959950D03*
X378119Y953696D03*
X392910Y948536D03*
X393998Y971780D03*
X381377Y1003008D03*
X381045Y1009444D03*
X378790Y1001083D03*
X380280Y1006071D03*
X378410Y1131573D03*
X380261Y1129692D03*
X387587Y1296675D03*
X387644Y1302089D03*
X385091Y1297453D03*
Y1300853D03*
X391284Y1307238D03*
X386415Y1321645D03*
X391691Y1326715D03*
X389458Y1365466D03*
X389188Y1369033D03*
X391757Y1383480D03*
X388600Y1395500D03*
X391852Y1389931D03*
X389985Y1405762D03*
X393094Y1423600D03*
X393951Y1447455D03*
X394000Y1508100D03*
X381900Y1544800D03*
X389700Y1536900D03*
X382017Y1555700D03*
Y1547700D03*
Y1551700D03*
Y1559700D03*
X392000Y1644980D03*
X408059Y3000D03*
X408680Y37530D03*
X396680Y37543D03*
X400714Y45448D03*
X404686D03*
X408493Y117577D03*
X395989Y117557D03*
X398913Y103621D03*
X402104Y112083D03*
X406393Y103621D03*
X395989Y131731D03*
Y122513D03*
Y136687D03*
X399373Y180527D03*
X394690Y180572D03*
X403096Y192421D03*
X394690Y185165D03*
X399328Y185121D03*
X406725Y186629D03*
X395942Y192300D03*
X398939Y206767D03*
X396439D03*
X395184Y228221D03*
X399069Y221708D03*
X396569D03*
X403419Y221642D03*
X395184Y231021D03*
X410299Y219379D03*
X400735Y236189D03*
X398235D03*
X395735D03*
X400676Y248765D03*
X398176D03*
X395676D03*
X407333Y265897D03*
X404833D03*
X401173Y268195D03*
Y270695D03*
X398373Y268195D03*
X395873D03*
Y270695D03*
X398373D03*
X398976Y293645D03*
X401476D03*
Y288345D03*
Y290845D03*
X398976Y288345D03*
Y290845D03*
X409484Y314921D03*
X405843Y315158D03*
X403343D03*
X398951Y333711D03*
X397374Y344439D03*
X394883Y341777D03*
Y338377D03*
X400993Y331589D03*
Y335589D03*
X407493Y354142D03*
X400728Y353152D03*
X394237Y370899D03*
X406421Y387151D03*
Y382151D03*
Y384651D03*
X398453Y387702D03*
X401253D03*
X394653Y389402D03*
X396373Y409904D03*
X409268Y408240D03*
X406843Y399161D03*
Y401661D03*
Y396661D03*
X394944Y398949D03*
X399518Y402642D03*
X402018D03*
X396633Y423944D03*
X409386Y420393D03*
X396693Y413611D03*
X399193D03*
X401693D03*
X401633Y423944D03*
X399133D03*
X395577Y438293D03*
Y441093D03*
Y455641D03*
Y450041D03*
Y452841D03*
Y443893D03*
X397315Y471560D03*
Y479560D03*
Y475560D03*
X405603Y668060D03*
X408103D03*
X403103D03*
X400603D03*
Y678060D03*
X405603D03*
X408103D03*
X403103D03*
X409284Y741316D03*
X406200Y741300D03*
X400900Y755400D03*
X400914Y762675D03*
X408300Y755487D03*
X400900Y770100D03*
X407965Y770196D03*
X408400Y795200D03*
Y792200D03*
X406600Y789000D03*
X397223Y796792D03*
X400023D03*
X397900Y789000D03*
X407000Y784700D03*
X402376Y842677D03*
X399876D03*
X402376Y850677D03*
X399876D03*
X396306Y864409D03*
X406967Y878764D03*
X406415Y874840D03*
X407193Y883566D03*
X401121Y929686D03*
X409121D03*
X401121Y936686D03*
X409121Y939186D03*
X401121D03*
X409121Y936686D03*
X401121Y932186D03*
X409121D03*
X396182Y955858D03*
X402682Y948536D03*
X402815Y951750D03*
X404971Y956256D03*
X402354Y956465D03*
X401968Y959111D03*
X399173Y959468D03*
X404176Y977684D03*
Y975084D03*
Y969984D03*
Y972484D03*
X406954Y982970D03*
X409554D03*
X404354D03*
X407547Y1058097D03*
X410047D03*
X405047D03*
X407547Y1060697D03*
X410047D03*
X405047D03*
X399285Y1081599D03*
X408989Y1082501D03*
X409015Y1087705D03*
Y1085205D03*
X408847Y1090956D03*
X398915Y1097278D03*
X396415D03*
X408847Y1093956D03*
X406895Y1107997D03*
X402695D03*
X409231Y1123101D03*
X402695Y1110897D03*
X407780Y1113648D03*
X409231Y1118801D03*
X406995Y1110597D03*
X404895Y1112397D03*
X404795Y1109397D03*
X402695Y1113797D03*
X406105Y1139435D03*
X410131Y1129301D03*
X407631D03*
X409231Y1125801D03*
X406105Y1131935D03*
Y1134435D03*
Y1136935D03*
Y1141935D03*
Y1146935D03*
Y1144435D03*
X403263Y1152684D03*
X408961Y1162384D03*
Y1164884D03*
Y1167384D03*
Y1169884D03*
Y1172384D03*
X403263Y1160834D03*
X408961Y1174884D03*
X406319Y1186709D03*
Y1184209D03*
Y1181709D03*
Y1179209D03*
Y1204405D03*
X404004Y1198321D03*
Y1200821D03*
Y1192621D03*
Y1190121D03*
X406319Y1206905D03*
Y1211905D03*
Y1209405D03*
X397063Y1221428D03*
X401063D03*
X405063D03*
X409063D03*
X397063Y1233428D03*
Y1229428D03*
Y1225428D03*
X401063Y1237428D03*
Y1229428D03*
Y1225428D03*
X405063Y1237428D03*
Y1233428D03*
Y1229428D03*
X409063Y1237428D03*
Y1229428D03*
Y1225428D03*
X401063Y1241428D03*
X405063Y1245428D03*
Y1241428D03*
X409063Y1245428D03*
Y1241428D03*
X397695Y1287071D03*
X404324Y1275889D03*
X399716Y1295198D03*
X407767Y1292198D03*
X403678Y1295426D03*
X398584Y1313443D03*
X401011Y1307258D03*
X402967Y1319815D03*
X409220Y1315516D03*
X404583Y1316131D03*
X408523Y1332967D03*
X404657D03*
X404921Y1321819D03*
X408787Y1321795D03*
X408937Y1351568D03*
X395959Y1352153D03*
X403981Y1351568D03*
X399959Y1352153D03*
X408159Y1349072D03*
X404759D03*
X403029Y1379716D03*
X403111Y1384920D03*
X408212Y1379695D03*
X394657Y1377875D03*
X403111Y1390103D03*
X408212Y1390083D03*
X395112Y1395690D03*
X398340Y1399779D03*
X395770Y1389817D03*
X410152Y1410928D03*
X398112Y1403741D03*
X410172Y1402446D03*
X402489Y1417275D03*
X405889D03*
X401711Y1419771D03*
X406667D03*
X395894Y1423600D03*
X401990Y1446807D03*
X399731Y1442755D03*
X407970Y1449751D03*
X404500Y1452500D03*
X395888Y1450022D03*
X395199Y1482223D03*
X407469Y1495035D03*
X407854Y1492118D03*
X395380Y1485778D03*
X406377Y1499142D03*
X397245Y1511640D03*
X404053Y1513673D03*
X397266Y1514647D03*
X398747Y1500959D03*
X395370Y1501022D03*
X397220Y1521207D03*
X397266Y1518047D03*
X408964Y1531149D03*
X400911Y1537902D03*
X407048D03*
X400911Y1544424D03*
X394391Y1537786D03*
Y1535286D03*
X407048Y1549936D03*
X400911D03*
X409461Y1569560D03*
X405461D03*
X397461D03*
X401461D03*
X420050Y33425D03*
X416900Y33400D03*
X422473Y22627D03*
X422378Y26534D03*
X426147Y147540D03*
Y151540D03*
X414626Y180665D03*
Y172665D03*
Y176665D03*
Y168665D03*
Y196665D03*
Y192665D03*
X414658Y212864D03*
Y200864D03*
Y204864D03*
Y216864D03*
Y221864D03*
X422873Y309966D03*
X419955Y306966D03*
X414999D03*
X423651Y307470D03*
X419177Y304470D03*
X415777D03*
X411984Y314921D03*
X415129Y325181D03*
X421231Y338523D03*
Y331255D03*
X412671Y333418D03*
X412812Y330617D03*
X421231Y345776D03*
X413432Y346797D03*
X426138Y355079D03*
X416318Y367903D03*
X424479Y367859D03*
X412318Y367903D03*
X420422Y367859D03*
X418997Y382210D03*
Y384710D03*
Y387210D03*
X418876Y401661D03*
Y396661D03*
X411768Y408240D03*
X414268D03*
X418876Y399161D03*
X411847Y424240D03*
X414386Y420393D03*
X411886D03*
X422215Y424939D03*
X411847Y426740D03*
X422215Y427439D03*
X414924Y435321D03*
Y438121D03*
X412124Y435321D03*
Y438121D03*
X414924Y440921D03*
X412124D03*
X415453Y455039D03*
X414924Y443721D03*
X412124D03*
X418754Y468607D03*
X411754Y474513D03*
X415433Y459170D03*
X425673Y461607D03*
X424876Y471334D03*
X414275Y492469D03*
X424731Y492704D03*
X414275Y497469D03*
Y499969D03*
X424731Y497704D03*
Y495204D03*
Y500204D03*
X414275Y494969D03*
X424731Y513452D03*
Y515952D03*
X414275Y508217D03*
Y510717D03*
Y515717D03*
Y513217D03*
X424731Y510952D03*
X419040Y533690D03*
Y528390D03*
Y530990D03*
Y536290D03*
Y538890D03*
X419340Y549990D03*
X419140Y547390D03*
Y544790D03*
X419340Y552590D03*
Y555190D03*
X423266Y631438D03*
X420266D03*
X417666D03*
X420266Y637038D03*
Y634238D03*
X417666Y637038D03*
Y634238D03*
X423266Y637038D03*
Y634238D03*
X423963Y625778D03*
X418226Y653288D03*
X423266Y642638D03*
X420266D03*
X417666D03*
X423266Y639838D03*
X420266D03*
X418226Y646480D03*
Y648980D03*
X417666Y639838D03*
X418226Y655788D03*
X410603Y668060D03*
Y678060D03*
X426607Y712360D03*
Y709760D03*
X415700Y755400D03*
X415696Y762466D03*
X415700Y770200D03*
X423700Y795500D03*
X426300Y797400D03*
X421200Y786400D03*
X411267Y829193D03*
Y831693D03*
X416267D03*
X413767D03*
Y829193D03*
X416267D03*
X424649Y842644D03*
X422149D03*
Y850644D03*
X424649D03*
X422149Y858644D03*
X424649D03*
X425759Y869921D03*
Y872721D03*
Y875521D03*
Y867121D03*
X422379Y867229D03*
X425759Y878321D03*
X411214Y892109D03*
X417121Y929686D03*
X425121D03*
Y936686D03*
Y939186D03*
X417121Y936686D03*
Y939186D03*
Y932186D03*
X425121D03*
X411960Y962261D03*
X414560D03*
X417160D03*
X411276Y978109D03*
X416476D03*
X413876D03*
X417677Y1052215D03*
X415047Y1058097D03*
X412547D03*
X415047Y1060697D03*
X412547D03*
X411989Y1082501D03*
X412015Y1085205D03*
X414989Y1082501D03*
X415015Y1085205D03*
X412015Y1088205D03*
X412297Y1091227D03*
X425175Y1098767D03*
X417171Y1098887D03*
X425060Y1101917D03*
X420782Y1105552D03*
X424995Y1106897D03*
X416988Y1104792D03*
X420661Y1119422D03*
X423141Y1113822D03*
X419731Y1123101D03*
X417231D03*
X423141Y1119422D03*
X418181Y1113822D03*
Y1119422D03*
X420661Y1113822D03*
X414580Y1113648D03*
X412080D03*
X422631Y1125801D03*
X425131Y1129301D03*
X422631D03*
X420131D03*
X417631D03*
X415131D03*
X412631D03*
X420131Y1125801D03*
X417631D03*
X425131D03*
X422495Y1152713D03*
Y1155213D03*
X412095Y1152713D03*
Y1155213D03*
X411461Y1162384D03*
Y1164884D03*
Y1167384D03*
Y1169884D03*
Y1172384D03*
X420619Y1179421D03*
Y1181921D03*
Y1184421D03*
Y1186921D03*
X411461Y1174884D03*
X422934Y1200821D03*
Y1198321D03*
X420619Y1204617D03*
X417469Y1200821D03*
Y1198321D03*
X422934Y1192621D03*
Y1190121D03*
X417469Y1192621D03*
Y1190121D03*
X420619Y1207117D03*
Y1209617D03*
Y1212117D03*
X413063Y1221428D03*
X417063D03*
X421063D03*
X425063D03*
X413063Y1237428D03*
Y1233428D03*
Y1229428D03*
Y1225428D03*
X417063Y1237428D03*
Y1233428D03*
Y1229428D03*
X421063Y1237428D03*
Y1233428D03*
Y1229428D03*
Y1225428D03*
X425063Y1233428D03*
Y1229428D03*
Y1225428D03*
X413063Y1245428D03*
Y1241428D03*
X417063Y1245428D03*
Y1241428D03*
X421063Y1245428D03*
Y1241428D03*
X425063Y1245428D03*
Y1241428D03*
X425702Y1257160D03*
X422702Y1260160D03*
Y1257160D03*
X425702Y1260160D03*
X419702Y1257160D03*
Y1260160D03*
X411174Y1282776D03*
X418537Y1300197D03*
X423741Y1300115D03*
X413354Y1300197D03*
X425582Y1291743D03*
X413526Y1288938D03*
X419977Y1288843D03*
X413640Y1292856D03*
X423762Y1305298D03*
X413374D03*
X418558Y1310523D03*
X413395Y1310481D03*
X423721Y1310523D03*
X419545Y1317722D03*
X413127Y1318011D03*
X414280Y1362561D03*
X425283Y1364023D03*
X417305Y1359169D03*
X425855Y1360495D03*
X425912Y1357141D03*
X413437Y1379736D03*
Y1384899D03*
X425283Y1373958D03*
X416029Y1371572D03*
X420636Y1383912D03*
X418610Y1371590D03*
X413395Y1390062D03*
X423400Y1394500D03*
X418430Y1394237D03*
X422729Y1400490D03*
X420925Y1390330D03*
X419045Y1398874D03*
X421300Y1415400D03*
X419100Y1402200D03*
X421200Y1417900D03*
X411000Y1463500D03*
Y1460500D03*
Y1457500D03*
Y1454500D03*
Y1451000D03*
X411147Y1474993D03*
X419818Y1474945D03*
X413934Y1477101D03*
X417334D03*
X415241Y1492990D03*
X415202Y1496118D03*
X415095Y1502750D03*
X415202Y1499518D03*
X411353Y1519440D03*
X419467Y1519706D03*
X420279Y1525978D03*
X410626Y1525991D03*
X417153Y1516886D03*
X413753D03*
X413012Y1537902D03*
Y1544098D03*
X426196Y1534087D03*
X419619Y1539978D03*
X413012Y1549936D03*
X421616Y1549885D03*
X418151Y1552470D03*
X413461Y1569560D03*
X417461Y1569584D03*
X412000Y1644980D03*
X428059Y3000D03*
X441727Y146461D03*
X429919Y141247D03*
X440629Y152367D03*
X435703Y306966D03*
X430747D03*
X427829Y309966D03*
X431525Y304470D03*
X434925D03*
X427051Y307470D03*
X441296Y325061D03*
X427713Y321965D03*
X430361Y323187D03*
X428459Y331255D03*
X435793D03*
X428500Y345776D03*
X435793Y345738D03*
X430439Y358115D03*
X428420Y353578D03*
X435886Y353867D03*
X435702Y367813D03*
X430746D03*
X431524Y370309D03*
X434924D03*
X428637Y408104D03*
X431437D03*
X434237D03*
X428354Y420375D03*
X431154D03*
X433954D03*
X433724Y433975D03*
X432310Y436164D03*
X427782Y464026D03*
X433673Y461607D03*
X429673D03*
X442704Y506427D03*
X427693Y506520D03*
X435789Y501525D03*
X427568Y502003D03*
X435831Y498923D03*
X438644Y500461D03*
X438353Y508685D03*
X427693Y509020D03*
X432700Y516277D03*
X435834Y509580D03*
X428740Y533690D03*
X442704Y533790D03*
X428740Y528390D03*
Y530990D03*
X442704Y528490D03*
Y531090D03*
X428740Y536290D03*
X431804Y536682D03*
X428740Y538890D03*
X431804Y539182D03*
X442704Y536390D03*
X439804Y536682D03*
X442704Y538990D03*
X439804Y539182D03*
X428740Y549990D03*
X442804Y546990D03*
Y544390D03*
X428740Y546990D03*
Y544390D03*
Y555190D03*
Y552590D03*
X431384D03*
Y555190D03*
Y544390D03*
Y546990D03*
Y549990D03*
X436369Y622883D03*
X441832Y626193D03*
X441612Y631011D03*
X439290Y712399D03*
X436790D03*
X439290Y709799D03*
X436790D03*
X434290Y712399D03*
Y709799D03*
X429290D03*
X431790Y712399D03*
X429290D03*
X431790Y709799D03*
X429253Y759847D03*
X429210Y784833D03*
X432303Y785067D03*
X434100Y797400D03*
X430600D03*
X428759Y869921D03*
Y867121D03*
Y872721D03*
Y875521D03*
Y878321D03*
X432332Y892049D03*
Y897649D03*
Y894849D03*
Y900449D03*
X432678Y1016186D03*
X429878D03*
X427078D03*
X427052Y1019384D03*
X429852D03*
X432652D03*
X433206Y1055498D03*
X430706D03*
Y1057998D03*
X433206D03*
Y1060498D03*
Y1062998D03*
X430706D03*
Y1060498D03*
X433378Y1091816D03*
Y1089316D03*
X430878Y1084316D03*
Y1086816D03*
X433378D03*
Y1084316D03*
X436244Y1090288D03*
X433378Y1081816D03*
X429677Y1106955D03*
X439023Y1107997D03*
X436244Y1093088D03*
X434823Y1107997D03*
X441359Y1123101D03*
X431476Y1115896D03*
X427810Y1110092D03*
X439908Y1113648D03*
X441359Y1116101D03*
Y1118801D03*
X439123Y1110597D03*
X434823Y1113797D03*
Y1110897D03*
X437023Y1112397D03*
X436923Y1109397D03*
X431476Y1118396D03*
X438233Y1139435D03*
X441359Y1125801D03*
X439759Y1129301D03*
X442259D03*
X429331Y1136935D03*
Y1134435D03*
Y1139435D03*
Y1131935D03*
X435733D03*
Y1134435D03*
Y1136935D03*
Y1139435D03*
X438233Y1131935D03*
Y1134435D03*
Y1136935D03*
X429348Y1129092D03*
X432838Y1128821D03*
X429331Y1141935D03*
X435733D03*
Y1146935D03*
Y1144435D03*
X438233Y1141935D03*
Y1146935D03*
Y1144435D03*
X437231Y1154902D03*
Y1152402D03*
X429331Y1146935D03*
Y1144435D03*
X436789Y1167384D03*
Y1164884D03*
Y1162384D03*
Y1172384D03*
Y1169884D03*
X439289Y1167384D03*
Y1164884D03*
Y1162384D03*
X427231D03*
X429731D03*
Y1164884D03*
Y1167384D03*
Y1169884D03*
Y1172384D03*
X427231D03*
Y1169884D03*
Y1167384D03*
Y1164884D03*
X439289Y1172384D03*
Y1169884D03*
X437132Y1158266D03*
X433249Y1186709D03*
Y1184209D03*
Y1181709D03*
Y1179209D03*
X429731Y1174884D03*
X427231D03*
X436789D03*
X439289D03*
X433249Y1204405D03*
X430934Y1200821D03*
Y1198321D03*
Y1190121D03*
Y1192621D03*
X433249Y1209405D03*
Y1211905D03*
Y1206905D03*
X429063Y1221428D03*
X433063D03*
X429063Y1237428D03*
Y1233428D03*
Y1229428D03*
X433063Y1237428D03*
Y1233428D03*
Y1229428D03*
Y1225428D03*
X429063Y1245428D03*
Y1241428D03*
X433063Y1245428D03*
Y1241428D03*
X440702Y1260160D03*
Y1257160D03*
X437702Y1260160D03*
Y1257160D03*
X428702D03*
X431702Y1260160D03*
Y1257160D03*
X434702Y1260160D03*
Y1257160D03*
X428702Y1260160D03*
X437991Y1286544D03*
X434424Y1286274D03*
X430527Y1289198D03*
X440906D03*
X440896Y1311366D03*
X431867Y1315696D03*
X431885Y1313115D03*
X432485Y1325784D03*
X439434Y1322369D03*
X429530Y1325051D03*
X440402Y1348187D03*
X443802D03*
X439624Y1345691D03*
Y1350683D03*
X440402Y1348187D03*
X443802Y1360099D03*
X440402D03*
X439624Y1357603D03*
Y1362595D03*
X440402Y1360099D03*
Y1372385D03*
Y1384297D03*
X443802Y1372385D03*
Y1384297D03*
X439624Y1381801D03*
Y1369889D03*
Y1374881D03*
X436002Y1382252D03*
X440402Y1372385D03*
Y1384297D03*
X439624Y1386793D03*
X435881Y1394934D03*
Y1398800D03*
X437675Y1550158D03*
X430657Y1563562D03*
X429784Y1548222D03*
X432000Y1644980D03*
X448059Y3000D03*
X445949Y141247D03*
X452686Y152562D03*
X458181Y157370D03*
X458454Y328963D03*
Y324007D03*
Y339755D03*
Y344711D03*
X443508Y337713D03*
X443480Y344014D03*
X453463Y370694D03*
X448092Y375770D03*
X455885Y367702D03*
X448391Y382641D03*
X448323Y379643D03*
X446179Y447101D03*
X453544Y461961D03*
X451144Y472809D03*
Y468809D03*
X443094Y491251D03*
X450942Y506449D03*
X448442D03*
X445942D03*
X446025Y511512D03*
X448525D03*
X446025Y519699D03*
X448525D03*
X452404Y533690D03*
Y528390D03*
Y530990D03*
X455104Y536582D03*
X452404Y536290D03*
X455104Y539082D03*
X452404Y538890D03*
Y549790D03*
X443004Y549890D03*
X452404Y546990D03*
Y544390D03*
X443004Y555090D03*
X452404Y552390D03*
Y554990D03*
X443004Y552490D03*
X455009Y554912D03*
Y552312D03*
Y544312D03*
Y546912D03*
Y549712D03*
X447279Y633881D03*
X448726Y653288D03*
Y646480D03*
Y648980D03*
X446987Y643360D03*
X456469Y638302D03*
X448726Y655788D03*
X447836Y711199D03*
X454815Y974622D03*
X458120Y974701D03*
X451460Y974695D03*
X448999Y994483D03*
X456210Y1004680D03*
X452319Y1000828D03*
X449731Y1000855D03*
X450591Y1004766D03*
X453270Y1003763D03*
X453710Y1018825D03*
X443091Y1022766D03*
X443591Y1019766D03*
X447091D03*
X443091Y1030266D03*
X450063Y1043140D03*
X443091Y1034266D03*
X449767Y1047047D03*
X450244Y1090268D03*
X457303Y1098767D03*
X446863Y1098428D03*
X450244Y1093068D03*
X457188Y1101917D03*
X452910Y1105552D03*
X457123Y1106897D03*
X449116Y1104792D03*
X449359Y1123101D03*
X451859D03*
X455269Y1119422D03*
X450309Y1113822D03*
Y1119422D03*
X452789Y1113822D03*
Y1119422D03*
X455269Y1113822D03*
X444208Y1113648D03*
X446708D03*
X457259Y1129301D03*
X449759Y1125801D03*
X452259D03*
X444759Y1129301D03*
X447259D03*
X449759D03*
X452259D03*
X454759Y1125801D03*
X457259D03*
X454759Y1129301D03*
X443223Y1155213D03*
Y1152713D03*
X452623D03*
Y1155213D03*
X457559Y1169884D03*
Y1167384D03*
Y1164884D03*
Y1162384D03*
X455059D03*
Y1164884D03*
Y1167384D03*
Y1169884D03*
Y1172384D03*
X457559D03*
X455059Y1174884D03*
X457559D03*
X447549Y1179421D03*
Y1181921D03*
Y1184421D03*
Y1186921D03*
Y1204617D03*
X449864Y1198321D03*
Y1200821D03*
Y1190121D03*
Y1192621D03*
X447549Y1209617D03*
Y1207117D03*
Y1212117D03*
X454120Y1269498D03*
X449702Y1260160D03*
Y1257160D03*
X443702Y1260160D03*
X446702D03*
Y1257160D03*
X443702D03*
X456213Y1286776D03*
X451889Y1301067D03*
X451304Y1293045D03*
X456832Y1299121D03*
X451304Y1297045D03*
X454385Y1301845D03*
X451889Y1306023D03*
X454385Y1305245D03*
X444288Y1314391D03*
X456042Y1348187D03*
X452642D03*
X456820Y1345691D03*
X451864D03*
Y1350683D03*
X456820D03*
X444580Y1345691D03*
Y1350683D03*
X452642Y1348187D03*
X456042D03*
X443802D03*
X452642Y1360099D03*
X456042D03*
X456820Y1362595D03*
Y1357603D03*
X451864Y1362595D03*
Y1357603D03*
X444580D03*
Y1362595D03*
X456042Y1360099D03*
X452642D03*
X443802D03*
X456042Y1372385D03*
X452642D03*
X456042Y1384297D03*
X452642D03*
X456820Y1374881D03*
X451864D03*
X444580Y1369889D03*
X456820Y1369795D03*
X451864D03*
X444580Y1374881D03*
Y1381801D03*
X456820D03*
X451864D03*
X443802Y1372385D03*
X452642D03*
X456042D03*
X452642Y1384297D03*
X456042D03*
X443802D03*
X452642Y1396583D03*
X456042D03*
X456820Y1399079D03*
X451864Y1393993D03*
Y1399079D03*
X456820Y1393993D03*
Y1386793D03*
X451864D03*
X444580D03*
X452642Y1396583D03*
X456042D03*
X452642Y1408495D03*
X456042D03*
X456820Y1405999D03*
X451864D03*
Y1410991D03*
X456820D03*
X452642Y1408495D03*
X456042D03*
X454125Y1461182D03*
Y1465913D03*
Y1471805D03*
Y1481267D03*
Y1476536D03*
Y1491890D03*
Y1487159D03*
Y1496621D03*
Y1511976D03*
Y1507245D03*
Y1502514D03*
Y1558813D03*
Y1578898D03*
Y1568275D03*
Y1563544D03*
Y1574167D03*
Y1583629D03*
Y1589522D03*
Y1594253D03*
Y1609607D03*
Y1598984D03*
Y1604876D03*
Y1614338D03*
X452000Y1644980D03*
X468059Y3000D03*
X464738Y110784D03*
X462089Y113394D03*
X470307Y102249D03*
X466307D03*
X462089Y116594D03*
X472332Y133298D03*
X464332D03*
X462089Y119594D03*
X474058D03*
X466479Y134579D03*
X460930Y161306D03*
X470107Y195176D03*
X467607D03*
X472607D03*
X472226Y198883D03*
X473655Y206838D03*
X467467Y203393D03*
X469967D03*
X467346Y218085D03*
X470146D03*
X473946Y216385D03*
X464054Y252371D03*
Y248371D03*
X460950Y328185D03*
Y324785D03*
X461454Y336837D03*
Y331881D03*
X463950Y332659D03*
Y336059D03*
X460950Y343933D03*
Y340533D03*
X461454Y347629D03*
Y352585D03*
X472810Y347995D03*
X472913Y360089D03*
X472608Y352495D03*
X463950Y351807D03*
Y348407D03*
X466375Y366365D03*
X472913Y369089D03*
Y373589D03*
X470389Y389553D03*
X472913Y387089D03*
Y391589D03*
Y382589D03*
Y378089D03*
X470796Y394592D03*
X473658Y467215D03*
X471048Y464566D03*
X464848D03*
X467848D03*
X465126Y460435D03*
X462126D03*
X467848Y476535D03*
X464848D03*
X468558Y503669D03*
Y507669D03*
Y495669D03*
Y499669D03*
Y512669D03*
Y516609D03*
X464199Y510184D03*
X463104Y536582D03*
X468850Y537507D03*
X463104Y539082D03*
X461849Y668016D03*
X459349D03*
X466849D03*
X469349D03*
X464349D03*
X469349Y678016D03*
X466849D03*
X459349D03*
X461849D03*
X464349D03*
X469300Y799500D03*
X462242Y809792D03*
X459245Y807152D03*
X473654Y821234D03*
X475032Y843252D03*
X472399Y839566D03*
X463404Y846870D03*
X474678Y857919D03*
X463134Y859203D03*
X465492Y861970D03*
X460455Y867050D03*
X475046Y885952D03*
X471726Y883705D03*
X467494Y924532D03*
X471110Y921577D03*
X471876Y937236D03*
X471068Y930235D03*
X473992Y952546D03*
X469495Y1011303D03*
X459360Y1004680D03*
X464795Y1000647D03*
X469495Y1023303D03*
Y1017303D03*
X462185Y1016825D03*
X459860Y1015825D03*
X462427Y1030218D03*
X471558Y1029482D03*
X473639Y1030952D03*
X459700Y1035716D03*
X460277Y1090268D03*
X474348Y1090171D03*
X460277Y1093068D03*
X462913Y1106365D03*
X474277Y1093048D03*
X472482Y1107997D03*
X468282D03*
X474818Y1123101D03*
X459938Y1110092D03*
X463604Y1115896D03*
X473367Y1113648D03*
X474818Y1116101D03*
Y1118801D03*
X472582Y1110597D03*
X470482Y1112397D03*
X468282Y1110897D03*
Y1113797D03*
X470382Y1109397D03*
X463604Y1118396D03*
X469192Y1131935D03*
X474818Y1125801D03*
X473218Y1129301D03*
X461459Y1136935D03*
Y1134435D03*
Y1139435D03*
Y1131935D03*
X471692Y1139435D03*
Y1136935D03*
Y1134435D03*
Y1131935D03*
X469192Y1139435D03*
Y1136935D03*
Y1134435D03*
X471692Y1146935D03*
Y1141935D03*
X469192Y1144435D03*
Y1146935D03*
Y1141935D03*
X471692Y1144435D03*
X461459D03*
X462687Y1152684D03*
X468850D03*
X461459Y1141935D03*
Y1146935D03*
X462687Y1160834D03*
X474548Y1172384D03*
Y1169884D03*
Y1167384D03*
Y1164884D03*
Y1162384D03*
X468850Y1160834D03*
X474548Y1174884D03*
X465785Y1197471D03*
X461285Y1193471D03*
Y1197471D03*
X465785Y1193471D03*
X463216Y1254164D03*
Y1250760D03*
Y1244055D03*
X474647Y1260160D03*
Y1257160D03*
X471647D03*
Y1260160D03*
X461613Y1286776D03*
X459290Y1297035D03*
X464882Y1348187D03*
X468282D03*
X477122D03*
X469060Y1345691D03*
Y1350683D03*
X464104Y1345691D03*
Y1350683D03*
X468282Y1348187D03*
X464882D03*
X477122Y1360099D03*
X464882D03*
X468282D03*
X469060Y1357603D03*
Y1362595D03*
X464104D03*
Y1357603D03*
X468282Y1360099D03*
X464882D03*
X468282Y1384297D03*
X464882D03*
X468282Y1372385D03*
X464882D03*
X477122Y1384297D03*
Y1372385D03*
X464104Y1381801D03*
X469060D03*
X464104Y1369889D03*
X469060D03*
X464104Y1374881D03*
X469060D03*
X464882Y1372385D03*
X468282D03*
X464882Y1384297D03*
X468282D03*
X477122Y1396583D03*
X464882D03*
X468282D03*
X469060Y1386793D03*
X464104D03*
X469060Y1399079D03*
X464104Y1394087D03*
X469060D03*
X464104Y1399079D03*
X468282Y1396583D03*
X464882D03*
Y1408495D03*
X468282D03*
X477122D03*
X464104Y1405999D03*
X469060D03*
X464104Y1410991D03*
X469060D03*
X464882Y1408495D03*
X468282D03*
X471448Y1461182D03*
X462786Y1460782D03*
X471448Y1465913D03*
X462786Y1465513D03*
X471448Y1481267D03*
X462786Y1480867D03*
X471448Y1471805D03*
Y1476536D03*
X462786Y1476136D03*
Y1470244D03*
X471448Y1496621D03*
X462786Y1496221D03*
X471448Y1491890D03*
X462786Y1491490D03*
Y1485598D03*
X471448Y1487159D03*
Y1511976D03*
Y1502514D03*
Y1507245D03*
X462786Y1511576D03*
Y1506845D03*
Y1500952D03*
Y1516307D03*
Y1563144D03*
X471448Y1558813D03*
X462786Y1578498D03*
X471448Y1574167D03*
Y1568275D03*
Y1563544D03*
X462786Y1567875D03*
Y1572606D03*
X471448Y1578898D03*
Y1594253D03*
X462786Y1593853D03*
X471448Y1589522D03*
Y1583629D03*
X462786Y1583229D03*
Y1587960D03*
X471448Y1598984D03*
X462786Y1609207D03*
Y1598584D03*
Y1603315D03*
X471448Y1609607D03*
Y1604876D03*
Y1614338D03*
X462786Y1613938D03*
Y1618669D03*
X472000Y1644980D03*
X484043Y4469D03*
X485404Y24773D03*
Y44773D03*
X487925Y95111D03*
X492775Y111255D03*
Y114655D03*
X485475Y118342D03*
X480324Y109172D03*
X477324D03*
X479331Y106495D03*
X483075Y116497D03*
X487875D03*
X490375Y109410D03*
Y116497D03*
X479331Y102495D03*
X492775Y125428D03*
Y128828D03*
X485475Y132515D03*
Y121742D03*
Y135915D03*
X483075Y130670D03*
X487875Y123584D03*
Y130670D03*
X490375Y123583D03*
Y130670D03*
X483075Y123584D03*
X485475Y118342D03*
Y121742D03*
Y132515D03*
X479065Y146012D03*
X480971Y141228D03*
X483075Y137757D03*
X487875D03*
X485475Y135915D03*
X479065Y142862D03*
X483859Y150847D03*
X487654Y195176D03*
X485154D03*
X482654D03*
X486672Y199248D03*
X490154Y195176D03*
X476155Y206838D03*
X491607Y213539D03*
X485235Y210509D03*
X482735D03*
X489672Y202048D03*
X486672Y201748D03*
X484508Y206806D03*
X487008D03*
X476659Y216970D03*
Y219470D03*
X476725Y226320D03*
X476659Y221970D03*
X485827Y247292D03*
X478617Y236121D03*
X475651Y238589D03*
X485053Y238689D03*
X483412Y242078D03*
X478643Y232971D03*
X488769Y246874D03*
X489288Y238714D03*
X478536Y253198D03*
X483242Y366481D03*
X483584Y375840D03*
X483736Y371266D03*
X481724Y373589D03*
Y369089D03*
X483541Y380306D03*
X481724Y391589D03*
Y387089D03*
Y382589D03*
Y378089D03*
X488438Y425464D03*
X482532Y418464D03*
X490985Y412342D03*
X485485Y439903D03*
X489485D03*
X482484Y444517D03*
X482193Y472784D03*
Y468784D03*
Y476784D03*
X482905Y531726D03*
X482737Y537215D03*
X482836Y534249D03*
X482905Y527726D03*
Y552726D03*
Y540726D03*
Y548726D03*
X486738Y581222D03*
X489538D03*
Y591215D03*
X486738D03*
X491340Y611091D03*
X487209Y611071D03*
X484772Y621311D03*
Y629311D03*
Y625311D03*
X481165Y646036D03*
X485005Y659771D03*
X491324Y667293D03*
X488765Y667224D03*
X485303Y681841D03*
X484341Y700528D03*
X486837Y701306D03*
X484341Y705484D03*
X486837Y704706D03*
X489406Y797558D03*
X486246Y804497D03*
X485824Y819787D03*
X481593Y826387D03*
X489572Y822805D03*
X479448Y828594D03*
X491453Y834546D03*
X491527Y843206D03*
X479700Y847600D03*
X488469Y857013D03*
X477574Y860815D03*
X481943Y924633D03*
X488388Y938903D03*
X483636Y952152D03*
X476475Y952249D03*
X489163Y977163D03*
X490143Y989521D03*
X487091Y989550D03*
X481495Y1011303D03*
X475495D03*
X481495Y1023303D03*
Y1017303D03*
X475495Y1023303D03*
X488041Y1020440D03*
X485678Y1039880D03*
X476148Y1057998D03*
Y1055498D03*
X478648D03*
Y1057998D03*
X476148Y1060498D03*
Y1062998D03*
X478648D03*
Y1060498D03*
X477607Y1089942D03*
X491503Y1086796D03*
Y1084296D03*
X478517Y1086724D03*
Y1084224D03*
Y1081724D03*
X476017D03*
Y1084224D03*
Y1086724D03*
X490762Y1098767D03*
X480322Y1098428D03*
X486369Y1105552D03*
X490647Y1101917D03*
X490582Y1106897D03*
X482575Y1104792D03*
X485318Y1123101D03*
X488728Y1119422D03*
X483768Y1113822D03*
X486248D03*
Y1119422D03*
X483768D03*
X488728Y1113822D03*
X482818Y1123101D03*
X480167Y1113648D03*
X477667D03*
X490718Y1129301D03*
X483218Y1125801D03*
X485718D03*
X475718Y1129301D03*
X478218D03*
X480718D03*
X483218D03*
X485718D03*
X488218Y1125801D03*
X490718D03*
X488218Y1129301D03*
X477682Y1152713D03*
Y1155213D03*
X488082D03*
Y1152713D03*
X477048Y1172384D03*
Y1169884D03*
Y1167384D03*
Y1164884D03*
Y1162384D03*
X479521Y1179209D03*
Y1181709D03*
Y1184209D03*
Y1186709D03*
X477048Y1174884D03*
X477206Y1198321D03*
X490671D03*
Y1200821D03*
X479521Y1204405D03*
X477206Y1200821D03*
X490671Y1192621D03*
Y1190121D03*
X477206Y1192621D03*
Y1190121D03*
X479521Y1206905D03*
Y1211905D03*
Y1209405D03*
X489647Y1260160D03*
Y1257160D03*
X486647D03*
Y1260160D03*
X480647Y1257160D03*
X477647D03*
Y1260160D03*
X480647D03*
X483647Y1257160D03*
Y1260160D03*
X484800Y1302000D03*
X490100Y1302100D03*
X487600D03*
X480522Y1348187D03*
X489362D03*
X492762D03*
X488584Y1345691D03*
Y1350683D03*
X481300Y1345691D03*
X476344D03*
X481300Y1350683D03*
X476344D03*
X489362Y1348187D03*
X480522D03*
X477122D03*
X489362Y1360099D03*
X492762D03*
X480522D03*
X488584Y1357603D03*
Y1362595D03*
X481300D03*
Y1357603D03*
X476344Y1362595D03*
Y1357603D03*
X480522Y1360099D03*
X477122D03*
X489362D03*
X480522Y1372385D03*
Y1384297D03*
X489362Y1372385D03*
Y1384297D03*
X492762Y1372385D03*
Y1384297D03*
X488584Y1381801D03*
X481300D03*
X488584Y1374881D03*
Y1369889D03*
X481300D03*
Y1374881D03*
X476344Y1381801D03*
Y1369889D03*
Y1374881D03*
X477122Y1372385D03*
X480522D03*
X489362D03*
Y1384297D03*
X480522D03*
X477122D03*
X489362Y1396583D03*
X492762D03*
X480522D03*
X488584Y1386793D03*
X481300D03*
Y1399079D03*
X476344Y1394087D03*
Y1399079D03*
X488584Y1394087D03*
X481300D03*
X488584Y1399079D03*
X476344Y1386793D03*
X480522Y1396583D03*
X477122D03*
X489362D03*
Y1408495D03*
X480522D03*
X492762D03*
X476344Y1410991D03*
X481300Y1405999D03*
X476344D03*
X488584D03*
Y1410991D03*
X481300D03*
X477122Y1408495D03*
X480522D03*
X489362D03*
X480109Y1460782D03*
Y1465513D03*
X488771Y1465913D03*
Y1461182D03*
X480109Y1476136D03*
Y1470244D03*
X488771Y1471805D03*
Y1476536D03*
Y1481267D03*
X480109Y1480867D03*
Y1496221D03*
X488771Y1487159D03*
Y1491890D03*
X480109Y1491490D03*
Y1485598D03*
X488771Y1496621D03*
Y1511976D03*
X480109Y1511576D03*
Y1506845D03*
Y1500952D03*
X488771Y1502514D03*
Y1507245D03*
X480109Y1516307D03*
X488771Y1558813D03*
X480109Y1563144D03*
X488771Y1578898D03*
X480109Y1578498D03*
X488771Y1574167D03*
Y1568275D03*
Y1563544D03*
X480109Y1567875D03*
Y1572606D03*
X488771Y1589522D03*
Y1583629D03*
X480109Y1583229D03*
Y1587960D03*
X488771Y1594253D03*
X480109Y1593853D03*
X488771Y1609607D03*
Y1604876D03*
Y1598984D03*
X480109Y1609207D03*
Y1598584D03*
Y1603315D03*
X488771Y1614338D03*
X480109Y1613938D03*
Y1618669D03*
X492725Y53597D03*
X503537Y77784D03*
Y75184D03*
Y80384D03*
Y82984D03*
X506091Y92849D03*
X503537Y85584D03*
X503075Y95236D03*
Y102323D03*
X503327Y109410D03*
Y116496D03*
X495075D03*
Y102323D03*
Y109410D03*
X492775Y114655D03*
Y111255D03*
X492294Y106561D03*
X495075Y130670D03*
Y123583D03*
X506653Y121652D03*
X504552Y130670D03*
X492775Y128828D03*
Y125428D03*
X504547Y137756D03*
X495075D03*
X493288Y238714D03*
X497424Y354559D03*
X492317Y376252D03*
X493485Y439903D03*
X503729Y439919D03*
X503682Y455466D03*
X497776Y448466D03*
X500729Y469905D03*
X496729Y470419D03*
X492736Y487982D03*
Y483982D03*
X505476Y485128D03*
X497095Y481467D03*
X492736Y499982D03*
X501887Y504825D03*
X499387D03*
X496887D03*
X492736Y495982D03*
X501828Y517401D03*
X499328D03*
X496828D03*
X502379Y522569D03*
X495444Y531948D03*
X503494Y531882D03*
X502379Y525369D03*
X500994Y531882D03*
X498494D03*
X504079Y529169D03*
X493929Y555194D03*
X496729D03*
X503729D03*
X500929D03*
X493929Y563194D03*
X496729D03*
X493929Y571194D03*
X496729D03*
X500929D03*
X503729D03*
Y563194D03*
X500929D03*
X492338Y581222D03*
X505286D03*
X502486D03*
X492338Y591215D03*
X505286D03*
X502486D03*
X505458Y610562D03*
X502658D03*
Y607762D03*
X505458D03*
X493778Y641817D03*
X494632Y654622D03*
X494465Y657772D03*
X502755Y657694D03*
X496070Y665976D03*
X504966Y678098D03*
X498284Y681453D03*
Y678953D03*
X501618Y698355D03*
X499012Y699819D03*
X503311Y715652D03*
X500705Y705524D03*
X500714Y708755D03*
X502832Y720491D03*
X507546Y738539D03*
X505673Y767961D03*
X500717D03*
X504895Y770457D03*
X501495D03*
X506166Y793224D03*
X504341Y812040D03*
X491655Y829173D03*
X506246Y824689D03*
X494677Y830468D03*
X492799Y846488D03*
X503741Y846830D03*
X497467Y833027D03*
X495073Y835586D03*
X495470Y844271D03*
X499640Y861538D03*
X495700Y849389D03*
X494315Y941212D03*
X503144Y957934D03*
X499595Y963963D03*
X493050Y976078D03*
X504088Y985171D03*
X506888D03*
X506702Y978947D03*
X493091Y989550D03*
X503933Y981392D03*
X506566Y1000766D03*
Y1004766D03*
Y1008766D03*
Y996766D03*
Y1016266D03*
Y1012266D03*
Y1030766D03*
X505981Y1052487D03*
X503177Y1058097D03*
X495677D03*
X493177D03*
X498177D03*
X500677D03*
X503177Y1060697D03*
X495677D03*
X493177D03*
X498177D03*
X500677D03*
X494003Y1086796D03*
X496503D03*
X499003D03*
X501503D03*
Y1084296D03*
X499003D03*
X496503D03*
X494003D03*
X501831Y1090288D03*
X496372Y1106298D03*
X504610Y1107997D03*
X501831Y1093088D03*
X500410Y1107997D03*
X506946Y1123101D03*
X497063Y1115896D03*
X505495Y1113648D03*
X506946Y1116101D03*
Y1118801D03*
X504710Y1110597D03*
X500410Y1113797D03*
X502610Y1112397D03*
X500410Y1110897D03*
X502510Y1109397D03*
X493397Y1110092D03*
X497063Y1118396D03*
X506946Y1125801D03*
X505346Y1129301D03*
X507846D03*
X503820Y1139435D03*
Y1136935D03*
Y1134435D03*
Y1131935D03*
X501320Y1139435D03*
Y1136935D03*
Y1134435D03*
Y1131935D03*
X494918Y1136935D03*
Y1134435D03*
Y1139435D03*
Y1131935D03*
X498727Y1128759D03*
X495236Y1129094D03*
X503820Y1144435D03*
Y1146935D03*
Y1141935D03*
X501320Y1144435D03*
Y1146935D03*
Y1141935D03*
X494918Y1146935D03*
Y1144435D03*
Y1141935D03*
X502562Y1152713D03*
Y1155213D03*
X502376Y1172384D03*
Y1169884D03*
Y1167384D03*
Y1164884D03*
Y1162384D03*
X504876Y1172384D03*
Y1169884D03*
Y1167384D03*
Y1164884D03*
Y1162384D03*
X492818D03*
Y1164884D03*
Y1167384D03*
Y1169884D03*
Y1172384D03*
X495318D03*
Y1169884D03*
Y1167384D03*
Y1164884D03*
Y1162384D03*
X502562Y1158200D03*
X506451Y1179209D03*
Y1181709D03*
Y1184209D03*
Y1186709D03*
X504876Y1174884D03*
X493821Y1186921D03*
Y1184421D03*
Y1181921D03*
Y1179421D03*
X492818Y1174884D03*
X495318D03*
X502376D03*
X506451Y1204405D03*
X504136Y1198321D03*
Y1200821D03*
X493821Y1204617D03*
X496136Y1200821D03*
Y1198321D03*
X504136Y1190121D03*
Y1192621D03*
X496136Y1190121D03*
Y1192621D03*
X506451Y1206905D03*
Y1211905D03*
Y1209405D03*
X493821Y1207117D03*
Y1209617D03*
Y1212117D03*
X506562Y1222194D03*
X502562D03*
X498562D03*
X494562D03*
X506562Y1226194D03*
Y1230194D03*
Y1234194D03*
X502562Y1226194D03*
Y1230194D03*
Y1234194D03*
Y1238194D03*
X498562Y1230194D03*
Y1234194D03*
Y1238194D03*
X494562Y1226194D03*
Y1230194D03*
Y1234194D03*
Y1238194D03*
Y1246194D03*
Y1242194D03*
X506562D03*
Y1246194D03*
X502562Y1242194D03*
Y1246194D03*
X498562D03*
X504647Y1257160D03*
X507347D03*
X501647D03*
Y1260160D03*
X495647D03*
X492647D03*
Y1257160D03*
X495647D03*
X498647D03*
Y1260160D03*
X507347D03*
X504647D03*
X501602Y1348187D03*
X505002D03*
X500824Y1350683D03*
Y1345691D03*
X505780Y1350683D03*
Y1345691D03*
X493540D03*
Y1350683D03*
X492762Y1348187D03*
X501602D03*
X505002D03*
X501602Y1360099D03*
X505002D03*
X505780Y1362595D03*
Y1357603D03*
X500824Y1362595D03*
Y1357603D03*
X493540Y1362595D03*
Y1357603D03*
X501602Y1360099D03*
X505002D03*
X492762D03*
X501602Y1384297D03*
Y1372385D03*
X505002Y1384297D03*
Y1372385D03*
X493540Y1381801D03*
Y1374881D03*
Y1369889D03*
X505780Y1381801D03*
Y1374881D03*
Y1369889D03*
X500824D03*
Y1381801D03*
Y1374881D03*
X505002Y1372385D03*
X492762D03*
X501602D03*
X492762Y1384297D03*
X505002D03*
X501602D03*
X505002Y1396583D03*
X501602D03*
X505002D03*
X500824Y1394087D03*
X505780Y1399079D03*
X500824D03*
X505780Y1394087D03*
X493540Y1386793D03*
Y1394087D03*
Y1399079D03*
X505780Y1386793D03*
X500824D03*
X492762Y1396583D03*
X501602D03*
Y1408495D03*
X505002D03*
X505780Y1410991D03*
X500824D03*
X505780Y1405999D03*
X500824D03*
X493540D03*
Y1410991D03*
X505002Y1408495D03*
X501602D03*
X492762D03*
X497432Y1465513D03*
X506093Y1465913D03*
X497432Y1460782D03*
X506093Y1461182D03*
X497432Y1480867D03*
X506093Y1481267D03*
X497432Y1476136D03*
Y1470244D03*
X506093Y1471805D03*
Y1476536D03*
X497432Y1496221D03*
Y1491490D03*
Y1485598D03*
X506093Y1487159D03*
Y1491890D03*
Y1496621D03*
Y1511976D03*
X497432Y1506845D03*
Y1500952D03*
X506093Y1502514D03*
Y1507245D03*
X497432Y1511576D03*
Y1516307D03*
Y1563144D03*
X506093Y1558813D03*
X497432Y1578498D03*
X506093Y1578898D03*
X497432Y1567875D03*
Y1572606D03*
X506093Y1574167D03*
Y1568275D03*
Y1563544D03*
X497432Y1587960D03*
X506093Y1589522D03*
Y1583629D03*
X497432Y1593853D03*
X506093Y1594253D03*
X497432Y1583229D03*
X506093Y1604876D03*
Y1598984D03*
X497432Y1609207D03*
X506093Y1609607D03*
X497432Y1598584D03*
Y1603315D03*
Y1613938D03*
Y1618669D03*
X506093Y1614338D03*
X492000Y1644980D03*
X512725Y53597D03*
X521872Y82593D03*
Y85193D03*
Y74793D03*
Y77393D03*
Y79993D03*
X513008Y95236D03*
X513051Y103037D03*
X513185Y116496D03*
Y109410D03*
X521185Y116496D03*
Y109410D03*
Y102323D03*
X523943Y107649D03*
Y104249D03*
X513185Y130670D03*
Y123583D03*
X521185Y130670D03*
Y123583D03*
X509251Y137756D03*
X521185D03*
X520965Y162368D03*
X523565D03*
X511820Y207978D03*
Y210478D03*
Y215478D03*
Y212978D03*
X522276Y208213D03*
Y213213D03*
Y210713D03*
Y226461D03*
Y228961D03*
Y231461D03*
X511820Y231226D03*
Y228726D03*
Y223726D03*
Y226226D03*
X522276Y215713D03*
X515149Y264180D03*
X517649D03*
X515074Y258880D03*
X524043Y270026D03*
Y267526D03*
X517866Y293796D03*
X515366D03*
X523380Y285690D03*
Y288190D03*
X511342Y311124D03*
X514769Y312953D03*
X511790Y313804D03*
X520845Y434508D03*
X516845D03*
X512845D03*
X514608Y445874D03*
X510022Y446352D03*
X523705Y444269D03*
X523583Y447201D03*
X511753Y454339D03*
Y456839D03*
X509253D03*
Y454339D03*
X508729Y469905D03*
X521310Y470045D03*
X513310D03*
X509253Y459339D03*
X511753D03*
X517310Y470045D03*
X523457Y482134D03*
Y484634D03*
X508325Y485138D03*
X512210Y478625D03*
X513910Y482425D03*
X513325Y485138D03*
X510825D03*
X519786Y491214D03*
X521636Y504699D03*
X516636D03*
X519136D03*
X516756Y500086D03*
X523489Y492987D03*
X519786Y493714D03*
X523489Y495487D03*
X517319Y521804D03*
X516338Y516979D03*
X521338D03*
X518838D03*
X513626Y531378D03*
X518781Y527449D03*
X517319Y524304D03*
X521581Y527449D03*
X509955Y537958D03*
X513658Y539731D03*
X518716Y541895D03*
X521216Y544895D03*
Y541895D03*
X513658Y542231D03*
X509955Y540458D03*
X521494Y572975D03*
Y582747D03*
X508086Y581222D03*
Y591215D03*
X519875Y608311D03*
X518940Y620653D03*
Y617853D03*
X511058Y610562D03*
Y607762D03*
X508258Y610562D03*
Y607762D03*
X520770Y605443D03*
X516770D03*
X512404Y629362D03*
X510215Y627948D03*
X523616Y625013D03*
X521778Y642184D03*
X518812Y665867D03*
X521868Y666577D03*
X518812Y662874D03*
X511990Y686365D03*
X510425Y683246D03*
X522200Y677613D03*
X521540Y686319D03*
X518001Y694940D03*
X522410Y694881D03*
X518067Y699378D03*
X515573Y692515D03*
X515484Y695757D03*
X515504Y701351D03*
X518299Y692384D03*
X520799D03*
X518530Y703584D03*
X522628Y703884D03*
X521159Y706388D03*
X515649D03*
X512530Y718301D03*
X514531Y716398D03*
X523929Y706388D03*
X518389D03*
X508237Y723585D03*
X512502Y738539D03*
X516953Y738575D03*
X521909D03*
X521131Y741071D03*
X517731D03*
X511724Y741035D03*
X508324D03*
X520159Y758832D03*
X520549Y761982D03*
X509096Y753072D03*
X515422Y753455D03*
X509063Y782867D03*
X517194Y773232D03*
X520833Y773389D03*
X513551Y773203D03*
X522316Y793574D03*
X509316Y793224D03*
X508130Y787488D03*
X522697Y797102D03*
X521178Y814001D03*
X518157Y803973D03*
X518565Y811973D03*
X521565Y820931D03*
X522481Y824661D03*
X517702Y826600D03*
X520720Y846133D03*
X517832Y834558D03*
X514682Y834590D03*
X511741Y846649D03*
X508049Y877789D03*
X523272Y880067D03*
X509428Y888390D03*
X521115Y897500D03*
X509673Y900295D03*
X521572Y901500D03*
X516256Y939157D03*
X520146Y939241D03*
X523289Y939195D03*
X514886Y952189D03*
X521353Y952266D03*
X509471Y981608D03*
X514566Y1000766D03*
X514690Y996766D03*
Y1004766D03*
X514566Y1016266D03*
X514649Y1020266D03*
X519792Y1031271D03*
X514843Y1030766D03*
X519500Y1028377D03*
X515831Y1090568D03*
X517702Y1098518D03*
X512450Y1098428D03*
X515831Y1093068D03*
X522890Y1098767D03*
X518497Y1105552D03*
X522775Y1101917D03*
X514703Y1104792D03*
X522710Y1106897D03*
X518376Y1113822D03*
Y1119422D03*
X520856Y1113822D03*
X514946Y1123101D03*
X517446D03*
X520856Y1119422D03*
X515896Y1113822D03*
Y1119422D03*
X509795Y1113648D03*
X512295D03*
X522846Y1129301D03*
X515346Y1125801D03*
X517846D03*
X510346Y1129301D03*
X512846D03*
X515346D03*
X517846D03*
X520346Y1125801D03*
X522846D03*
X520346Y1129301D03*
X518210Y1155213D03*
Y1152713D03*
X508810D03*
Y1155213D03*
X520646Y1169884D03*
Y1167384D03*
Y1164884D03*
Y1162384D03*
X523146D03*
Y1164884D03*
Y1167384D03*
Y1169884D03*
Y1172384D03*
X520646D03*
X520751Y1186921D03*
Y1184421D03*
Y1181921D03*
Y1179421D03*
X523146Y1174884D03*
X520646D03*
X520751Y1204617D03*
X523066Y1200821D03*
Y1198321D03*
Y1190121D03*
Y1192621D03*
X520751Y1207117D03*
Y1209617D03*
Y1212117D03*
X522562Y1222194D03*
X518562D03*
X514562D03*
X510562D03*
X522562Y1226194D03*
X518562D03*
Y1230194D03*
Y1234194D03*
X514562Y1226194D03*
Y1234194D03*
Y1238194D03*
X510562Y1226194D03*
Y1230194D03*
Y1234194D03*
Y1238194D03*
X514562Y1242194D03*
Y1246194D03*
X510562Y1242194D03*
Y1246194D03*
X517374Y1287222D03*
X514363Y1287370D03*
X520548Y1287181D03*
X513842Y1348187D03*
X517242D03*
X526082D03*
X517242D03*
X513064Y1345691D03*
X518020Y1350683D03*
X513064D03*
X518020Y1345691D03*
X513842Y1348187D03*
X526082Y1360099D03*
X513842D03*
X517242D03*
X518020Y1357603D03*
X513064Y1362595D03*
Y1357603D03*
X518020Y1362595D03*
X513842Y1360099D03*
X517242D03*
Y1384297D03*
X513842D03*
X517242Y1372385D03*
X513842D03*
X526082Y1384297D03*
Y1372385D03*
X517242D03*
X513064Y1369889D03*
Y1381801D03*
Y1374881D03*
X518020Y1369889D03*
Y1381801D03*
Y1374881D03*
X513842Y1372385D03*
X517242Y1384297D03*
X513842D03*
X526082Y1396583D03*
X513842D03*
X517242D03*
X518020Y1394087D03*
Y1399079D03*
X513064Y1394087D03*
Y1399079D03*
Y1386793D03*
X518020D03*
X517242Y1396583D03*
X513842D03*
Y1408495D03*
X517242D03*
X526082D03*
X518020Y1405999D03*
Y1410991D03*
X513064D03*
Y1405999D03*
X517242Y1408495D03*
X513842D03*
X514755Y1460782D03*
Y1465513D03*
Y1480867D03*
Y1476136D03*
Y1470244D03*
Y1491490D03*
Y1485598D03*
Y1496221D03*
Y1511576D03*
Y1506845D03*
Y1500952D03*
Y1516307D03*
Y1563144D03*
Y1567875D03*
Y1572606D03*
Y1578498D03*
Y1593853D03*
Y1583229D03*
Y1587960D03*
Y1603315D03*
Y1609207D03*
Y1598584D03*
Y1613938D03*
Y1618669D03*
X512000Y1644980D03*
X531518Y5374D03*
X530831Y24773D03*
Y44773D03*
X526468Y94017D03*
X530197Y101701D03*
X534468Y94017D03*
X538477D03*
X530468D03*
X530197Y98551D03*
X533092Y111223D03*
Y114623D03*
X530596Y115401D03*
X535588Y110445D03*
Y115401D03*
X530596Y110445D03*
X537747Y103783D03*
X533092Y114623D03*
Y111223D03*
X533747Y103783D03*
X533092Y125396D03*
Y128796D03*
X530596Y124618D03*
Y129574D03*
X535588Y124618D03*
Y129574D03*
X533092Y128796D03*
Y125396D03*
X532281Y141247D03*
X528509Y147540D03*
Y151540D03*
X530665Y162793D03*
Y165393D03*
Y170493D03*
Y167993D03*
X535668Y181009D03*
X529662Y181426D03*
X532873Y181366D03*
X538659Y184619D03*
X532159Y191941D03*
X529870Y184221D03*
X532487Y184012D03*
X533906Y211359D03*
Y213859D03*
X528848Y211695D03*
X537609Y213132D03*
X526348Y208695D03*
Y211695D03*
X530245Y229286D03*
X525983Y226141D03*
X533938Y222212D03*
Y224712D03*
X537609Y215632D03*
X526226Y236611D03*
X531226D03*
X528726D03*
X530245Y231786D03*
X528428Y248891D03*
X530928D03*
X533853Y256535D03*
X525928Y248891D03*
X537853Y256303D03*
X526843Y270026D03*
X529343D03*
X526843Y267526D03*
X529343D03*
X525880Y285690D03*
X528680D03*
X525880Y288190D03*
X528680D03*
X532906Y290755D03*
X536906D03*
X524206Y354119D03*
X533027Y351836D03*
X530215Y364422D03*
X535142Y397552D03*
X531992D03*
X526216Y456652D03*
X528716D03*
X526216Y459152D03*
Y461652D03*
X528716Y459152D03*
Y461652D03*
X535119Y481086D03*
Y478586D03*
X526902Y478446D03*
Y475946D03*
X531412Y480705D03*
X535119Y476086D03*
X528612Y480705D03*
X535119Y491133D03*
X531047Y498151D03*
X535119Y493633D03*
Y496133D03*
Y498633D03*
X531047Y495151D03*
X528547D03*
X528247Y498151D03*
X532936Y519544D03*
X525288Y522129D03*
X527936Y519544D03*
X525436D03*
X530436D03*
X525288Y524629D03*
Y527129D03*
Y529929D03*
X529481Y532849D03*
X532281D03*
X525288Y537877D03*
X535219Y555897D03*
Y553297D03*
X533488Y548344D03*
X525288Y540377D03*
Y545377D03*
Y542877D03*
X528488Y548344D03*
X525988D03*
X530988D03*
X524708Y572842D03*
X535219Y561097D03*
Y563697D03*
Y558497D03*
X532009Y570478D03*
X529214Y570686D03*
X532863Y585507D03*
X528270D03*
X528816Y579475D03*
X529423Y573303D03*
X532069Y573689D03*
X532426Y576484D03*
X532908Y590190D03*
X528314Y590145D03*
X524770Y597232D03*
X532770Y605443D03*
X526756Y613913D03*
Y616713D03*
Y619513D03*
X538826Y614158D03*
Y616958D03*
Y619758D03*
X536770Y605443D03*
X538826Y633450D03*
X526756Y636005D03*
Y633205D03*
X538826Y636250D03*
Y639050D03*
X526756Y638805D03*
X524653Y643595D03*
X533486Y664052D03*
X538442D03*
X524941Y661387D03*
X530796D03*
X537664Y661556D03*
X534264D03*
X529664Y664056D03*
X526264D03*
X534940Y684489D03*
X539111Y681459D03*
X526956Y694959D03*
X526951Y699443D03*
X538316Y687357D03*
X535738Y687489D03*
X529493Y692443D03*
Y697443D03*
Y699943D03*
X529501Y702622D03*
X526993Y692443D03*
X529493Y694943D03*
X524493Y692443D03*
X535387Y712617D03*
X526933Y703820D03*
X529469Y706230D03*
X526699Y706388D03*
X532628Y720776D03*
X526276Y721339D03*
X539763Y734097D03*
X534807D03*
X531763Y739097D03*
X526807D03*
X535585Y736593D03*
X538985D03*
X530985Y741593D03*
X527585D03*
X532450Y767474D03*
X532278Y762736D03*
X524598Y753387D03*
X532449Y782389D03*
X534672Y785037D03*
X531501Y792331D03*
X531260Y794934D03*
X531666Y815724D03*
X532304Y806649D03*
X531313Y812850D03*
Y822693D03*
Y826630D03*
X527733Y847026D03*
X536641Y838649D03*
X532316Y833649D03*
X534000Y843000D03*
X537300Y842900D03*
X534632Y849830D03*
X528868Y873683D03*
X525718Y873821D03*
X533468Y878533D03*
X538468Y888033D03*
X530968Y888283D03*
X527346Y911458D03*
X528975Y898346D03*
X537279Y897943D03*
X533143Y897910D03*
X527879Y952189D03*
X530473Y961728D03*
X528674Y964851D03*
X528500Y1106365D03*
X529191Y1115896D03*
X525525Y1110092D03*
X529191Y1118396D03*
X527046Y1131935D03*
Y1139435D03*
Y1134435D03*
Y1136935D03*
X528274Y1152684D03*
X527046Y1146935D03*
Y1144435D03*
Y1141935D03*
X528274Y1160834D03*
X529482Y1348187D03*
X538322D03*
X541722D03*
X525304Y1345691D03*
X530260D03*
X537544Y1350683D03*
X525304D03*
X530260D03*
X537544Y1345691D03*
X529482Y1348187D03*
X526082D03*
X538322D03*
Y1360099D03*
X541722D03*
X529482D03*
X537544Y1357603D03*
X525304Y1362595D03*
X530260D03*
X525304Y1357603D03*
X530260D03*
X537544Y1362595D03*
X538322Y1360099D03*
X529482D03*
X526082D03*
X529482Y1384297D03*
X538322D03*
X529482Y1372385D03*
X538322D03*
X541722Y1384297D03*
Y1372385D03*
X529482D03*
X537544Y1374881D03*
X525304Y1369889D03*
Y1381801D03*
Y1374881D03*
X530260Y1369889D03*
Y1381801D03*
Y1374881D03*
X537544Y1369889D03*
Y1381801D03*
X538322Y1384297D03*
X529482D03*
X538322Y1372385D03*
X526082D03*
Y1384297D03*
X538322Y1396583D03*
X541722D03*
X529482D03*
X526082D03*
X537544Y1399079D03*
Y1394087D03*
X530260D03*
Y1399079D03*
X525304Y1394087D03*
Y1399079D03*
X537544Y1386793D03*
X525304D03*
X530260D03*
X538322Y1396583D03*
X529482D03*
Y1408495D03*
X538322D03*
X541722D03*
X537544Y1410991D03*
Y1405999D03*
X530260D03*
X525304D03*
X530260Y1410991D03*
X525304D03*
X529482Y1408495D03*
X526082D03*
X538322D03*
X532000Y1644980D03*
X550421Y3000D03*
X554198Y68581D03*
X543545Y84140D03*
Y80140D03*
Y76140D03*
X554211Y80581D03*
X546293Y76587D03*
Y72615D03*
X543494Y118335D03*
X540998Y117557D03*
X545990D03*
X548914Y103621D03*
X540682Y106186D03*
X552105Y112083D03*
X556394Y103621D03*
X543494Y132509D03*
Y121735D03*
Y135909D03*
X545990Y122513D03*
Y131731D03*
X540998Y122513D03*
Y131731D03*
X543494Y121735D03*
Y132509D03*
Y118335D03*
Y135909D03*
X544089Y146461D03*
X545990Y136687D03*
X540998D03*
X548311Y141247D03*
X542991Y152367D03*
X555048Y152562D03*
X549374Y180527D03*
X544691Y180572D03*
X540843Y168697D03*
X553097Y192421D03*
X549329Y185121D03*
X544691Y185165D03*
X541931Y191941D03*
X540639Y206760D03*
X548940Y206767D03*
X546440D03*
X543940D03*
X549070Y221708D03*
X546570D03*
X553420Y221642D03*
X545185Y231021D03*
Y228221D03*
X544070Y221708D03*
X543485Y224421D03*
X550736Y236189D03*
X548236D03*
X545736D03*
X541853Y256535D03*
X550677Y248765D03*
X548177D03*
X545677D03*
X542883Y279208D03*
X545874Y268195D03*
X548374D03*
X551174Y270695D03*
X554834Y265897D03*
X551174Y268195D03*
X548374Y270695D03*
X545874D03*
X551477Y288345D03*
Y290845D03*
X548977Y288345D03*
Y290845D03*
Y293645D03*
X551477D03*
X551536Y359223D03*
Y354723D03*
Y350223D03*
Y345723D03*
Y377223D03*
Y372723D03*
Y368223D03*
Y363723D03*
X541644Y389047D03*
X553731Y388487D03*
X541706Y381723D03*
X551536D03*
X552905Y430829D03*
X544738Y581659D03*
X540770Y605443D03*
X544770D03*
X550274Y658676D03*
X551475Y661504D03*
X556574Y684031D03*
X547227Y678299D03*
X547276Y675521D03*
X556574Y700031D03*
Y688987D03*
X543101Y698772D03*
X556574Y716031D03*
Y704987D03*
Y720987D03*
X540379Y719785D03*
X552384Y762892D03*
X552188Y766577D03*
X545768Y781600D03*
X549168D03*
X542599Y782389D03*
X549168Y781600D03*
X545768D03*
X542546Y784911D03*
X554357Y784889D03*
X551524D03*
X550420Y793743D03*
X556326D03*
X540578Y793889D03*
X553871Y811298D03*
X545741Y804149D03*
X548464Y823156D03*
X540807Y816556D03*
X541129Y828335D03*
X546855Y829949D03*
X550087Y829836D03*
X556326Y829989D03*
X541129Y838865D03*
X545981Y846389D03*
X549241Y841388D03*
X546241Y843149D03*
X545237Y850319D03*
X548665Y850399D03*
X548521Y877859D03*
Y874859D03*
X540968Y878360D03*
X545144Y909025D03*
X544793Y899220D03*
X552238Y959102D03*
X548215Y1006560D03*
X552923Y997860D03*
X542793Y998507D03*
X541766Y1018368D03*
X551673Y1023900D03*
X556493Y1118351D03*
X553962Y1348187D03*
X550562D03*
X553962D03*
X554740Y1345597D03*
X542500Y1345691D03*
X549784Y1345597D03*
X542500Y1350683D03*
X549784D03*
X554740D03*
X541722Y1348187D03*
X550562D03*
X553962Y1360099D03*
X550562D03*
X554740Y1362595D03*
Y1357603D03*
X542500Y1362595D03*
X549784D03*
X542500Y1357603D03*
X549784D03*
X553962Y1360099D03*
X550562D03*
X541722D03*
X550562Y1384297D03*
X553962D03*
Y1372385D03*
X550562D03*
X541722D03*
X550562D03*
X554740Y1381801D03*
Y1374881D03*
X542500D03*
X549784Y1369889D03*
Y1381801D03*
Y1374881D03*
X542500Y1369889D03*
Y1381801D03*
X554740Y1369889D03*
X541722Y1384297D03*
X553962D03*
X550562D03*
X553962Y1372385D03*
Y1396583D03*
X550562D03*
X553962D03*
X541722D03*
X554740Y1399079D03*
Y1393993D03*
X542500Y1399079D03*
X549784Y1393993D03*
Y1399079D03*
X542500Y1394087D03*
X554740Y1386793D03*
X549784D03*
X542500D03*
X550562Y1396583D03*
Y1408495D03*
X553962D03*
X554740Y1410991D03*
Y1405999D03*
X542500Y1410991D03*
X549784D03*
X542500Y1405999D03*
X549784D03*
X553962Y1408495D03*
X550562D03*
X541722D03*
X552000Y1644980D03*
X570421Y3000D03*
X566287Y60922D03*
X561123Y55513D03*
X563433Y60438D03*
X557973Y55513D03*
X563224Y96813D03*
X558316Y91951D03*
X558341Y88801D03*
X569114Y94374D03*
X561258Y94351D03*
X560701Y85731D03*
X564255Y86046D03*
X556920Y117261D03*
X567100Y110784D03*
X564451Y113394D03*
X572669Y102249D03*
X568669D03*
X564451Y116594D03*
X567290Y130898D03*
X564451Y119594D03*
X568841Y134579D03*
X563292Y161306D03*
X560543Y157370D03*
X564627Y180665D03*
Y172665D03*
Y176665D03*
Y168665D03*
X569969Y195176D03*
X572469D03*
X556726Y186629D03*
X564627Y196665D03*
Y192665D03*
X564740Y186778D03*
X572329Y203393D03*
X564659Y212864D03*
Y200864D03*
X569829Y203393D03*
X564659Y204864D03*
Y221864D03*
Y216864D03*
X569708Y218085D03*
X572508D03*
X560300Y219379D03*
X566416Y252371D03*
Y248371D03*
X557334Y265897D03*
X570634Y375453D03*
X569938Y378317D03*
X559070Y684809D03*
X559074Y696987D03*
Y692031D03*
X559070Y700809D03*
Y688209D03*
X561570Y696209D03*
Y692809D03*
X559074Y712987D03*
Y708031D03*
X559070Y716809D03*
X561570Y708809D03*
Y712209D03*
X559070Y704209D03*
X561886Y728138D03*
X559070Y720209D03*
X558616Y732530D03*
X562001Y732834D03*
X562374Y721593D03*
X559625Y739609D03*
X557813Y747814D03*
X570578Y749800D03*
X567428Y750145D03*
X557847Y744599D03*
X570695Y767052D03*
X570038Y752339D03*
X564276Y776701D03*
X558241Y796389D03*
X562231Y784911D03*
X558294D03*
X569186Y787332D03*
X561401Y811242D03*
X567559Y812850D03*
X567316Y806224D03*
X561061Y803606D03*
X561001Y806889D03*
X567559Y803008D03*
X563099Y829943D03*
X560263Y829989D03*
X567316Y827724D03*
X559741Y822149D03*
X567559Y824661D03*
X562400Y818900D03*
X572171Y842346D03*
X559196Y846296D03*
X560813Y840574D03*
X568990Y844721D03*
X572476Y845535D03*
X559295Y874267D03*
X559887Y877196D03*
X569577Y886913D03*
X559260Y891043D03*
X564165Y894411D03*
X560814Y901022D03*
X568503Y936807D03*
X562328Y957307D03*
X566303Y951807D03*
X569403D03*
X563103D03*
X560923Y980443D03*
X556923Y980523D03*
X564923Y988813D03*
X556923D03*
X564923Y997860D03*
X560923D03*
X568923D03*
X556923D03*
X568362Y1008262D03*
X571857Y1009354D03*
X558112Y1009655D03*
X560912D03*
X568362Y1011762D03*
X571857Y1016827D03*
X565451Y1035102D03*
X559057Y1030563D03*
X562057D03*
X568057Y1030672D03*
X565057D03*
X571857Y1029427D03*
X569520Y1102091D03*
X560211D03*
X566020D03*
X569520Y1114691D03*
X566020D03*
X560211D03*
Y1109564D03*
X566058Y1122164D03*
X560211D03*
X569520Y1139891D03*
X566020D03*
X560211D03*
X566020Y1127291D03*
X560211D03*
X569520D03*
X566058Y1134764D03*
X566020Y1152491D03*
X560211D03*
X569520D03*
X566058Y1147364D03*
X560211D03*
X566020Y1165091D03*
X569520D03*
X566058Y1159964D03*
X560211D03*
X566058Y1172564D03*
X560211D03*
Y1177691D03*
X566020D03*
X569520D03*
X566058Y1185164D03*
X560211D03*
X563673Y1204932D03*
X568532Y1200001D03*
X569882Y1223749D03*
X562802Y1348187D03*
X566202D03*
X562024Y1350683D03*
Y1345691D03*
X566980D03*
Y1350683D03*
X562802Y1348187D03*
X566202D03*
X562802Y1360099D03*
X566202D03*
X562024Y1357603D03*
X566980D03*
Y1362595D03*
X562024D03*
X566202Y1360099D03*
X562802D03*
Y1384297D03*
X566202D03*
X562802Y1372385D03*
X566202D03*
D03*
X562024Y1369889D03*
Y1381801D03*
Y1374881D03*
X566980Y1369889D03*
Y1381801D03*
Y1374881D03*
X566202Y1384297D03*
X562802D03*
Y1372385D03*
X566202Y1396583D03*
X562802D03*
X566202D03*
X566980Y1399079D03*
Y1394087D03*
X562024Y1399079D03*
Y1394087D03*
X566980Y1386793D03*
X562024D03*
X562802Y1396583D03*
Y1408495D03*
X566202D03*
X566980Y1410991D03*
X562024D03*
X566980Y1405999D03*
X562024D03*
X566202Y1408495D03*
X562802D03*
X565600Y1530800D03*
X567324Y1528151D03*
X572432Y1521462D03*
X569349Y1541947D03*
X560635Y1543531D03*
X566800Y1541800D03*
X565400Y1535100D03*
X586405Y4469D03*
X587766Y24773D03*
Y44773D03*
X587837Y118342D03*
X582686Y109172D03*
X579686D03*
X581693Y106495D03*
X585437Y116497D03*
X581693Y102495D03*
X576420Y116594D03*
X587837Y132515D03*
Y121742D03*
Y135915D03*
X574694Y133298D03*
X585437Y123584D03*
Y130670D03*
X587837Y118342D03*
Y121742D03*
Y132515D03*
X576420Y119594D03*
X581427Y146012D03*
X583333Y141228D03*
X585437Y137757D03*
X587837Y135915D03*
X581427Y142862D03*
X588568Y143762D03*
X586221Y150847D03*
X574969Y195176D03*
X574588Y198883D03*
X587516Y195176D03*
X585016D03*
X589034Y199248D03*
X578517Y206838D03*
X576017D03*
X587597Y210509D03*
X585097D03*
X589034Y201748D03*
X586870Y206806D03*
X576308Y216385D03*
X579021Y216970D03*
Y219470D03*
X579087Y226320D03*
X579021Y221970D03*
X587415Y238689D03*
X588189Y247292D03*
X580979Y236121D03*
X578013Y238589D03*
X585774Y242078D03*
X581005Y232971D03*
X580898Y253198D03*
X581487Y336676D03*
X573805Y728301D03*
X576556Y728219D03*
X575979Y732517D03*
X573778Y747437D03*
X574620Y772724D03*
X584624Y781850D03*
X588345Y798030D03*
X582100Y787600D03*
X586060Y793145D03*
X581001Y814123D03*
X583501Y800831D03*
X581001Y810973D03*
X588377Y807536D03*
X588272Y804601D03*
X588231Y801520D03*
X579758Y817753D03*
X577501Y829069D03*
X588001Y829624D03*
X581158Y823473D03*
X573300Y829600D03*
X579827Y884000D03*
Y888000D03*
X579251Y903364D03*
X582706Y908959D03*
X583065Y903294D03*
X577903Y940907D03*
X581703D03*
X576003Y935107D03*
X573103Y941307D03*
X585703D03*
X581903Y954507D03*
X577303D03*
X577249Y965445D03*
X573895Y965319D03*
X580923Y988813D03*
X588923D03*
X572923D03*
X580923Y997860D03*
X576923D03*
X588923D03*
X577666Y1009354D03*
X581166D03*
X572923Y997860D03*
X584923D03*
X577666Y1021954D03*
X577704Y1016827D03*
X581967Y1105091D03*
Y1117691D03*
Y1130291D03*
Y1155491D03*
Y1142891D03*
Y1168091D03*
Y1180691D03*
X578298Y1215195D03*
X584024Y1209607D03*
X586502Y1227300D03*
X587689Y1505724D03*
X583661Y1529142D03*
X573784Y1530646D03*
X575332Y1523740D03*
X583800Y1518000D03*
X583740Y1520640D03*
X587858Y1517942D03*
X572849Y1518702D03*
X577645Y1540982D03*
X580700Y1544100D03*
X595087Y53597D03*
X590287Y95111D03*
X595137Y114655D03*
Y111255D03*
X592737Y109410D03*
X590237Y116497D03*
X592737D03*
X597437Y102323D03*
Y109410D03*
Y116496D03*
X595137Y111255D03*
Y114655D03*
X594656Y106561D03*
X595137Y128828D03*
Y125428D03*
X597437Y123583D03*
Y130670D03*
X592737Y123583D03*
X590237Y123584D03*
Y130670D03*
X592737D03*
X595137Y125428D03*
Y128828D03*
X597437Y137756D03*
X590237Y137757D03*
X590016Y195176D03*
X592516D03*
X593969Y213539D03*
X592034Y202048D03*
X589370Y206806D03*
X595650Y238714D03*
X591131Y246874D03*
X591650Y238714D03*
X590178Y309760D03*
X592900Y309871D03*
X605778Y391001D03*
Y394401D03*
X603282Y390223D03*
X605147Y382600D03*
X597776Y401513D03*
Y398113D03*
X605778Y408574D03*
Y405174D03*
X595376Y412287D03*
X600272Y397335D03*
X603282Y395179D03*
Y404396D03*
Y409352D03*
X595280Y402291D03*
X600272D03*
X595280Y397335D03*
X597776Y401513D03*
Y398113D03*
X605778Y419347D03*
Y422747D03*
X595376Y426460D03*
Y415687D03*
X592880Y416465D03*
Y411509D03*
X603282Y418569D03*
Y423525D03*
X597872Y425682D03*
X592880D03*
X597872Y416465D03*
Y411509D03*
X595376Y412287D03*
Y426460D03*
Y415687D03*
Y429860D03*
Y440633D03*
X605778Y436921D03*
Y433521D03*
X595376Y444033D03*
X603282Y432743D03*
Y437699D03*
X597872Y439855D03*
X592880D03*
X597872Y430638D03*
X592880D03*
X595376Y440633D03*
Y429860D03*
X597872Y444811D03*
X592880D03*
X593690Y450750D03*
X605262Y458711D03*
X595376Y444033D03*
Y472787D03*
Y469387D03*
X605778Y476499D03*
X592880Y468609D03*
X597872D03*
X592880Y473565D03*
X597872D03*
X595376Y469387D03*
Y472787D03*
X604606Y463600D03*
X605778Y479899D03*
Y490673D03*
X595376Y486960D03*
Y483560D03*
X603282Y489895D03*
X592880Y487738D03*
X597872D03*
X603282Y480677D03*
Y475721D03*
X592880Y482782D03*
X597872D03*
X595376Y483560D03*
Y486960D03*
X605778Y494073D03*
X603282Y494851D03*
X598462Y504684D03*
X605778Y524033D03*
Y520633D03*
X595376Y513521D03*
Y516921D03*
X592880Y517699D03*
X597872D03*
X603282Y519855D03*
X597872Y512743D03*
X592880D03*
X595376Y513521D03*
Y516921D03*
Y531094D03*
Y527694D03*
X605778Y538206D03*
Y534806D03*
X592880Y526916D03*
X597872Y531872D03*
X592880D03*
X603282Y524811D03*
Y538984D03*
Y534028D03*
X597872Y526916D03*
X597789Y536382D03*
X595376Y531094D03*
Y527694D03*
X599110Y552466D03*
X602756Y597580D03*
X604979Y599588D03*
X604241Y589556D03*
X604180Y592354D03*
X602695Y594668D03*
X604982Y596095D03*
X605011Y603600D03*
X604979Y607588D03*
X605011Y619600D03*
Y623600D03*
X592238Y880612D03*
X592272Y877262D03*
X592110Y895611D03*
X597129Y913386D03*
X601084Y913544D03*
X602385Y940920D03*
X589203Y941407D03*
X591403Y938807D03*
Y936007D03*
X589603Y952907D03*
X602484Y965764D03*
X604923Y988813D03*
X596923D03*
Y997860D03*
X592923D03*
X604923D03*
X600923D03*
X602603Y1012354D03*
Y1024954D03*
X593613Y1012354D03*
Y1024954D03*
X604405Y1034870D03*
X591898Y1035011D03*
X603682Y1053457D03*
X590957Y1105091D03*
Y1117691D03*
Y1130291D03*
Y1155491D03*
Y1142891D03*
Y1168091D03*
Y1180691D03*
X593519Y1224472D03*
X592978Y1514812D03*
X591858Y1523542D03*
X591872Y1518071D03*
X598800Y1546400D03*
X615087Y53597D03*
X605899Y80384D03*
Y82984D03*
Y77784D03*
Y75184D03*
X608453Y92849D03*
X605899Y85584D03*
X615370Y95236D03*
X605437D03*
X615413Y103037D03*
X605437Y102323D03*
X605689Y109410D03*
Y116496D03*
X615547D03*
Y109410D03*
X605861Y124576D03*
X615547Y130670D03*
Y123583D03*
X606914Y130670D03*
X606909Y137756D03*
X612138D03*
X620727Y162368D03*
X614182Y210478D03*
Y215478D03*
Y212978D03*
Y207978D03*
Y223726D03*
Y226226D03*
Y231226D03*
Y228726D03*
X617511Y264180D03*
X620011D03*
X617436Y258880D03*
X617728Y293796D03*
X620228D03*
X608274Y390223D03*
X605778Y391001D03*
X608274Y395179D03*
Y404396D03*
Y409352D03*
X605778Y405174D03*
Y394401D03*
Y408574D03*
X608274Y418569D03*
Y423525D03*
X605778Y422747D03*
Y419347D03*
X608274Y432743D03*
Y437699D03*
X605778Y433521D03*
Y436921D03*
X607789Y453682D03*
X606026Y455921D03*
X608274Y489895D03*
Y480677D03*
Y475721D03*
X605778Y479899D03*
Y490673D03*
Y476499D03*
X608274Y494851D03*
X605778Y494073D03*
X608274Y519855D03*
X605778Y520633D03*
Y524033D03*
X608274Y538984D03*
Y534028D03*
Y524811D03*
X605778Y534806D03*
Y538206D03*
X614461Y555234D03*
X614176Y562003D03*
X609472Y634946D03*
X612489Y941024D03*
X609133Y941137D03*
X605733D03*
X608965Y966414D03*
X616923Y997860D03*
X608923D03*
X618878Y1011914D03*
X620151Y1040363D03*
X621479Y1030482D03*
X619086Y1056453D03*
X620715Y1046785D03*
X617634Y1049283D03*
X617894Y1043955D03*
X612955Y1062941D03*
X612000Y1644980D03*
X633248Y44884D03*
X624234Y74793D03*
Y82593D03*
Y85193D03*
Y77393D03*
Y79993D03*
X636830Y94017D03*
X628830D03*
X632830D03*
X632559Y101701D03*
Y98551D03*
X635454Y111223D03*
Y114623D03*
X632958Y110445D03*
X623547Y109410D03*
Y116496D03*
X632958Y115401D03*
X623547Y102323D03*
X635454Y114623D03*
Y111223D03*
X636109Y103783D03*
X626305Y104249D03*
Y107649D03*
X635454Y128796D03*
Y125396D03*
Y128796D03*
X632958Y124618D03*
X623547Y123583D03*
Y130670D03*
X632958Y129574D03*
X635454Y125396D03*
X623547Y137756D03*
X630871Y147540D03*
X634643Y141247D03*
X630871Y151540D03*
X625927Y162368D03*
X623327D03*
X633027Y165393D03*
Y162793D03*
Y170493D03*
Y167993D03*
X632024Y181426D03*
X635235Y181366D03*
X634521Y191941D03*
X632232Y184221D03*
X634849Y184012D03*
X628710Y211695D03*
Y208695D03*
X624638Y208213D03*
X636268Y211359D03*
Y213859D03*
X631210Y211695D03*
X624638Y213213D03*
Y210713D03*
Y231461D03*
X636300Y222212D03*
Y224712D03*
X632607Y229286D03*
X624638Y226461D03*
X628345Y226141D03*
X624638Y228961D03*
Y215713D03*
X633588Y236611D03*
X631088D03*
X632607Y231786D03*
X628588Y236611D03*
X630790Y248891D03*
X633290D03*
X628290D03*
X636215Y256535D03*
X629205Y267526D03*
X626405D03*
X631705D03*
X629205Y270026D03*
X626405D03*
X631705D03*
X631042Y288190D03*
Y285690D03*
X625742Y288190D03*
X628242Y285690D03*
X625742D03*
X628242Y288190D03*
X635268Y290755D03*
X634455Y389154D03*
Y396240D03*
Y403327D03*
Y410413D03*
Y417500D03*
Y424587D03*
Y431673D03*
Y438760D03*
Y445847D03*
Y467539D03*
Y474626D03*
Y488799D03*
Y481713D03*
Y495886D03*
Y511673D03*
Y518760D03*
Y525847D03*
Y532933D03*
Y540020D03*
Y547106D03*
X632009Y541863D03*
Y545263D03*
X630201Y553407D03*
X632701D03*
X630201Y550907D03*
X632701D03*
X634185Y569426D03*
X634471Y566929D03*
X628425Y572070D03*
X629772Y569928D03*
X632119Y570962D03*
X631862Y568475D03*
X633736Y602197D03*
X634200Y595108D03*
X622270Y864781D03*
X621592Y1033862D03*
X638528Y1384297D03*
Y1372385D03*
Y1396583D03*
X629688D03*
X626288D03*
X630466Y1394087D03*
X625510Y1399079D03*
Y1394087D03*
X630466Y1399079D03*
X629688Y1396583D03*
X626288D03*
X629688Y1408495D03*
X626288D03*
X638528D03*
X626288D03*
X625510Y1405999D03*
X630466D03*
X625510Y1410991D03*
X630466D03*
X629688Y1408495D03*
X636015Y1460782D03*
X627354Y1461182D03*
X636015Y1465513D03*
X627354Y1465913D03*
Y1456451D03*
X636015Y1476136D03*
X627354Y1476536D03*
X636015Y1480867D03*
X627354Y1481267D03*
Y1471805D03*
X636015Y1470244D03*
X627354Y1487159D03*
X636015Y1485598D03*
Y1491490D03*
X627354Y1491890D03*
X636015Y1496221D03*
X627354Y1496621D03*
Y1507245D03*
Y1511976D03*
X636015Y1511576D03*
X627354Y1502514D03*
X636015Y1500952D03*
Y1506845D03*
Y1516307D03*
X627354Y1558813D03*
X636015Y1563144D03*
X627354Y1563544D03*
X621727Y1556800D03*
X636015Y1567875D03*
X627354Y1568275D03*
Y1574167D03*
X636015Y1572606D03*
Y1578498D03*
X627354Y1578898D03*
X636015Y1593853D03*
X627354Y1594253D03*
X636015Y1583229D03*
X627354Y1583629D03*
Y1589522D03*
X636015Y1587960D03*
X627354Y1604876D03*
X636015Y1603315D03*
Y1598584D03*
X627354Y1598984D03*
X636015Y1609207D03*
X627354Y1609607D03*
X636015Y1618669D03*
Y1613938D03*
X627354Y1614338D03*
X632000Y1644980D03*
X645907Y76140D03*
Y84140D03*
Y80140D03*
X648655Y76587D03*
Y72615D03*
X640839Y94017D03*
X645856Y118335D03*
X643360Y117557D03*
X637950Y110445D03*
Y115401D03*
X648352Y117557D03*
X651276Y103621D03*
X640109Y103783D03*
X643044Y106186D03*
X645856Y121735D03*
Y132509D03*
Y135909D03*
Y118335D03*
X643360Y122513D03*
Y131731D03*
X637950Y124618D03*
Y129574D03*
X648352Y122513D03*
Y131731D03*
X645856Y132509D03*
Y121735D03*
X646451Y146461D03*
X643360Y136687D03*
X648352D03*
X645856Y135909D03*
X650673Y141247D03*
X645353Y152367D03*
X647053Y180572D03*
X651736Y180527D03*
X638030Y181009D03*
X643205Y168697D03*
X651691Y185121D03*
X647053Y185165D03*
X641021Y184619D03*
X644293Y191941D03*
X643001Y206760D03*
X646302Y206767D03*
X651302D03*
X648802D03*
X639971Y213132D03*
X648932Y221708D03*
X647547Y228221D03*
X645847Y224421D03*
X646432Y221708D03*
X651432D03*
X639971Y215632D03*
X650598Y236189D03*
X648098D03*
X653098D03*
X644215Y256535D03*
X653039Y248765D03*
X650539D03*
X648039D03*
X640215Y256303D03*
X645245Y279208D03*
X650736Y268195D03*
X653536Y270695D03*
Y268195D03*
X650736Y270695D03*
X648236D03*
Y268195D03*
X651339Y290845D03*
Y293645D03*
X653839D03*
X639268Y290755D03*
X653839Y288345D03*
Y290845D03*
X651339Y288345D03*
X642255Y389154D03*
X649074D03*
X642255Y396240D03*
X643534Y404911D03*
X647604Y396240D03*
X642488Y412571D03*
X652381Y414823D03*
X651689Y422864D03*
X643675Y426299D03*
X651759Y429832D03*
X651364Y436447D03*
X653399Y447953D03*
X643986Y445847D03*
X642255Y467539D03*
X652566D03*
X642255Y474626D03*
X651308Y472772D03*
X652042Y487711D03*
X652155Y479104D03*
X642516Y480828D03*
X644466Y498834D03*
X652566Y495886D03*
X647915Y516841D03*
X651166Y510565D03*
X642255Y518760D03*
Y511673D03*
Y525847D03*
X642862Y550123D03*
X642740Y552872D03*
X644494Y572334D03*
X642185Y562443D03*
X643953Y560675D03*
X642726Y574102D03*
X651149Y577716D03*
X648211Y602400D03*
Y598400D03*
Y594400D03*
Y606400D03*
Y614400D03*
Y610400D03*
X647361Y653161D03*
X648352Y645467D03*
X650958Y677843D03*
X650768Y1348187D03*
X654168D03*
X649990Y1350683D03*
Y1345691D03*
X650768Y1348187D03*
X654168Y1360099D03*
X650768D03*
X649990Y1357603D03*
Y1362595D03*
X650768Y1360099D03*
X641928Y1384297D03*
Y1372385D03*
X650768Y1384297D03*
Y1372385D03*
X654168Y1384297D03*
Y1372385D03*
X649990Y1381801D03*
X642706Y1374881D03*
Y1381801D03*
Y1369889D03*
X649990Y1374881D03*
Y1369889D03*
X637750Y1374881D03*
Y1381801D03*
Y1369889D03*
X650768Y1384297D03*
Y1372385D03*
X638528D03*
X641928D03*
X638528Y1384297D03*
X641928D03*
X654168Y1396583D03*
X641928D03*
X650768D03*
X649990Y1399079D03*
Y1394087D03*
X642706Y1386793D03*
X649990D03*
X637750Y1399079D03*
X642706Y1394087D03*
X637750D03*
X642706Y1399079D03*
X637750Y1386793D03*
X641928Y1396583D03*
X638528D03*
X650768D03*
X641928Y1408495D03*
X650768D03*
X654168D03*
X638528D03*
X649990Y1405999D03*
Y1410991D03*
X637750D03*
X642706D03*
Y1405999D03*
X637750D03*
X641928Y1408495D03*
X650768D03*
X653338Y1465513D03*
X644677Y1461182D03*
Y1456451D03*
Y1465913D03*
X653338Y1460782D03*
X644677Y1476536D03*
Y1471805D03*
X653338Y1480867D03*
Y1470244D03*
Y1476136D03*
X644677Y1481267D03*
X653338Y1491490D03*
X644677Y1496621D03*
Y1491890D03*
Y1487159D03*
X653338Y1496221D03*
Y1485598D03*
X644677Y1511976D03*
X653338Y1511576D03*
Y1500952D03*
Y1506845D03*
X644677Y1502514D03*
Y1507245D03*
X653338Y1516307D03*
X644677Y1558813D03*
X653338Y1563144D03*
X644677Y1563544D03*
X653338Y1572606D03*
Y1578498D03*
X644677Y1578898D03*
Y1574167D03*
X653338Y1567875D03*
X644677Y1568275D03*
X653338Y1587960D03*
Y1593853D03*
X644677Y1594253D03*
Y1589522D03*
X653338Y1583229D03*
X644677Y1583629D03*
X653338Y1609207D03*
X644677Y1598984D03*
Y1604876D03*
Y1609607D03*
X653338Y1603315D03*
Y1598584D03*
Y1613938D03*
X644677Y1614338D03*
X653338Y1618669D03*
X652000Y1644980D03*
X668649Y60922D03*
X666209Y57297D03*
X665795Y60438D03*
X657507Y58013D03*
X656560Y68581D03*
X656573Y80581D03*
X665423Y96853D03*
X660678Y91951D03*
X660703Y88801D03*
X663620Y94351D03*
X663063Y85731D03*
X666617Y86046D03*
X659282Y117261D03*
X666813Y113394D03*
X669462Y110784D03*
X666813Y116594D03*
X654467Y112083D03*
X669056Y133298D03*
X666813Y119594D03*
X665654Y161306D03*
X657410Y152562D03*
X662905Y157370D03*
X666989Y172665D03*
Y180665D03*
Y176665D03*
Y168665D03*
X655459Y192421D03*
X659088Y186629D03*
X666989Y196665D03*
Y192665D03*
X667102Y186778D03*
X667021Y200864D03*
Y212864D03*
Y204864D03*
Y221864D03*
Y216864D03*
X655782Y221642D03*
X662662Y219379D03*
X668778Y252371D03*
X668886Y248371D03*
X657196Y265897D03*
X659696D03*
X670066Y390995D03*
Y394395D03*
X660366Y389154D03*
X667666Y389153D03*
X670066Y390995D03*
X662766Y401482D03*
X670066Y408568D03*
X662766Y398082D03*
X670066Y405168D03*
X662766Y412255D03*
X660366Y403327D03*
Y410413D03*
X665166Y396240D03*
X667666D03*
X665166Y403327D03*
X667666Y403326D03*
X665166Y410413D03*
X667666D03*
X660366Y396240D03*
X670066Y405168D03*
X662766Y398082D03*
X670066Y408568D03*
Y394395D03*
X662766Y401482D03*
X670066Y419341D03*
Y422741D03*
X662766Y426428D03*
Y415655D03*
X667666Y417499D03*
X665166Y424586D03*
X667666D03*
X660366Y417500D03*
Y424586D03*
X665166Y417500D03*
X670066Y422741D03*
Y419341D03*
X662766Y415655D03*
Y426428D03*
Y412255D03*
X670066Y436915D03*
X662766Y429828D03*
X670066Y433515D03*
X662766Y440602D03*
Y444002D03*
X665166Y431673D03*
Y438760D03*
X667666D03*
Y431673D03*
X660366D03*
Y438760D03*
X662766Y440602D03*
X670066Y433515D03*
X662766Y429828D03*
X670066Y436915D03*
X665166Y445847D03*
X660366D03*
X662766Y444002D03*
X670066Y472781D03*
Y469381D03*
X662766Y476468D03*
X667666Y467539D03*
X660366D03*
X665166Y474626D03*
X667666D03*
X660366D03*
X670066Y469381D03*
Y472781D03*
Y486954D03*
Y483554D03*
X662766Y479868D03*
Y490641D03*
X660366Y488799D03*
X665166D03*
X667666D03*
Y481712D03*
X665166D03*
X660366Y481713D03*
X662766Y476468D03*
Y490641D03*
X670066Y483554D03*
Y486954D03*
X662766Y479868D03*
Y494041D03*
X665166Y495886D03*
X660366D03*
X662766Y494041D03*
X670066Y516915D03*
Y513515D03*
X662766Y520602D03*
Y524002D03*
X667666Y518760D03*
X665166D03*
X667666Y511673D03*
X660366D03*
Y518760D03*
X670066Y516915D03*
X662766Y520602D03*
Y524002D03*
X670066Y513515D03*
Y527688D03*
X662766Y534775D03*
X670066Y531088D03*
X662766Y538175D03*
X667666Y532933D03*
X665166D03*
Y540020D03*
Y525846D03*
X667666D03*
X660366Y525847D03*
Y532933D03*
Y540020D03*
X670066Y527688D03*
X662766Y534775D03*
X670066Y531088D03*
X662766Y538175D03*
X660366Y554193D03*
Y547106D03*
X660826Y570414D03*
Y567914D03*
Y565414D03*
X669546Y560500D03*
X661760Y561420D03*
Y558917D03*
X660826Y575414D03*
Y572914D03*
X657581Y577937D03*
X660366Y602205D03*
Y595118D03*
X658233Y646449D03*
X655752Y668885D03*
X661776Y662981D03*
X657967D03*
X662092Y666275D03*
X656157Y691851D03*
X659209D03*
X661768Y705043D03*
X661018Y707592D03*
X663008Y1348187D03*
X666408D03*
X654946Y1350683D03*
X662230D03*
X667186D03*
Y1345691D03*
X654946D03*
X662230D03*
X666408Y1348187D03*
X663008D03*
X654168D03*
X663008Y1360099D03*
X666408D03*
X654946Y1357603D03*
Y1362595D03*
X662230Y1357603D03*
Y1362595D03*
X667186Y1357603D03*
Y1362595D03*
X666408Y1360099D03*
X663008D03*
X654168D03*
X666408Y1384297D03*
X663008D03*
X666408Y1372385D03*
X663008D03*
X662230Y1369889D03*
X667186Y1374881D03*
Y1381801D03*
Y1369889D03*
X662230Y1374881D03*
Y1381801D03*
X654946D03*
Y1369889D03*
Y1374881D03*
X654168Y1384297D03*
Y1372385D03*
X663008D03*
X666408D03*
X663008Y1384297D03*
X666408D03*
X663008Y1396583D03*
X666408D03*
X667186Y1399079D03*
Y1393993D03*
X662230D03*
Y1399079D03*
X655046D03*
Y1394087D03*
X667186Y1386793D03*
X662230D03*
X654946D03*
X666408Y1396583D03*
X663008D03*
X654168D03*
X666408Y1408495D03*
X663008D03*
X667186Y1410991D03*
Y1405999D03*
X662230D03*
Y1410991D03*
X655046Y1405999D03*
Y1410991D03*
X666408Y1408495D03*
X663008D03*
X654168D03*
X662000Y1456451D03*
Y1465913D03*
Y1461182D03*
Y1481267D03*
Y1476536D03*
Y1471805D03*
Y1496621D03*
Y1491890D03*
Y1487159D03*
Y1511976D03*
Y1502514D03*
Y1507245D03*
Y1563544D03*
Y1558813D03*
Y1568275D03*
Y1578898D03*
Y1574167D03*
Y1594253D03*
Y1589522D03*
Y1583629D03*
Y1598984D03*
Y1604876D03*
Y1609607D03*
Y1614338D03*
X671476Y94374D03*
X682048Y109172D03*
X685048D03*
X684055Y106495D03*
X678782Y116594D03*
X684055Y102495D03*
X677056Y133298D03*
X678782Y119594D03*
X671203Y134579D03*
X683789Y146012D03*
X685695Y141228D03*
X683789Y142862D03*
X672331Y195176D03*
X674831D03*
X677331D03*
X676950Y198883D03*
X672191Y203393D03*
X674691D03*
X678379Y206838D03*
X680879D03*
X674870Y218085D03*
X681383Y219470D03*
Y216970D03*
X678670Y216385D03*
X681383Y221970D03*
X681449Y226320D03*
X672070Y218085D03*
X680375Y238589D03*
X683341Y236121D03*
X683367Y232971D03*
X683260Y253198D03*
X686012Y339795D03*
X685353Y392718D03*
X672466Y389153D03*
Y410413D03*
X685353Y408718D03*
Y400718D03*
X672466Y396240D03*
Y403326D03*
X685353Y396718D03*
X672466Y424586D03*
Y417499D03*
Y438760D03*
Y431673D03*
X678461Y455981D03*
X672466Y467539D03*
Y474626D03*
X675237Y465611D03*
X672466Y488799D03*
Y481712D03*
Y518760D03*
Y511673D03*
Y525846D03*
Y532933D03*
X682586Y530000D03*
X681586Y555000D03*
X681011Y543925D03*
X682086Y540500D03*
X681086Y547075D03*
X681286Y549800D03*
X681126Y558800D03*
X681190Y562800D03*
X675248Y1348187D03*
X678648D03*
X687488D03*
X679426Y1350683D03*
X674470Y1345691D03*
X679426D03*
X674470Y1350683D03*
X678648Y1348187D03*
X675248D03*
X687488Y1360099D03*
X675248D03*
X678648D03*
X674470Y1357603D03*
Y1362595D03*
X679426Y1357603D03*
Y1362595D03*
X678648Y1360099D03*
X675248D03*
Y1384297D03*
X678648D03*
Y1372385D03*
X675248D03*
X687488Y1384297D03*
Y1372385D03*
X679426Y1374881D03*
X674470D03*
Y1381801D03*
X679426D03*
Y1369889D03*
X674470D03*
X675248Y1384297D03*
X678648D03*
Y1372385D03*
X675248D03*
X687488Y1396583D03*
X675248D03*
X678648D03*
X679426Y1399079D03*
X674470Y1394087D03*
X679426D03*
X674470Y1399079D03*
Y1386793D03*
X679426D03*
X675248Y1396583D03*
X678648D03*
X675248Y1408495D03*
X678648D03*
X687488D03*
X674470Y1405999D03*
X679426D03*
X674470Y1410991D03*
X679426D03*
X678648Y1408495D03*
X675248D03*
X679322Y1461182D03*
Y1456451D03*
Y1465913D03*
X670661Y1460782D03*
Y1465513D03*
Y1470244D03*
Y1476136D03*
X679322Y1481267D03*
Y1476536D03*
Y1471805D03*
X670661Y1480867D03*
X679322Y1487159D03*
X670661Y1496221D03*
Y1485598D03*
Y1491490D03*
X679322Y1496621D03*
Y1491890D03*
X670661Y1500952D03*
Y1506845D03*
X679322Y1511976D03*
Y1502514D03*
Y1507245D03*
X670661Y1511576D03*
Y1516307D03*
X679322Y1558813D03*
X670661Y1563144D03*
X679322Y1563544D03*
Y1578898D03*
Y1574167D03*
Y1568275D03*
X670661Y1572606D03*
Y1578498D03*
Y1567875D03*
X679322Y1583629D03*
X670661Y1587960D03*
Y1593853D03*
Y1583229D03*
X679322Y1594253D03*
Y1589522D03*
Y1604876D03*
Y1609607D03*
X670661Y1603315D03*
Y1598584D03*
Y1609207D03*
X679322Y1598984D03*
Y1614338D03*
X670661Y1618669D03*
Y1613938D03*
X672000Y1644980D03*
X690073Y44662D03*
X697387Y53619D03*
X692649Y95111D03*
X697499Y111255D03*
Y114655D03*
X690199Y118342D03*
X695099Y109410D03*
X687799Y116497D03*
X692599D03*
X695099D03*
X699799Y116496D03*
Y109410D03*
Y102323D03*
X697499Y114655D03*
Y111255D03*
X697018Y106561D03*
X690199Y121742D03*
X697499Y128828D03*
Y125428D03*
X690199Y132515D03*
Y135915D03*
X687799Y123584D03*
X695099Y123583D03*
X692599Y123584D03*
X687799Y130670D03*
X692599D03*
X695099D03*
X699799Y123583D03*
Y130670D03*
X690199Y132515D03*
X697499Y125428D03*
Y128828D03*
X690199Y121742D03*
Y118342D03*
X687799Y137757D03*
X692599D03*
X699799Y137756D03*
X690199Y135915D03*
X688583Y150847D03*
X691396Y199248D03*
X687378Y195176D03*
X689878D03*
X694878D03*
X692378D03*
X696331Y213539D03*
X691396Y201748D03*
X689232Y206806D03*
X687459Y210509D03*
X689959D03*
X694396Y202048D03*
X691732Y206806D03*
X698012Y238714D03*
X689777Y238689D03*
X690551Y247292D03*
X694012Y238714D03*
X688136Y242078D03*
X693493Y246874D03*
X702448Y546712D03*
Y542712D03*
X700164Y636842D03*
X699188Y656321D03*
X698936Y678462D03*
X702086D03*
X692478Y730641D03*
X702691Y766471D03*
Y753471D03*
Y762971D03*
Y756971D03*
X702677Y771159D03*
Y780659D03*
Y775159D03*
Y784659D03*
X690449Y814406D03*
X690888Y1348187D03*
X699728D03*
X703128D03*
X698950Y1350683D03*
Y1345597D03*
X686710Y1350683D03*
X691666D03*
X686710Y1345691D03*
X691666D03*
X690888Y1348187D03*
X687488D03*
X699728D03*
X703128Y1360099D03*
X690888D03*
X699728D03*
X698950Y1362595D03*
Y1357603D03*
X686710D03*
Y1362595D03*
X691666Y1357603D03*
Y1362595D03*
X687488Y1360099D03*
X690888D03*
X699728D03*
X690888Y1384297D03*
Y1372385D03*
X699728Y1384297D03*
Y1372385D03*
X703128Y1384297D03*
Y1372385D03*
X698950Y1374881D03*
Y1381801D03*
Y1369889D03*
X691666D03*
Y1374881D03*
Y1381801D03*
X686710Y1374881D03*
Y1369889D03*
Y1381801D03*
X699728Y1372385D03*
Y1384297D03*
X690888Y1372385D03*
X687488D03*
Y1384297D03*
X690888D03*
X703128Y1396583D03*
X690888D03*
X699728D03*
X698950Y1399079D03*
Y1394087D03*
X686710D03*
Y1399079D03*
X691666Y1394087D03*
Y1399079D03*
X698950Y1386793D03*
X691666D03*
X686710D03*
X690888Y1396583D03*
X687488D03*
X699728D03*
X690888Y1408495D03*
X699728D03*
X703128D03*
X698950Y1405999D03*
Y1410991D03*
X686710D03*
X691666D03*
X686710Y1405999D03*
X691666D03*
X687488Y1408495D03*
X690888D03*
X699728D03*
X696645Y1461183D03*
Y1456452D03*
Y1465914D03*
X687984Y1460782D03*
Y1465513D03*
Y1470244D03*
Y1476136D03*
X696645Y1481268D03*
Y1471806D03*
Y1476537D03*
X687984Y1480867D03*
X696645Y1491891D03*
X687984Y1496221D03*
Y1485598D03*
Y1491490D03*
X696645Y1496622D03*
Y1487160D03*
Y1511977D03*
Y1502515D03*
Y1507246D03*
X687984Y1511576D03*
Y1500952D03*
Y1506845D03*
Y1516307D03*
X696645Y1558813D03*
Y1563544D03*
X687984Y1563144D03*
X696645Y1574167D03*
Y1578898D03*
X687984Y1572606D03*
Y1578498D03*
X696645Y1568275D03*
X687984Y1567875D03*
Y1583229D03*
X696645Y1589522D03*
Y1594253D03*
X687984Y1587960D03*
Y1593853D03*
X696645Y1583629D03*
Y1598984D03*
Y1609607D03*
X687984Y1603315D03*
Y1598584D03*
Y1609207D03*
X696645Y1604876D03*
X687984Y1613938D03*
X696645Y1614338D03*
X687984Y1618669D03*
X692000Y1644980D03*
X718503Y-38525D03*
X718500Y-33320D03*
Y-30420D03*
X718488Y-36010D03*
Y-27642D03*
X718503Y-25127D03*
X717387Y53619D03*
X708261Y82984D03*
Y80384D03*
Y77784D03*
Y75184D03*
X710815Y92849D03*
X708261Y85584D03*
X717732Y95236D03*
X707799D03*
X717775Y103037D03*
X707799Y102323D03*
X708051Y109410D03*
Y116496D03*
X717909D03*
Y109410D03*
X708223Y124576D03*
X717909Y130670D03*
Y123583D03*
X709276Y130670D03*
X714500Y137756D03*
X709271D03*
X716544Y215478D03*
Y210478D03*
Y207978D03*
Y212978D03*
Y228726D03*
Y231226D03*
Y226226D03*
Y223726D03*
X718338Y305272D03*
X713162Y434493D03*
X711598Y438323D03*
X711764Y449873D03*
X710643Y456335D03*
X711764Y445873D03*
X713791Y474424D03*
X718691Y465492D03*
Y472579D03*
X716191D03*
X711391D03*
X713791Y474424D03*
Y477824D03*
Y488597D03*
Y491997D03*
X716191Y479666D03*
X718691D03*
X711391D03*
Y486752D03*
X716191D03*
X718691D03*
X713791Y488597D03*
Y477824D03*
X711391Y493839D03*
X716191D03*
X713791Y491997D03*
Y518558D03*
Y521958D03*
X716191Y516713D03*
Y523800D03*
X718691D03*
X711391D03*
Y516713D03*
X718691D03*
Y509626D03*
X713791Y518558D03*
Y521958D03*
Y536131D03*
Y532731D03*
X718691Y530886D03*
X716191D03*
Y537973D03*
X711391Y530886D03*
Y537973D03*
X713791Y536131D03*
Y532731D03*
Y571997D03*
Y568597D03*
X711391Y566752D03*
X718691Y559665D03*
Y566752D03*
X716191D03*
X713791Y571997D03*
Y568597D03*
Y582771D03*
Y586171D03*
X711391Y573839D03*
X718691D03*
X716191D03*
X711391Y588013D03*
X718691Y588012D03*
X716191Y588013D03*
X718691Y580926D03*
X716191D03*
X711391D03*
X713791Y582771D03*
Y586171D03*
Y596944D03*
Y600344D03*
X716191Y602186D03*
X711391D03*
X718691Y602185D03*
Y595099D03*
X711391D03*
X716191D03*
X713791Y596944D03*
Y600344D03*
Y611117D03*
Y614517D03*
X711391Y609272D03*
X716191D03*
X718691D03*
X716191Y616359D03*
X711391D03*
X713791Y611117D03*
Y614517D03*
X704364Y618288D03*
X706070Y638125D03*
X716656Y646429D03*
X711328Y653821D03*
X703669Y665140D03*
X705390Y655789D03*
X705776Y678519D03*
X716350Y699477D03*
X703604Y699653D03*
X713200Y699676D03*
X716623Y702463D03*
X703600Y702212D03*
X703680Y697094D03*
X715802Y706446D03*
X710196Y707562D03*
X704446Y760611D03*
X717434Y782500D03*
X710275Y786131D03*
X713222Y793312D03*
Y790812D03*
X712901Y821600D03*
X711968Y1348187D03*
X715368D03*
X716146Y1350683D03*
X711190D03*
X716146Y1345691D03*
X711190D03*
X703906Y1350683D03*
Y1345597D03*
X715368Y1348187D03*
X711968D03*
X703128D03*
X715368Y1360099D03*
X711968D03*
X716146Y1357603D03*
X711190D03*
Y1362595D03*
X716146D03*
X703906Y1357603D03*
Y1362595D03*
X715368Y1360099D03*
X711968D03*
X703128D03*
X715368Y1384297D03*
X711968Y1372385D03*
X715368D03*
X711968Y1384297D03*
X716146Y1374881D03*
Y1381801D03*
Y1369889D03*
X711190D03*
Y1374881D03*
Y1381801D03*
X703906D03*
Y1369889D03*
Y1374881D03*
X703128Y1372385D03*
Y1384297D03*
X715368Y1372385D03*
X711968D03*
X715368Y1384297D03*
X711968D03*
Y1396583D03*
X715368D03*
X716146Y1399079D03*
X711190D03*
X716146Y1393993D03*
X711190D03*
X703906Y1394087D03*
Y1399079D03*
X716146Y1386793D03*
X711190D03*
X703906D03*
X715368Y1396583D03*
X711968D03*
X703128D03*
X715368Y1408495D03*
X711968D03*
X716146Y1405999D03*
X711190D03*
X716146Y1410991D03*
X711190D03*
X703906Y1405999D03*
Y1410991D03*
X715368Y1408495D03*
X711968D03*
X703128D03*
X712000Y1644980D03*
X721756Y-38539D03*
X724781Y-37219D03*
X721741Y-36024D03*
Y-27628D03*
X721756Y-25113D03*
X724781Y-26433D03*
X726596Y74793D03*
Y77393D03*
Y79993D03*
Y85193D03*
Y82593D03*
X735192Y94017D03*
X731192D03*
X734921Y101701D03*
Y98551D03*
X725909Y102323D03*
Y116496D03*
Y109410D03*
X728667Y104249D03*
Y107649D03*
X725909Y130670D03*
Y123583D03*
Y137756D03*
X733233Y147540D03*
Y151540D03*
X728289Y162368D03*
X725689D03*
X734386Y181426D03*
X734594Y184221D03*
X727000Y213213D03*
Y208213D03*
X731072Y208695D03*
X733572Y211695D03*
X731072D03*
X727000Y210713D03*
Y228961D03*
X730707Y226141D03*
X727000Y226461D03*
X734969Y229286D03*
X727000Y231461D03*
Y215713D03*
X733450Y236611D03*
X730950D03*
X734969Y231786D03*
X733152Y248891D03*
X730652D03*
X722373Y264180D03*
X719873D03*
X719798Y258880D03*
X731567Y267526D03*
X728767D03*
X734067D03*
Y270026D03*
X731567D03*
X728767D03*
X733404Y285690D03*
X720090Y293796D03*
X722590D03*
X728104Y288190D03*
X730604Y285690D03*
X728104D03*
X730604Y288190D03*
X733404D03*
X731511Y390500D03*
X734606Y379562D03*
X731511Y381113D03*
X722097Y410394D03*
Y403307D03*
X723031Y440098D03*
Y437598D03*
Y435098D03*
Y432598D03*
Y430098D03*
X732035Y442606D03*
X723491Y458406D03*
Y451319D03*
X722097Y453881D03*
X731952Y446606D03*
X722097Y446595D03*
X721091Y467337D03*
Y470737D03*
X723491Y465492D03*
X731291Y466027D03*
X723315Y462264D03*
X723491Y472579D03*
X731433Y475262D03*
X721091Y470737D03*
Y467337D03*
X732959Y463479D03*
X733430Y467367D03*
X721091Y481510D03*
Y484910D03*
X731433Y489435D03*
Y482666D03*
X723491Y479665D03*
Y486752D03*
X721091Y484910D03*
Y481510D03*
X723491Y493839D03*
X731249Y495088D03*
X724362Y504731D03*
X721091Y514871D03*
Y511471D03*
Y525644D03*
X723491Y523799D03*
Y516713D03*
Y509626D03*
X731984Y514608D03*
X731906Y522134D03*
X731291Y509626D03*
X721091Y514871D03*
Y511471D03*
Y529044D03*
X723491Y530886D03*
Y537973D03*
X732549Y529136D03*
X732388Y535677D03*
X721091Y525644D03*
Y529044D03*
Y561510D03*
Y564910D03*
X723491Y566752D03*
Y559665D03*
X731291D03*
X731672Y565574D03*
X721091Y561510D03*
Y564910D03*
Y579084D03*
Y575684D03*
Y589857D03*
X723491Y573839D03*
Y588012D03*
Y580926D03*
X731319Y574338D03*
X721091Y579084D03*
Y575684D03*
Y593257D03*
Y604030D03*
X723491Y595099D03*
Y602185D03*
X721091Y593257D03*
Y604030D03*
Y589857D03*
Y607430D03*
X723491Y609272D03*
Y616358D03*
X731418D03*
X721091Y607430D03*
X734819Y646429D03*
X722473Y693718D03*
X723656Y705858D03*
X720985Y711658D03*
X725667Y732161D03*
X723177Y728219D03*
X721218Y742131D03*
X721163Y738981D03*
X720271Y782481D03*
X733000Y816000D03*
X730880Y828924D03*
X733680Y828977D03*
X732713Y853890D03*
X722600Y869600D03*
X725318Y890354D03*
X724707Y893143D03*
X719661Y904900D03*
X722789Y927095D03*
X720373Y940310D03*
X722400Y942500D03*
X720271Y931730D03*
X732306Y942682D03*
X724547Y958287D03*
X728846Y948331D03*
X727116Y959326D03*
X724208Y1348187D03*
X727608D03*
X736448D03*
X723430Y1350683D03*
X728386Y1345691D03*
X723430D03*
X728386Y1350683D03*
X727608Y1348187D03*
X724208D03*
X736448Y1360099D03*
X724208D03*
X727608D03*
X728386Y1357603D03*
Y1362595D03*
X723430Y1357603D03*
Y1362595D03*
X724208Y1360099D03*
X727608D03*
Y1384297D03*
X724208D03*
X727608Y1372385D03*
X724208D03*
X736448D03*
Y1384297D03*
X728386Y1381801D03*
Y1374881D03*
Y1369889D03*
X723430D03*
Y1381801D03*
Y1374881D03*
X724208Y1372385D03*
Y1384297D03*
X727608D03*
Y1372385D03*
X736448Y1396489D03*
X727608D03*
X724208D03*
X728386Y1386793D03*
X723430D03*
X728386Y1398985D03*
Y1393993D03*
X723430Y1398985D03*
Y1393993D03*
X724208Y1396489D03*
X727608D03*
Y1408401D03*
X724208D03*
X736448D03*
X728386Y1410897D03*
Y1405905D03*
X723430Y1410897D03*
Y1405905D03*
X724208Y1408401D03*
X727608D03*
X732825Y1604100D03*
X732000Y1644980D03*
X736242Y5374D03*
X735555Y24773D03*
Y44773D03*
X748269Y84140D03*
Y76140D03*
Y80140D03*
X751017Y76587D03*
Y72615D03*
X743201Y94017D03*
X739192D03*
X737816Y114623D03*
Y111223D03*
X748218Y118335D03*
X737816Y114623D03*
X750714Y117557D03*
X745722D03*
X740312Y115401D03*
Y110445D03*
X735320D03*
Y115401D03*
X742471Y103783D03*
X737816Y111223D03*
X745406Y106186D03*
X738471Y103783D03*
X737816Y125396D03*
X748218Y121735D03*
Y132509D03*
X737816Y128796D03*
X748218Y135909D03*
Y118335D03*
X745722Y131731D03*
Y122513D03*
X740312Y129574D03*
Y124618D03*
X735320D03*
Y129574D03*
X750714Y131731D03*
Y122513D03*
X737816Y128796D03*
X748218Y132509D03*
Y121735D03*
X737816Y125396D03*
X748218Y135909D03*
X750714Y136687D03*
X745722D03*
X748813Y146461D03*
X737005Y141247D03*
X747715Y152367D03*
X735389Y165393D03*
Y162793D03*
X749415Y180572D03*
X735389Y170493D03*
Y167993D03*
X740392Y181009D03*
X737597Y181366D03*
X745567Y168697D03*
X749415Y185165D03*
X743383Y184619D03*
X736883Y191941D03*
X746655D03*
X737211Y184012D03*
X750667Y192300D03*
X745363Y206760D03*
X751164Y206767D03*
X748664D03*
X738630Y213859D03*
Y211359D03*
X742333Y213132D03*
X738662Y224712D03*
Y222212D03*
X749909Y228221D03*
Y231021D03*
X751294Y221708D03*
X748209Y224421D03*
X748794Y221708D03*
X742333Y215632D03*
X735950Y236611D03*
X750460Y236189D03*
X735652Y248891D03*
X738577Y256535D03*
X746577D03*
X750401Y248765D03*
X742577Y256303D03*
X747607Y279208D03*
X750598Y268195D03*
Y270695D03*
X741630Y290755D03*
X737630D03*
X741051Y316389D03*
X741161Y381500D03*
X749606Y384410D03*
X749586Y410394D03*
Y403307D03*
X741259Y439963D03*
X741381Y430760D03*
X741402Y433570D03*
X741218Y437072D03*
X749539Y438269D03*
Y440869D03*
Y435669D03*
Y430469D03*
Y433069D03*
X741503Y443180D03*
X741523Y454744D03*
X741465Y452018D03*
X749402Y458406D03*
X735599Y449961D03*
X750393Y451677D03*
Y454177D03*
X741602Y465492D03*
X741568Y460250D03*
X739333Y470136D03*
X749402Y465492D03*
X741602Y472579D03*
X749402D03*
X741072Y478958D03*
X741602Y486752D03*
X749402Y479665D03*
Y486752D03*
Y493839D03*
X741602D03*
X749402Y523799D03*
Y516713D03*
Y509626D03*
X741602D03*
Y516713D03*
X749402Y537973D03*
Y530886D03*
X738062Y537973D03*
X740542Y525483D03*
X740463Y532756D03*
X749402Y559665D03*
Y566752D03*
X741602Y559665D03*
Y566752D03*
X749402Y573839D03*
Y588012D03*
Y580925D03*
X741452Y579978D03*
X741602Y573839D03*
X749402Y602185D03*
Y595099D03*
Y609272D03*
Y616358D03*
X741666Y608117D03*
X741992Y763480D03*
X741000Y771100D03*
X743428Y772418D03*
X741993Y775909D03*
X735576Y861780D03*
X736000Y864266D03*
X742407Y988452D03*
X743062Y1004460D03*
X739848Y1348187D03*
X748688D03*
X752088D03*
X747910Y1345691D03*
Y1350683D03*
X735670D03*
X740626D03*
X735670Y1345691D03*
X740626D03*
X739848Y1348187D03*
X736448D03*
X748688D03*
X752088Y1360099D03*
X739848D03*
X748688D03*
X747910Y1357603D03*
Y1362595D03*
X735670Y1357603D03*
Y1362595D03*
X740626Y1357603D03*
Y1362595D03*
X736448Y1360099D03*
X739848D03*
X748688D03*
Y1384297D03*
X739848Y1372385D03*
Y1384297D03*
X748688Y1372385D03*
X752088Y1384297D03*
Y1372385D03*
X747910Y1374881D03*
Y1381801D03*
Y1369889D03*
X740626Y1381801D03*
Y1369889D03*
Y1374881D03*
X735670Y1381801D03*
Y1369889D03*
Y1374881D03*
X748688Y1372385D03*
Y1384297D03*
X739848Y1372385D03*
X736448D03*
X739848Y1384297D03*
X736448D03*
X739848Y1396489D03*
X747910Y1386793D03*
X735670Y1393993D03*
X740626D03*
Y1398985D03*
X735670D03*
X740626Y1386793D03*
X735670D03*
X739848Y1396489D03*
X736448D03*
X739848Y1408401D03*
X735670Y1405905D03*
Y1410897D03*
X740626Y1405905D03*
Y1410897D03*
X739848Y1408401D03*
X736448D03*
X742655Y1445733D03*
X749439Y1458777D03*
X751140Y1581335D03*
X740640Y1586885D03*
X747140Y1581335D03*
X737892Y1602340D03*
X748924Y1617709D03*
X735878Y1617010D03*
X747590Y1627871D03*
X744924Y1617709D03*
X743331Y1627871D03*
X741705Y1622015D03*
X738325Y1634485D03*
X755145Y3000D03*
X765847Y55513D03*
X762697D03*
X758922Y68581D03*
X758935Y80581D03*
X763040Y91951D03*
X763065Y88801D03*
X765982Y94351D03*
X765425Y85731D03*
X762065Y117040D03*
X753638Y103621D03*
X756829Y112083D03*
X761118Y103621D03*
X753035Y141247D03*
X759772Y152562D03*
X765267Y157370D03*
X754098Y180527D03*
X757821Y192421D03*
X754053Y185121D03*
X761450Y186629D03*
X753182Y198671D03*
X753664Y206767D03*
X753794Y221708D03*
X758144Y221642D03*
X765024Y219379D03*
X763653Y224536D03*
X752960Y236189D03*
X755460D03*
X755401Y248765D03*
X752901D03*
X753098Y268195D03*
X755898D03*
X753098Y270695D03*
X755898D03*
X759558Y265897D03*
X762058D03*
X756201Y288345D03*
Y290845D03*
X753701Y288345D03*
Y290845D03*
Y293645D03*
X756201D03*
X760407Y324494D03*
X767099Y316731D03*
X759029Y328867D03*
X763898Y342319D03*
X759029Y332017D03*
X766344Y377912D03*
Y393924D03*
Y389912D03*
Y385912D03*
X758038Y381143D03*
X766344Y381912D03*
Y409924D03*
Y405924D03*
Y401924D03*
X752341Y407148D03*
X756800Y403824D03*
X758381Y395391D03*
X766344Y397912D03*
X752339Y438269D03*
Y433069D03*
Y430469D03*
Y435669D03*
Y440869D03*
X759543Y445787D03*
X755593Y445908D03*
X752893Y451677D03*
Y454177D03*
X752097Y460218D03*
Y463618D03*
X760928Y1348187D03*
X764328D03*
X765106Y1350683D03*
Y1345597D03*
X760150D03*
Y1350683D03*
X752866Y1345691D03*
Y1350683D03*
X760928Y1348187D03*
X764328D03*
X752088D03*
X760928Y1360099D03*
X764328D03*
X765106Y1362595D03*
Y1357603D03*
X760150D03*
Y1362595D03*
X752866Y1357603D03*
Y1362595D03*
X764328Y1360099D03*
X760928D03*
X752088D03*
X760928Y1372385D03*
Y1384297D03*
X764328Y1372385D03*
Y1384297D03*
X765106Y1374881D03*
Y1381801D03*
Y1369889D03*
X760150Y1374881D03*
Y1381801D03*
Y1369889D03*
X752866Y1374881D03*
Y1381801D03*
Y1369889D03*
X752088Y1372385D03*
Y1384297D03*
X764328Y1372385D03*
X760928D03*
X764328Y1384297D03*
X760928D03*
X765106Y1386793D03*
X760150D03*
X752866D03*
X755035Y1443524D03*
X765713Y1437365D03*
X766433Y1583713D03*
X755187Y1580821D03*
X759802Y1590864D03*
X752150Y1627871D03*
X762671Y1619367D03*
X756358Y1613767D03*
X762776Y1629415D03*
X752000Y1644980D03*
X775145Y3000D03*
X771011Y60922D03*
X768157Y60438D03*
X767929Y96890D03*
X773838Y94374D03*
X768979Y86046D03*
X771824Y110784D03*
X777393Y102249D03*
X773393D03*
X769175Y113394D03*
X781144Y116594D03*
X769175D03*
X779418Y133298D03*
X771960Y130898D03*
X781144Y119594D03*
X769175D03*
X773565Y134579D03*
X768016Y161306D03*
X769351Y172665D03*
Y180665D03*
Y176665D03*
Y168665D03*
X779693Y195176D03*
X779312Y198883D03*
X777193Y195176D03*
X774693D03*
X769351Y192665D03*
X769464Y186778D03*
X780741Y206838D03*
X783241D03*
X777053Y203393D03*
X774553D03*
X769383Y200864D03*
Y212864D03*
Y204864D03*
Y221864D03*
Y216864D03*
X777232Y218085D03*
X783745Y216970D03*
X781032Y216385D03*
X783745Y221970D03*
X783811Y226320D03*
X783745Y219470D03*
X782737Y238589D03*
X771140Y252371D03*
Y248371D03*
X780968Y303839D03*
X771941Y311740D03*
X776943Y321649D03*
X772990Y336324D03*
X777569Y353506D03*
X774419Y353470D03*
X778985Y442498D03*
X778881Y446510D03*
X779029Y450510D03*
X778079Y470706D03*
Y467306D03*
X780575Y471484D03*
X775584Y466528D03*
X780575D03*
X775583Y471484D03*
X778079Y467306D03*
Y470706D03*
Y484879D03*
Y481479D03*
X780575Y480701D03*
X775583D03*
Y485657D03*
X780575D03*
X778079Y481479D03*
Y484879D03*
Y514839D03*
Y511439D03*
Y525613D03*
X780575Y510661D03*
X775583Y515617D03*
X780575D03*
X775583Y510661D03*
X778079Y514839D03*
Y511439D03*
Y529013D03*
X780575Y524835D03*
Y529791D03*
X775583Y524835D03*
Y529791D03*
X778079Y529013D03*
Y525613D03*
X775746Y539315D03*
X777708Y553287D03*
X781429Y545017D03*
X778079Y561479D03*
Y564879D03*
X780575Y560701D03*
Y565657D03*
X775583Y560701D03*
Y565657D03*
X778079Y561479D03*
Y564879D03*
Y575652D03*
Y579052D03*
Y589825D03*
X775583Y579830D03*
X780575D03*
X775583Y574874D03*
X780575D03*
X775583Y589047D03*
X780575D03*
X778079Y575652D03*
Y579052D03*
Y593225D03*
Y603999D03*
X780575Y594003D03*
X775583D03*
Y603221D03*
X780575D03*
X778079Y589825D03*
Y593225D03*
Y603999D03*
Y607399D03*
X775583Y608177D03*
X780575D03*
X778079Y607399D03*
X778860Y626912D03*
X778205Y622912D03*
X773168Y1348187D03*
X776568D03*
X772390Y1350683D03*
X777346D03*
Y1345691D03*
X772390D03*
X776568Y1348187D03*
X773168D03*
X776568Y1360099D03*
X773168D03*
X772390Y1357603D03*
Y1362595D03*
X777346Y1357603D03*
Y1362595D03*
X773168Y1360099D03*
X776568D03*
X783694Y1410977D03*
X778685Y1416198D03*
X780162Y1412848D03*
X777749Y1431432D03*
X783469Y1424655D03*
X777114Y1442270D03*
X771557Y1446818D03*
X768910Y1437741D03*
X777749Y1435432D03*
Y1439432D03*
X777260Y1446237D03*
X778428Y1455156D03*
X777725Y1450193D03*
X768812Y1453306D03*
X777033Y1595215D03*
X781124Y1583553D03*
X781545Y1602835D03*
X774658Y1601012D03*
X778045Y1622545D03*
X782289Y1620109D03*
X773822Y1627418D03*
X778045Y1619395D03*
X778358Y1627418D03*
X771383Y1616917D03*
X772000Y1644980D03*
X791129Y4469D03*
X792490Y24773D03*
Y44773D03*
X799811Y53597D03*
X795011Y95111D03*
X799861Y111255D03*
Y114655D03*
X792561Y118342D03*
X784410Y109172D03*
X787410D03*
X794961Y116497D03*
X797461D03*
X790161D03*
X786417Y106495D03*
X797461Y109410D03*
X799861Y114655D03*
Y111255D03*
X786417Y102495D03*
X799380Y106561D03*
X799861Y125428D03*
Y128828D03*
X792561Y121742D03*
Y132515D03*
Y135915D03*
X797461Y123583D03*
X794961Y123584D03*
X790161D03*
X794961Y130670D03*
X797461D03*
X790161D03*
X792561Y132515D03*
Y118342D03*
X799861Y128828D03*
X792561Y121742D03*
X799861Y125428D03*
X794961Y137757D03*
X790161D03*
X788057Y141228D03*
X786151Y146012D03*
X793221Y140296D03*
X792561Y135915D03*
X786151Y142862D03*
X790945Y150847D03*
X797240Y195176D03*
X794740D03*
X789740D03*
X792240D03*
X793758Y199248D03*
X798693Y213539D03*
X794094Y206806D03*
X791594D03*
X789821Y210509D03*
X792321D03*
X793758Y201748D03*
X796758Y202048D03*
X792913Y247292D03*
X792139Y238689D03*
X785703Y236121D03*
X796374Y238714D03*
X790498Y242078D03*
X785729Y232971D03*
X795855Y246874D03*
X785622Y253198D03*
X788522Y290304D03*
X800155Y337368D03*
X800029Y333368D03*
X799937Y347340D03*
X797141Y350368D03*
X792564Y406410D03*
X784586Y421000D03*
Y418500D03*
Y413500D03*
Y416000D03*
X784804Y425371D03*
X794173Y450510D03*
X788481Y474418D03*
X785985Y473640D03*
X790977D03*
X788481Y474418D03*
Y477818D03*
Y488591D03*
Y491991D03*
X785985Y487813D03*
X790977D03*
X785985Y478596D03*
X790977D03*
X788481Y477818D03*
Y488591D03*
X785985Y492769D03*
X790977D03*
X788481Y491991D03*
Y518552D03*
Y521952D03*
X790977Y517774D03*
Y522730D03*
X785985Y517774D03*
Y522730D03*
X788481Y518552D03*
Y521952D03*
Y532725D03*
Y536125D03*
X785985Y531947D03*
Y536903D03*
X790977Y531947D03*
Y536903D03*
X788481Y532725D03*
Y536125D03*
X796000Y553101D03*
X788481Y571991D03*
Y568591D03*
X784665Y564843D03*
X790977Y567813D03*
X785985Y572769D03*
X790977D03*
X785985Y567813D03*
X788481Y571991D03*
Y568591D03*
Y586165D03*
Y582765D03*
X790977Y581987D03*
Y586943D03*
X785985Y581987D03*
Y586943D03*
X788481Y586165D03*
Y582765D03*
Y600338D03*
Y596938D03*
X790977Y601116D03*
X785985D03*
Y596160D03*
X790977D03*
X788481Y600338D03*
Y596938D03*
Y614511D03*
Y611111D03*
X790977Y615289D03*
Y610333D03*
X785985Y615289D03*
Y610333D03*
X788481Y614511D03*
Y611111D03*
X788600Y1006923D03*
X791686Y1025440D03*
X799631D03*
X795631D03*
X789050Y1026150D03*
X794716Y1186071D03*
X787887Y1174500D03*
X798542Y1188345D03*
X794533Y1195766D03*
X792183Y1334030D03*
Y1331230D03*
X789383Y1334030D03*
Y1331230D03*
X794983Y1334030D03*
Y1331230D03*
X794506Y1411307D03*
X795296Y1416995D03*
X792848Y1414718D03*
X793459Y1429165D03*
X788648Y1422044D03*
X785820Y1425993D03*
X793744Y1437159D03*
X786787Y1433800D03*
X799057Y1449158D03*
Y1456016D03*
X793723Y1468071D03*
X799314Y1475693D03*
X797318Y1471242D03*
X787447Y1593586D03*
X791610Y1593708D03*
X793564Y1642682D03*
X810623Y77784D03*
Y82984D03*
Y80384D03*
Y75184D03*
X813177Y92849D03*
X810623Y85584D03*
X810161Y95236D03*
Y102323D03*
X810413Y109410D03*
Y116496D03*
X802161D03*
Y109410D03*
Y102323D03*
X810585Y124576D03*
X811638Y130670D03*
X802161D03*
Y123583D03*
X811633Y137756D03*
X802161D03*
X800374Y238714D03*
X805952Y301675D03*
X801097Y325858D03*
X809489Y313830D03*
X809490Y321368D03*
Y333368D03*
X804536Y441486D03*
X816177Y441442D03*
X813456Y441474D03*
X802136Y452334D03*
X815840Y444091D03*
Y456060D03*
X810756Y471071D03*
Y468571D03*
X814580Y468806D03*
X814828Y472053D03*
X810756Y473571D03*
Y491118D03*
Y488618D03*
Y483618D03*
X816364Y486870D03*
X810756Y486118D03*
X813864Y486870D03*
X810756Y476071D03*
X815492Y732917D03*
X813902Y730738D03*
X813566Y744187D03*
X813653Y746856D03*
X812661Y810032D03*
X813000Y805000D03*
X813548Y814000D03*
X812980Y824166D03*
X813009Y819734D03*
X815500Y824000D03*
X816016Y838036D03*
X813182Y852800D03*
X812440Y862306D03*
X812575Y880834D03*
X814731Y889365D03*
X812219Y883586D03*
X812811Y908162D03*
X803673Y1025440D03*
X809682Y1133284D03*
X803453Y1134729D03*
X814835D03*
X806835D03*
X806787Y1148000D03*
X815034Y1159455D03*
X809623Y1160168D03*
X809393Y1187252D03*
X814160Y1178240D03*
X807487Y1193019D03*
X815487D03*
X811487D03*
X815455Y1201043D03*
X811485D03*
X807489D03*
X804452Y1199814D03*
X809027Y1219895D03*
X807020Y1217900D03*
X812302Y1223170D03*
X815149Y1226016D03*
X810148Y1374884D03*
X800627Y1392748D03*
X806318Y1401661D03*
X800703Y1426779D03*
X812901Y1432804D03*
X815901D03*
X810059Y1432778D03*
X812104Y1426483D03*
X809986Y1438785D03*
X812986D03*
X815986D03*
X809986Y1441485D03*
X812986D03*
X815986D03*
X812901Y1435504D03*
X815901D03*
X810001D03*
X806874Y1447457D03*
X812474D03*
X803057Y1449158D03*
X801057Y1447158D03*
X806874Y1452587D03*
Y1457717D03*
X812474D03*
X815096Y1464387D03*
X803057Y1456016D03*
X801057Y1458016D03*
X812009Y1473432D03*
Y1470432D03*
X815096Y1467387D03*
X812096Y1479587D03*
Y1476587D03*
X815096Y1473387D03*
Y1479587D03*
Y1476587D03*
Y1470387D03*
X801354Y1478681D03*
X804919Y1489247D03*
X811457Y1639797D03*
X819811Y53597D03*
X828958Y79993D03*
Y77393D03*
Y74793D03*
Y85193D03*
Y82593D03*
X820094Y95236D03*
X820137Y103037D03*
X820271Y116496D03*
Y109410D03*
X828271Y116496D03*
Y109410D03*
Y102323D03*
X831029Y104249D03*
Y107649D03*
X820271Y130670D03*
Y123583D03*
X828271Y130670D03*
Y123583D03*
X816637Y137756D03*
X828271D03*
X830651Y162368D03*
X828051D03*
X829362Y213213D03*
X818906Y207978D03*
Y212978D03*
Y215478D03*
Y210478D03*
X829362Y208213D03*
Y210713D03*
Y231461D03*
Y228961D03*
Y226461D03*
X818906Y228726D03*
Y231226D03*
Y226226D03*
Y223726D03*
X829362Y215713D03*
X822235Y264180D03*
X824735D03*
X831129Y267526D03*
Y270026D03*
X824952Y293796D03*
X822452D03*
X830466Y285690D03*
Y288190D03*
X825792Y305225D03*
X825971Y345101D03*
X829381Y348036D03*
X825103Y430358D03*
Y435558D03*
Y432958D03*
X831378Y433086D03*
Y435686D03*
Y430486D03*
X824650Y446740D03*
X822040Y444091D03*
X818840Y456060D03*
X826262Y462326D03*
Y459326D03*
X823529Y467189D03*
X817328Y472053D03*
X820810Y471243D03*
X817380Y468806D03*
X823544Y475061D03*
Y472561D03*
X820810Y473743D03*
X818973Y491258D03*
Y488758D03*
X822418Y485070D03*
Y482570D03*
X828918Y480580D03*
X831418D03*
X831057Y484036D03*
X828272Y535462D03*
X827291Y533100D03*
X830318Y674164D03*
X829496Y676793D03*
X823790Y713375D03*
X829784Y713939D03*
Y716589D03*
Y705489D03*
X823890Y703415D03*
X823670Y710542D03*
X823843Y732109D03*
X824387Y726246D03*
X818307Y724144D03*
X830484Y746701D03*
X819890Y736924D03*
X826484Y747127D03*
X827500Y750000D03*
X819788Y739634D03*
X819993Y754109D03*
X817500Y760000D03*
X824500Y760500D03*
X822151Y752283D03*
X817365Y756827D03*
X820547Y780314D03*
X826925Y769000D03*
X820500Y777500D03*
X824500Y778500D03*
X826925Y787000D03*
X820500Y792000D03*
X824500Y796500D03*
X818500Y814000D03*
X820432Y800529D03*
X826925Y805000D03*
X824500Y814500D03*
X826925Y823000D03*
X829946Y829788D03*
X829791Y839020D03*
X825721Y836666D03*
Y839816D03*
X830014Y833046D03*
X822608Y848526D03*
X826165Y863000D03*
X819134Y863607D03*
X829000Y852000D03*
X831583Y853454D03*
X825686Y869496D03*
X823234Y867680D03*
X826209Y866052D03*
X823234Y870830D03*
X826797Y883756D03*
X825774Y895553D03*
X826070Y893014D03*
X817152Y896380D03*
X817139Y890330D03*
X823900Y882083D03*
X825508Y913869D03*
X818031Y907747D03*
X822462Y915095D03*
X831057Y916745D03*
X818347Y939610D03*
X823552Y930700D03*
X829617Y939583D03*
X816519Y931147D03*
X828193Y949324D03*
X824168Y949538D03*
X828423Y964731D03*
X825670Y964671D03*
X832423Y964669D03*
X828964Y977780D03*
X832711Y993268D03*
X828385Y1120599D03*
X830356Y1116251D03*
X827856D03*
X817006Y1133027D03*
X822006Y1130208D03*
X825335Y1137129D03*
X819449Y1134534D03*
X819026Y1128137D03*
X825744Y1150087D03*
X823220Y1162817D03*
Y1170767D03*
X823487Y1193019D03*
X819487D03*
X819489Y1201039D03*
X823489Y1200969D03*
X826612Y1219254D03*
X819522Y1212164D03*
X821816Y1214458D03*
X823608Y1208993D03*
X817360Y1228226D03*
X816648Y1377608D03*
Y1380758D03*
X824901Y1427404D03*
X827901D03*
X821901D03*
X818901Y1430104D03*
X821901D03*
X830901D03*
X827901D03*
X824901D03*
Y1432804D03*
X827901D03*
X830901D03*
X821901D03*
X818901D03*
X824901Y1435504D03*
X827901D03*
X821901D03*
X818901D03*
X821986Y1441485D03*
X818986D03*
Y1438785D03*
X821986D03*
X817974Y1447457D03*
X832084Y1461072D03*
X817974Y1452587D03*
Y1457717D03*
X818096Y1464387D03*
X821096D03*
X818096Y1473387D03*
X821096D03*
X824096D03*
X818096Y1479587D03*
X821096D03*
X824096D03*
X818096Y1476587D03*
X821096D03*
X824096D03*
X818096Y1467387D03*
Y1470387D03*
X821096D03*
Y1467387D03*
X824096D03*
Y1470387D03*
X831457Y1639797D03*
X838503Y-77705D03*
X841756Y-77719D03*
X838500Y-72500D03*
X838488Y-75190D03*
X841741Y-75204D03*
X844781Y-76399D03*
X838500Y-69600D03*
X844781Y-65613D03*
X841756Y-64293D03*
X838503Y-64307D03*
X841741Y-66808D03*
X838488Y-66822D03*
X838606Y5374D03*
X837919Y24773D03*
Y44773D03*
X841554Y94017D03*
X837554D03*
X845563D03*
X833554D03*
X837283Y101701D03*
Y98551D03*
X840178Y114623D03*
Y111223D03*
X850580Y118335D03*
X840178Y114623D03*
X837682Y110445D03*
Y115401D03*
X848084Y117557D03*
X842674Y115401D03*
Y110445D03*
X844833Y103783D03*
X840178Y111223D03*
X840833Y103783D03*
X847768Y106186D03*
X850580Y121735D03*
Y132509D03*
X840178Y125396D03*
Y128796D03*
X850580Y135909D03*
X842674Y129574D03*
Y124618D03*
X837682D03*
Y129574D03*
X848084Y131731D03*
Y122513D03*
X840178Y128796D03*
Y125396D03*
X848084Y136687D03*
X837751Y165393D03*
Y162793D03*
Y170493D03*
Y167993D03*
X842754Y181009D03*
X839959Y181366D03*
X836748Y181426D03*
X847929Y168697D03*
X839245Y191941D03*
X845745Y184619D03*
X839573Y184012D03*
X836956Y184221D03*
X847725Y206760D03*
X833434Y208695D03*
X835934Y211695D03*
X840992Y213859D03*
Y211359D03*
X833434Y211695D03*
X844695Y213132D03*
X837331Y229286D03*
X841024Y224712D03*
Y222212D03*
X833069Y226141D03*
X844695Y215632D03*
X835812Y236611D03*
X838312D03*
X833312D03*
X837331Y231786D03*
X833014Y248891D03*
X848939Y256535D03*
X840939D03*
X838014Y248891D03*
X835514D03*
X844939Y256303D03*
X836429Y267526D03*
X833929D03*
Y270026D03*
X836429D03*
X832966Y288190D03*
Y285690D03*
X835766Y288190D03*
Y285690D03*
X843992Y290755D03*
X839992D03*
X839573Y325327D03*
X842240Y324854D03*
X848879Y360849D03*
X846098Y408715D03*
X833185Y456309D03*
Y452309D03*
Y448309D03*
X833293Y490636D03*
Y487836D03*
X833918Y480580D03*
X834215Y484138D03*
X844227Y479882D03*
X842476Y482382D03*
X833269Y506683D03*
X835236Y533174D03*
X833953Y530621D03*
X845729Y661263D03*
X836503Y667845D03*
X839636Y666533D03*
X842640Y662814D03*
X838152Y700215D03*
X845784Y713939D03*
Y705489D03*
Y716589D03*
Y708089D03*
X835987Y713745D03*
X846484Y746701D03*
X838484D03*
X841500Y758161D03*
Y776161D03*
X842661Y769521D03*
X846000Y772079D03*
X841500Y794161D03*
Y812161D03*
X840136Y830903D03*
X836839Y831301D03*
X836894Y824401D03*
X848224Y823502D03*
X838685Y832987D03*
X835626Y843629D03*
X838189Y843459D03*
Y847490D03*
X848384Y843459D03*
X846239Y847490D03*
X835553Y835119D03*
X848384Y839459D03*
Y835459D03*
X838194Y836962D03*
X848739Y847459D03*
X837183Y855459D03*
X840234Y851459D03*
X847138Y859459D03*
X839530Y859408D03*
X848384Y863459D03*
X846336Y855459D03*
X845820Y863413D03*
X848384Y851459D03*
X843574Y859423D03*
X837434Y851459D03*
X833327Y855560D03*
X837383Y879530D03*
X837396Y871459D03*
X840234Y875459D03*
X836999Y867413D03*
X845876Y879459D03*
X848384Y867459D03*
X845820Y867413D03*
X848384Y879459D03*
Y871459D03*
Y875459D03*
X845654Y895437D03*
X833870Y881860D03*
X837290Y887490D03*
X842827Y895443D03*
X848322Y888421D03*
X848792Y896472D03*
X836066Y894955D03*
X845633Y883492D03*
X845964Y887490D03*
X837276Y883459D03*
X848200Y883400D03*
X839381Y915839D03*
X841329Y926602D03*
X841274Y914060D03*
X843315Y916612D03*
X836909Y916618D03*
Y914018D03*
X839122Y939655D03*
X833683Y939579D03*
X836243D03*
X833683Y949105D03*
X836243D03*
X836423Y964669D03*
X835431Y977775D03*
X848520Y1016855D03*
X840935Y1011499D03*
X844058Y1011738D03*
X848045Y1019310D03*
X848070Y1022190D03*
X839744Y1444959D03*
Y1440859D03*
Y1448959D03*
X836704Y1448849D03*
Y1440849D03*
X836744Y1444849D03*
X845306Y1438269D03*
X846844Y1454334D03*
X837685Y1453196D03*
X839744Y1457959D03*
X846044Y1451459D03*
X839744Y1461959D03*
X834475Y1460059D03*
X850145Y3000D03*
X865059Y55513D03*
X861284Y68581D03*
X850631Y84140D03*
Y80140D03*
Y76140D03*
X861297Y80581D03*
X853379Y76587D03*
Y72615D03*
X864006Y117261D03*
X853076Y117557D03*
X856000Y103621D03*
X859191Y112083D03*
X863480Y103621D03*
X850580Y118335D03*
Y132509D03*
X853076Y131731D03*
Y122513D03*
X850580Y121735D03*
X853076Y136687D03*
X850580Y135909D03*
X851777Y180572D03*
X856460Y180527D03*
X860183Y192421D03*
X851777Y185165D03*
X856415Y185121D03*
X849017Y191941D03*
X863812Y186629D03*
X853029Y192300D03*
X853526Y206767D03*
X856026D03*
X851026D03*
X860506Y221642D03*
X852271Y228221D03*
X853656Y221708D03*
X856156D03*
X850571Y224421D03*
X851156Y221708D03*
X852822Y236189D03*
X855322D03*
X857822D03*
X852763Y248765D03*
X855263D03*
X857763D03*
X849969Y279208D03*
X852960Y268195D03*
Y270695D03*
X855460D03*
X864420Y265897D03*
X858260Y268195D03*
Y270695D03*
X861920Y265897D03*
X855460Y268195D03*
X858563Y293645D03*
Y290845D03*
X856063Y293645D03*
Y290845D03*
X858563Y288345D03*
X856063D03*
X864920Y343168D03*
X861770Y343006D03*
X854622Y359004D03*
X852569Y356712D03*
X856069Y356426D03*
X854086Y374500D03*
X858586D03*
X863086D03*
X854086Y385000D03*
X858586D03*
X864086Y384000D03*
X857973Y404867D03*
X862522Y400229D03*
X862566Y404867D03*
X857928Y400184D03*
X862020Y410899D03*
X861413Y417071D03*
X858827Y419896D03*
X858410Y413890D03*
X858767Y416685D03*
X861622Y419688D03*
X862882Y458991D03*
X854882D03*
X862882Y468791D03*
Y465991D03*
X854882D03*
Y468791D03*
X850733Y461382D03*
X850832Y473382D03*
X862882Y461791D03*
X854882D03*
X850748Y465382D03*
X861468Y491303D03*
X850738Y477382D03*
X850909Y482382D03*
X861468Y483303D03*
Y487303D03*
X858169Y495032D03*
X853900Y627700D03*
X853989Y630453D03*
Y632953D03*
X858202Y646330D03*
X851111Y656635D03*
X856145Y677887D03*
X855646Y685230D03*
X849680Y694789D03*
X858186Y701170D03*
X855646Y692710D03*
X857986Y722670D03*
X854484Y746701D03*
X849500Y761000D03*
Y758500D03*
Y763500D03*
X863443Y753254D03*
X859000Y764000D03*
Y760000D03*
X864575Y770500D03*
X849500Y779000D03*
Y776500D03*
Y781500D03*
X861425Y770500D03*
X859000Y781000D03*
Y778000D03*
X864575Y788500D03*
X849500Y797000D03*
X853282Y789887D03*
X857632Y789385D03*
X849500Y794500D03*
Y799500D03*
X861425Y788500D03*
X859000Y800000D03*
Y796000D03*
X849500Y815000D03*
X864575Y806500D03*
X861425D03*
X849500Y812500D03*
X859000Y814000D03*
X865004Y831273D03*
X864464Y828503D03*
X864575Y824500D03*
X851782Y823720D03*
X850496Y831469D03*
X861425Y824500D03*
X849500Y817500D03*
X859000Y818000D03*
X851184Y839459D03*
Y835459D03*
X859165Y848728D03*
X851239Y847459D03*
X851184Y843459D03*
X851161Y855205D03*
X851184Y863459D03*
X862114Y859479D03*
X851184Y851459D03*
X859603Y863570D03*
X859461Y859459D03*
X851184Y867459D03*
Y871459D03*
Y875459D03*
X859234Y879600D03*
X859463Y866125D03*
X851184Y879459D03*
X849267Y892567D03*
X859614Y883800D03*
Y887846D03*
X850900Y888359D03*
X850800Y883500D03*
X855524Y898505D03*
X856628Y915242D03*
X864253D03*
X849600Y915266D03*
X864253Y918042D03*
X856628D03*
X849600Y918028D03*
X849205Y924129D03*
X855867Y935540D03*
X849088Y951081D03*
X852247Y1009529D03*
X850686Y1006923D03*
X853449Y1007048D03*
X863334Y1009393D03*
X861047Y1018909D03*
X860887Y1026762D03*
X863956Y1020763D03*
X863689Y1024974D03*
X849996Y1091073D03*
X850023Y1095179D03*
X863342Y1120636D03*
X855542D03*
X858142D03*
X860842D03*
X863442Y1130336D03*
X858242D03*
X855642D03*
X860942D03*
Y1139336D03*
X863442D03*
X861119Y1148080D03*
X863619D03*
X863944Y1432359D03*
Y1429359D03*
X860944Y1432359D03*
X857944Y1429359D03*
X860944D03*
Y1426359D03*
X857944D03*
X863944D03*
X857944Y1432359D03*
X863944Y1435359D03*
Y1441359D03*
Y1438359D03*
X860944Y1441359D03*
X857944Y1435359D03*
X860944D03*
X857944Y1441359D03*
Y1438359D03*
X860944D03*
X859071Y1447459D03*
X864671D03*
X850544Y1447559D03*
X859071Y1452589D03*
Y1457719D03*
X864671D03*
X864644Y1464759D03*
X861644D03*
X855644D03*
X858644D03*
X853514Y1457510D03*
X850644Y1457359D03*
X858644Y1467759D03*
X855644Y1470759D03*
X858644D03*
X864644Y1467759D03*
Y1470759D03*
X861644Y1467759D03*
Y1470759D03*
X855644Y1467759D03*
Y1473759D03*
X858644D03*
X864644D03*
X861644D03*
X855644Y1476759D03*
X858644D03*
X864644D03*
X861644D03*
X851457Y1639797D03*
X873373Y60922D03*
X868209Y55513D03*
X870519Y60438D03*
X870395Y96738D03*
X865402Y91951D03*
X865427Y88801D03*
X876200Y94374D03*
X868344Y94351D03*
X871341Y86046D03*
X871713Y172665D03*
Y180665D03*
Y168665D03*
Y176665D03*
Y196665D03*
Y192665D03*
X871826Y186778D03*
X871745Y200864D03*
Y212864D03*
Y204864D03*
Y208864D03*
Y216864D03*
Y221864D03*
X867386Y219379D03*
X876622Y293721D03*
X876246Y302754D03*
X872050Y302644D03*
X879112Y302369D03*
X877977Y305368D03*
Y309368D03*
Y313368D03*
Y325368D03*
Y317368D03*
Y321368D03*
X873885Y340892D03*
X877977Y333368D03*
Y329368D03*
X873733Y357844D03*
X872158Y359962D03*
X871382Y373971D03*
X868086Y373750D03*
X872736Y383125D03*
X876736D03*
X880736D03*
X867586Y385000D03*
X872318Y408589D03*
X869342Y407627D03*
X866128Y417532D03*
X869342Y417399D03*
X877253Y420380D03*
X876917Y415322D03*
X879417D03*
X881190Y411619D03*
X878690D03*
X874253Y422880D03*
X877253D03*
X881271Y426952D03*
X878771D03*
X873536Y437408D03*
X876036D03*
X881036D03*
X878536D03*
X873771Y426952D03*
X876271D03*
X870882Y458991D03*
X880910Y454634D03*
Y457434D03*
Y471982D03*
Y469182D03*
Y466382D03*
X870882Y465991D03*
Y468791D03*
X880910Y460234D03*
X870882Y461791D03*
X875907Y486256D03*
X867093Y554703D03*
X866938Y549771D03*
X874649Y545296D03*
X867093Y558703D03*
Y562703D03*
Y566703D03*
Y578703D03*
Y586828D03*
Y574703D03*
X876351Y605023D03*
Y608523D03*
X879135Y632552D03*
X870137Y669461D03*
X872862Y666859D03*
X869313Y688486D03*
X872069Y700894D03*
X876286Y686970D03*
Y690970D03*
X868919Y700894D03*
X876286Y694970D03*
Y698970D03*
X877616Y749484D03*
X878610Y747171D03*
X873318Y744597D03*
X881157Y749148D03*
X874142Y748914D03*
X875473Y742056D03*
X878670Y742841D03*
X869325Y761259D03*
X871294Y771809D03*
X867000Y774000D03*
X873250Y798750D03*
X867000Y792000D03*
X875916Y808965D03*
X874925Y800746D03*
X870035Y801032D03*
X867000Y810000D03*
X879916Y808965D03*
X872700Y816615D03*
X877407Y828017D03*
X877818Y824214D03*
X876475Y830372D03*
X878220Y848442D03*
Y845293D03*
Y835844D03*
Y851592D03*
X877800Y876500D03*
X872628Y915242D03*
X880628D03*
X872628Y918042D03*
X876628Y915242D03*
X880628Y918042D03*
X876628D03*
X868908Y933640D03*
X867199Y949372D03*
X865830Y961600D03*
X869390Y978003D03*
X865973Y978187D03*
X874066Y977928D03*
X875391Y993796D03*
X872183Y993980D03*
X878976Y994020D03*
X871069Y1023114D03*
X878927Y1022387D03*
X878783Y1018751D03*
X872845Y1018988D03*
X866906Y1018751D03*
X866887Y1023208D03*
X875887D03*
X878887Y1026762D03*
X872887D03*
X866887D03*
X873824Y1071604D03*
X871224D03*
X876424D03*
Y1074104D03*
X871224D03*
X873824D03*
X868624Y1071604D03*
Y1074104D03*
X870057Y1091604D03*
X875257D03*
Y1089104D03*
X870057D03*
X872657D03*
X880115Y1084666D03*
X867457Y1091604D03*
Y1089104D03*
X872657Y1091604D03*
X875375Y1107647D03*
X872675D03*
X870075D03*
X867475D03*
X871364Y1120636D03*
X873964D03*
X876564D03*
X879264D03*
X875376Y1110175D03*
X872676D03*
X870076D03*
X867476D03*
X871364Y1139336D03*
X868664D03*
X879264Y1130336D03*
X876564D03*
X873964D03*
X871364D03*
X870522Y1148080D03*
X868022D03*
X871624Y1213314D03*
X874624D03*
X871624Y1221714D03*
Y1218914D03*
Y1216114D03*
X874624Y1221714D03*
Y1218914D03*
Y1216114D03*
X872440Y1230083D03*
Y1227583D03*
X871624Y1224514D03*
X874624D03*
X872440Y1234483D03*
Y1236983D03*
X878004Y1224406D03*
X872440Y1243883D03*
Y1241383D03*
Y1248283D03*
Y1250783D03*
X875700Y1299700D03*
X872600Y1300833D03*
Y1298333D03*
X872944Y1432359D03*
Y1429359D03*
Y1426359D03*
X869944Y1432359D03*
Y1429359D03*
Y1426359D03*
X866944Y1432359D03*
Y1429359D03*
Y1426359D03*
X872944Y1435359D03*
Y1441359D03*
Y1438359D03*
X869944Y1435359D03*
X866944D03*
X869944Y1441359D03*
Y1438359D03*
X866944Y1441359D03*
Y1438359D03*
X870171Y1447459D03*
X881244Y1448859D03*
Y1440859D03*
X870171Y1452589D03*
Y1457719D03*
X867644Y1464759D03*
X870644D03*
X881244Y1464859D03*
Y1453059D03*
Y1456859D03*
X875744Y1453573D03*
X867644Y1467759D03*
X870644D03*
X867644Y1470759D03*
X870644D03*
X867644Y1473759D03*
X870644D03*
X867644Y1476759D03*
X870644D03*
X881244Y1476859D03*
X871457Y1639797D03*
X883233Y147540D03*
X887005Y141247D03*
X886011Y154100D03*
X895780Y237517D03*
Y232634D03*
X893284Y233339D03*
Y236739D03*
X891383Y243203D03*
X896034Y243307D03*
X886261Y252090D03*
X885741Y261150D03*
X887148Y249670D03*
X896953Y272012D03*
X895140Y265236D03*
X885918Y289500D03*
X885989Y309368D03*
Y305368D03*
Y317368D03*
X885953Y325368D03*
X885989Y313368D03*
X885953Y329368D03*
X886026Y346584D03*
X896592Y358369D03*
Y354369D03*
X883552Y357276D03*
X896592Y362369D03*
Y366369D03*
Y370369D03*
Y374369D03*
X884736Y383125D03*
X893736D03*
X888736D03*
X891251Y387484D03*
X887266Y400158D03*
Y405158D03*
Y402658D03*
X896579Y404043D03*
X893779D03*
X889979Y405743D03*
X894844Y418983D03*
X887770Y415290D03*
X890270D03*
X891699Y423245D03*
X897344Y418983D03*
X894519Y426952D03*
X889596Y437264D03*
X896388Y437614D03*
X887096Y437264D03*
X892019Y426952D03*
X897019D03*
X890903Y454634D03*
Y457434D03*
Y469182D03*
Y471982D03*
Y466382D03*
Y460234D03*
X882907Y480350D03*
X891454Y486303D03*
X896431Y534093D03*
X882891Y536122D03*
X892931Y534093D03*
X885931D03*
X896449Y550863D03*
X893949Y550363D03*
X891449Y547363D03*
X893949D03*
X886549Y553963D03*
X892023Y570176D03*
X882949Y557363D03*
X887417Y566713D03*
X890959Y579788D03*
X890956Y588325D03*
X894015Y588253D03*
X891673Y600049D03*
X895933Y618143D03*
X887949Y608863D03*
X894449Y606363D03*
X891933Y618143D03*
X883309Y666608D03*
X892461Y666671D03*
X886304Y666650D03*
X884903Y694119D03*
Y696678D03*
X884911Y690279D03*
X889436Y715970D03*
X886836D03*
X893241Y704656D03*
X883686Y729778D03*
X889525Y722060D03*
X882098Y741565D03*
X884976Y740891D03*
X884463Y744757D03*
X881637Y744154D03*
X883126Y766124D03*
X883413Y759855D03*
X889083Y780371D03*
X888545Y785528D03*
X888514Y797602D03*
X889763Y788159D03*
X891916Y799605D03*
X884002Y797616D03*
X891916Y808965D03*
X887916Y800815D03*
X895916Y808965D03*
X883916D03*
X887916D03*
X895829Y800660D03*
X883916Y800815D03*
X897118Y848442D03*
X881370Y835844D03*
X893968Y845293D03*
X884519Y848442D03*
X897118Y842143D03*
X893968D03*
X887669Y848442D03*
X886093Y835318D03*
X897118Y845293D03*
X893968Y838994D03*
X890818Y842143D03*
X893968Y835846D03*
X887669Y845293D03*
X890818D03*
X893968Y848442D03*
X884519Y845293D03*
X881370D03*
X884519Y842143D03*
X887669D03*
X881370Y848442D03*
X890818D03*
X897118Y857891D03*
Y864189D03*
Y854742D03*
X893968Y864189D03*
Y857891D03*
Y854742D03*
X887669Y851592D03*
X890818Y854742D03*
X887669D03*
X897118Y851592D03*
X890818Y864189D03*
Y857891D03*
X887669Y864189D03*
X884519Y854742D03*
Y851592D03*
Y857891D03*
X887669D03*
X890818Y851592D03*
X893967Y851591D03*
X881370Y851592D03*
X897118Y873638D03*
Y870488D03*
Y867338D03*
X893968Y870488D03*
Y873638D03*
Y867338D03*
X887669Y876787D03*
Y867338D03*
X890818Y870488D03*
X887669D03*
X897118Y876787D03*
X890818Y867338D03*
X881370D03*
X897118Y879937D03*
X884519Y873638D03*
X887669D03*
X884519Y876787D03*
X890818Y879937D03*
X881370Y876787D03*
X887669Y879937D03*
X884519Y867338D03*
X890818Y873638D03*
X893968Y876787D03*
Y879937D03*
X890818Y876787D03*
X884519Y879937D03*
Y870488D03*
X881370D03*
Y883086D03*
X884585Y886354D03*
X885126Y889742D03*
X881370Y886236D03*
X889178Y905619D03*
X884628Y915242D03*
Y918042D03*
X896553D03*
X892628Y915242D03*
X888628D03*
Y918042D03*
X882763Y933472D03*
X882609Y994245D03*
X888400Y994579D03*
X894660Y994330D03*
X891343Y994378D03*
X881887Y1023208D03*
X888743Y1019931D03*
X895394Y1026985D03*
X893147Y1020025D03*
X893887Y1023208D03*
X887887D03*
X890887Y1026762D03*
X884887D03*
X882779Y1074104D03*
Y1071604D03*
X887979Y1074104D03*
X885379D03*
X890579D03*
Y1071604D03*
X885379D03*
X887979D03*
X897056Y1091391D03*
X882615Y1084666D03*
X891055Y1095407D03*
X897056Y1095984D03*
X884906Y1102760D03*
X884890Y1098724D03*
X892856Y1102760D03*
X894249Y1114103D03*
X891549D03*
X888949D03*
X886349D03*
Y1123803D03*
X888949D03*
X891549D03*
X894249D03*
X895275Y1132870D03*
X892575D03*
X895547Y1145169D03*
X893190Y1208069D03*
X893328Y1212887D03*
X894887Y1227209D03*
X886888Y1263058D03*
X889388D03*
X891888D03*
X889388Y1260558D03*
X886888D03*
X891888D03*
X891003Y1292765D03*
X886926Y1298712D03*
X889729Y1295516D03*
X890738Y1311132D03*
X891107Y1314305D03*
X887342Y1314990D03*
X892244Y1449636D03*
Y1440859D03*
X889944Y1457959D03*
X889244Y1460859D03*
X895244Y1457510D03*
X893919Y1462132D03*
X889244Y1472859D03*
X891457Y1639797D03*
X898813Y146461D03*
X903035Y141247D03*
X897715Y152367D03*
X909772Y152562D03*
X899573Y158195D03*
X898851Y231496D03*
Y238583D03*
Y245669D03*
X910977Y238583D03*
Y243307D03*
X898851Y259843D03*
X898576Y253056D03*
X910977Y252756D03*
Y257480D03*
Y248032D03*
Y262205D03*
X898851Y274016D03*
X910977Y266929D03*
X898851D03*
X898048Y269387D03*
X912786Y306697D03*
X901848Y307782D03*
Y312738D03*
X910076Y304843D03*
X905120D03*
X913057Y311046D03*
X899352Y308560D03*
Y311960D03*
X909298Y302347D03*
X905898D03*
X909417Y323302D03*
X912278Y343881D03*
X913206Y336489D03*
X912085Y332335D03*
X898533Y334498D03*
X910040Y353532D03*
X908521Y356708D03*
X908625Y359317D03*
X898869Y351114D03*
X913288Y372752D03*
X911072Y386992D03*
X897736Y383125D03*
X901747Y398492D03*
Y403492D03*
Y400992D03*
X902169Y413002D03*
Y418002D03*
Y415502D03*
X905094Y424581D03*
X902594D03*
X907594D03*
X905212Y436734D03*
X902712D03*
X907712D03*
X907173Y440581D03*
X898888Y437614D03*
X907173Y443081D03*
X910250Y457262D03*
Y454462D03*
X907450D03*
Y457262D03*
X910250Y451662D03*
X907450D03*
X910779Y471380D03*
X910250Y460062D03*
X907450D03*
X910759Y475511D03*
X903431Y534093D03*
X906996Y530707D03*
X902459Y530755D03*
X899931Y534093D03*
X899530Y530753D03*
X911630Y543998D03*
X910578Y550186D03*
X909362Y555614D03*
X898156Y554812D03*
X913853Y561487D03*
X904393Y570176D03*
X908517D03*
X898815D03*
X899407Y560019D03*
X909024Y578394D03*
X898232Y588320D03*
X909024Y586768D03*
X902635Y588305D03*
X906999Y588274D03*
X909024Y574394D03*
X898207Y599891D03*
X908730Y619120D03*
X913686D03*
X899898Y619040D03*
X904854D03*
X900676Y621536D03*
X904076D03*
X909508Y621616D03*
X912908D03*
X900753Y656925D03*
X909265Y677795D03*
X910036Y702285D03*
X912462Y687770D03*
X906886Y702285D03*
X905313Y709259D03*
X910753Y715864D03*
X908699Y709387D03*
X902841Y703665D03*
X905050Y720268D03*
X910836Y721570D03*
X913858Y721289D03*
X907866Y795572D03*
X911028Y796598D03*
X913716Y800815D03*
X899916D03*
X911053Y800510D03*
X909785Y810778D03*
X903916Y810809D03*
X913716Y811954D03*
X899916Y808965D03*
X902641Y800748D03*
X907884Y829866D03*
X912864Y848442D03*
Y845293D03*
Y842143D03*
X909714Y845293D03*
Y842143D03*
Y838994D03*
X906565Y848442D03*
X900267D03*
X906565Y838994D03*
X900267Y838992D03*
X909714Y848442D03*
X906565Y842143D03*
X900267Y845293D03*
Y842143D03*
X906565Y845293D03*
X900266Y835844D03*
X900267Y864189D03*
X909714Y854742D03*
X906565Y857891D03*
X909714D03*
X906565Y864189D03*
X909714D03*
X906565Y854742D03*
X900267Y857891D03*
Y854742D03*
X912864Y851592D03*
Y864189D03*
Y857891D03*
Y854742D03*
X900267Y851592D03*
X906565D03*
X909714D03*
Y873638D03*
Y870488D03*
X906565Y873638D03*
Y870488D03*
Y867338D03*
X900267Y873638D03*
Y870488D03*
Y867338D03*
X909714D03*
X912864Y870488D03*
Y867338D03*
X909714Y876787D03*
X900267Y879937D03*
Y876787D03*
X906565D03*
X912864Y873638D03*
Y879937D03*
X909714D03*
X906565D03*
X912864Y876787D03*
X899693Y895207D03*
X908920Y905630D03*
X904833Y915340D03*
X912628Y928101D03*
X900628Y918042D03*
X912628Y915242D03*
X908628Y918042D03*
X900628Y915242D03*
X912628Y918042D03*
X904838D03*
X908628Y915242D03*
X911355Y944909D03*
X906710Y962433D03*
X903759Y951358D03*
X913005Y969605D03*
X912690Y994350D03*
X897825Y994413D03*
X909166Y994188D03*
X909296Y1020224D03*
X909300Y1014639D03*
X897717Y1019915D03*
X899887Y1023208D03*
Y1026762D03*
X908422Y1023103D03*
X908856Y1017677D03*
X901739Y1091346D03*
X897815Y1078042D03*
X901366Y1078069D03*
X901694Y1095940D03*
X908799Y1096659D03*
X911071Y1123803D03*
X905771D03*
X903171D03*
X908371D03*
X910971Y1114103D03*
X908271D03*
X903071D03*
X905671D03*
X911699Y1129488D03*
X909041Y1126328D03*
X911641D03*
X901428Y1136426D03*
X903908Y1132870D03*
X904063Y1135946D03*
X898278Y1136426D03*
X904897Y1145169D03*
X902397D03*
X898047D03*
X913784Y1221057D03*
X901940Y1236799D03*
Y1229899D03*
Y1232399D03*
X910633Y1222799D03*
X906309Y1226647D03*
X909077Y1232724D03*
X901940Y1246199D03*
Y1243699D03*
Y1239299D03*
X899699Y1283872D03*
X904703Y1297398D03*
X910788Y1299456D03*
X906506Y1299188D03*
X902908Y1299828D03*
X911117Y1314130D03*
X902875Y1309301D03*
X905740Y1309264D03*
X908700Y1316300D03*
X911135Y1345560D03*
X904177Y1359955D03*
X899944Y1432359D03*
X908944Y1426359D03*
Y1429359D03*
Y1432359D03*
X911944Y1426359D03*
Y1429359D03*
Y1432359D03*
X905944Y1426359D03*
X899944D03*
X902944D03*
Y1429359D03*
X899944D03*
X902944Y1432359D03*
X905944Y1429359D03*
Y1432359D03*
X902944Y1438359D03*
X899944D03*
Y1441359D03*
X902944Y1435359D03*
X899944D03*
X908944Y1438359D03*
Y1441359D03*
X911944Y1438359D03*
Y1441359D03*
X902944D03*
X905944Y1438359D03*
Y1441359D03*
X908944Y1435359D03*
X911944D03*
X905944D03*
X912171Y1447459D03*
X906671D03*
X901071D03*
X912171Y1457719D03*
Y1452589D03*
X906671Y1457719D03*
X901071D03*
Y1452589D03*
X908370Y1464583D03*
X905370D03*
X899370D03*
X902370D03*
X911370D03*
X905370Y1476583D03*
X908370D03*
X902370D03*
X899370D03*
X905370Y1473583D03*
X908370D03*
X902370D03*
X899370D03*
X902370Y1467583D03*
X899370Y1470583D03*
X902370D03*
X908370Y1467583D03*
Y1470583D03*
X905370Y1467583D03*
Y1470583D03*
X899370Y1467583D03*
X911370Y1476583D03*
Y1473583D03*
Y1467583D03*
Y1470583D03*
X911457Y1639797D03*
X930145Y3000D03*
X919175Y113394D03*
X921824Y110784D03*
X923393Y102249D03*
X927393D03*
X919175Y116594D03*
X921418Y133298D03*
X929418D03*
X919175Y119594D03*
X923565Y134579D03*
X918016Y161306D03*
X915267Y157370D03*
X925359Y180347D03*
X927859D03*
X916453Y167975D03*
X925219Y188564D03*
X927719D03*
X929978Y184054D03*
X927898Y203256D03*
X925098D03*
X919606Y231000D03*
X919577Y245669D03*
Y233858D03*
X919682Y236921D03*
X919577Y240945D03*
Y259843D03*
Y255118D03*
Y250394D03*
X919729Y274580D03*
X919577Y271654D03*
X919616Y268462D03*
X919577Y264567D03*
X920142Y308501D03*
X917882Y328216D03*
Y324816D03*
X926801Y323302D03*
X917906Y321670D03*
X917882Y328216D03*
Y324816D03*
X924564Y344041D03*
X915954Y344150D03*
X927964Y344041D03*
X919354Y344150D03*
X922629Y336609D03*
X922198Y342051D03*
X917858Y331453D03*
X923902Y332411D03*
X915954Y344150D03*
X916229Y336333D03*
X919354Y344150D03*
X919629Y336333D03*
X927964Y344041D03*
X924564D03*
X927309Y357267D03*
X921389D03*
X915395D03*
X921847Y346622D03*
X915395Y363212D03*
X927309Y363239D03*
Y369210D03*
X921468D03*
X915395D03*
X929943Y372600D03*
X927072Y386992D03*
X919072D03*
X923072D03*
X915072D03*
X914323Y398551D03*
Y403551D03*
Y401051D03*
X914202Y418002D03*
Y413002D03*
Y415502D03*
X927563Y424445D03*
X924763D03*
X921963D03*
X927280Y436716D03*
X921680D03*
X924480D03*
X917541Y441280D03*
X927636Y452505D03*
X929050Y450316D03*
X917541Y443780D03*
X928999Y477948D03*
X920999D03*
X924999D03*
X924600Y533706D03*
X920961Y550075D03*
X915949Y563363D03*
X923453Y569578D03*
X919080Y587640D03*
X921507Y578791D03*
X921217Y589216D03*
X913998Y597103D03*
X915712Y613792D03*
X925949Y612363D03*
Y608863D03*
X922626Y633772D03*
X915800Y629700D03*
X918300D03*
X915194Y666671D03*
X929690Y666593D03*
X920090Y666714D03*
X928043Y677795D03*
X917286Y679625D03*
X928353Y686342D03*
X928704Y680261D03*
X924932Y701051D03*
X921061Y715386D03*
X926961Y723797D03*
X914202Y797460D03*
X923872Y798271D03*
X916590Y800636D03*
X921790Y810965D03*
X922352Y800809D03*
X917803Y811365D03*
X927916Y800909D03*
Y817015D03*
X925228Y816934D03*
X919163Y848442D03*
X928612Y835844D03*
X922313Y845293D03*
X919163Y848442D03*
X916014D03*
Y842143D03*
X919163Y845293D03*
X922313Y842143D03*
X916014Y845293D03*
X919163Y835844D03*
Y838994D03*
Y842143D03*
X925462Y845293D03*
X919163Y851592D03*
X922313D03*
X929611Y858669D03*
X919163Y854742D03*
Y857891D03*
X922313Y854742D03*
X916014Y857891D03*
Y854742D03*
X919163Y851592D03*
X916014D03*
Y864189D03*
X925462Y851592D03*
X922313Y864189D03*
Y857891D03*
X925462D03*
X928612Y864189D03*
X919163D03*
X925462D03*
X916014Y870488D03*
X925462Y873638D03*
X922313Y876787D03*
X928612Y870488D03*
X925462D03*
X916014Y873638D03*
X922313D03*
X916014Y876787D03*
X928612Y873638D03*
X925462Y876787D03*
X928612D03*
Y879937D03*
X916014D03*
X922313D03*
X919163D03*
X925462D03*
X916014Y867338D03*
X919163Y873638D03*
Y870488D03*
X922313D03*
X919163Y876787D03*
X922313Y867338D03*
X919163D03*
X925462D03*
X922313Y883086D03*
Y886236D03*
X925462D03*
X919163Y883086D03*
X928612Y886236D03*
X925462Y883086D03*
X928612D03*
X921451Y903800D03*
X920628Y928101D03*
X928628D03*
X916628D03*
X924628D03*
X920628Y918042D03*
X924628D03*
Y915242D03*
X920628D03*
X928628D03*
X916628D03*
X914193Y945318D03*
X924487Y951244D03*
X928227Y951125D03*
X921364Y951251D03*
X918648Y964717D03*
X915490Y969886D03*
X918265Y969745D03*
X923289Y965780D03*
X926796Y966297D03*
X916932Y994405D03*
X924864Y1026762D03*
X925024Y1018909D03*
X927861Y1024768D03*
X916749Y1080659D03*
Y1088659D03*
Y1084659D03*
X916992Y1076659D03*
X917110Y1101902D03*
X916875Y1098643D03*
X916749Y1104659D03*
X927598Y1120636D03*
X924898D03*
X914661Y1132612D03*
X914299Y1129488D03*
X914241Y1126328D03*
X924919Y1130336D03*
X927619D03*
X924919Y1139336D03*
X927419D03*
X925097Y1147708D03*
X927597D03*
X914637Y1210568D03*
Y1214838D03*
X927146Y1328597D03*
Y1323641D03*
X924650Y1327819D03*
Y1324419D03*
X914033Y1345613D03*
X927193Y1361547D03*
X920255Y1383264D03*
X914944Y1426359D03*
Y1429359D03*
Y1432359D03*
Y1438359D03*
Y1441359D03*
Y1435359D03*
X921498Y1446692D03*
X914370Y1464583D03*
X925697Y1460109D03*
X920244Y1451605D03*
X919285Y1456226D03*
X914370Y1476583D03*
Y1473583D03*
Y1467583D03*
Y1470583D03*
X924803Y1474743D03*
X925435Y1478114D03*
X926044Y1545370D03*
Y1542370D03*
X929094Y1542353D03*
Y1545353D03*
X926041Y1554503D03*
Y1551503D03*
Y1548503D03*
Y1557503D03*
Y1560503D03*
X941129Y4469D03*
X942490Y24773D03*
Y44773D03*
X945011Y95111D03*
X942561Y118342D03*
X944961Y116497D03*
X934410Y109172D03*
X936417Y106495D03*
X937410Y109172D03*
X940161Y116497D03*
X931144Y116594D03*
X936417Y102495D03*
X942561Y121742D03*
Y132515D03*
Y135915D03*
X940161Y123584D03*
X944961D03*
X940161Y130670D03*
X944961D03*
X931144Y119594D03*
X942561Y118342D03*
Y132515D03*
Y121742D03*
X940161Y137757D03*
X944961D03*
X936151Y146012D03*
X938057Y141228D03*
X942561Y135915D03*
X936151Y142862D03*
X940945Y150847D03*
X930359Y180347D03*
X945406D03*
X940406D03*
X942906D03*
X931407Y192009D03*
X933907D03*
X944424Y186919D03*
X944760Y191977D03*
X942260D03*
X940487Y195680D03*
X942987D03*
X944424Y184419D03*
X934411Y202141D03*
X931698Y201556D03*
X934411Y207141D03*
X934477Y211491D03*
X934411Y204641D03*
X938125Y230891D03*
X942805Y223860D03*
X936369Y221292D03*
X936395Y218142D03*
X940158Y245707D03*
X933403Y245507D03*
X946064Y252998D03*
X941845Y278968D03*
X945018Y276051D03*
X943183Y281652D03*
X939606Y310521D03*
X930727Y302571D03*
X937000Y312284D03*
X939331Y324044D03*
X942731D03*
X939653Y317474D03*
X940924Y328959D03*
X936608Y326058D03*
X945120Y326441D03*
X937000Y315684D03*
X942731Y324044D03*
X939331D03*
X940997Y335312D03*
Y331912D03*
X939300Y346363D03*
X942700D03*
X932388Y330517D03*
X930398Y342050D03*
X936453Y345336D03*
X945599Y345383D03*
X940972Y338238D03*
X932622Y336817D03*
X940997Y331912D03*
Y335312D03*
X943663Y355674D03*
X944694Y352192D03*
X942700Y346363D03*
X939300D03*
X934464Y358618D03*
X944900Y363700D03*
X938499Y362202D03*
X940600Y370600D03*
X934047Y369160D03*
X931072Y386992D03*
X941872Y440942D03*
X941505Y463442D03*
X939827Y531104D03*
X939992Y536726D03*
X936653Y526836D03*
X944351Y534211D03*
X939992Y527726D03*
Y540726D03*
Y552726D03*
Y548726D03*
X931627Y561578D03*
Y565578D03*
Y557641D03*
Y569578D03*
X943825Y581222D03*
X931620Y584417D03*
X931627Y581578D03*
Y577578D03*
Y573578D03*
X933725Y585936D03*
X943825Y591215D03*
X931594Y599420D03*
X931647Y593271D03*
X931578Y590669D03*
X933741Y598087D03*
Y594687D03*
X933725Y589336D03*
X944296Y611071D03*
X941859Y621311D03*
Y629311D03*
X943181Y632536D03*
X945434Y634325D03*
X941859Y625311D03*
X946128Y666522D03*
X935281Y680945D03*
X931244Y720471D03*
X936026Y730600D03*
Y727450D03*
X933974Y719371D03*
X945626Y789761D03*
X942676Y789286D03*
X941916Y808965D03*
X944916D03*
X932000Y831000D03*
X931916Y817015D03*
X942858Y819430D03*
X945736Y819397D03*
X935124Y831382D03*
X935262Y825135D03*
X932418D03*
X940716Y840074D03*
X944297Y839975D03*
X933021Y840893D03*
X933054Y843804D03*
X937200Y841000D03*
X936450Y858327D03*
X937551Y860801D03*
X932770Y878233D03*
X935765Y878317D03*
X934928Y871727D03*
X932319Y871626D03*
X945982Y886737D03*
X942634Y886520D03*
X933700Y887508D03*
X945982Y886737D03*
X932300Y890200D03*
X944839Y902400D03*
X938188Y900853D03*
X930800Y904840D03*
X941592Y900908D03*
X932628Y928101D03*
X936628D03*
X940497D03*
X936628Y915242D03*
X940628D03*
X932628D03*
X936628Y918042D03*
X932628D03*
X936371Y951484D03*
X940716Y951733D03*
X946363Y951179D03*
X935255Y962725D03*
X940015Y1020176D03*
X934911Y1023579D03*
X945864Y1023208D03*
X930864Y1026762D03*
X936864D03*
X942864D03*
X939864Y1023208D03*
X930864D03*
X930883Y1018751D03*
X936822Y1018988D03*
X942760Y1018751D03*
X932289Y1074182D03*
Y1071682D03*
X937489Y1074182D03*
X934889D03*
X940089D03*
Y1071682D03*
X934889D03*
X937489D03*
X944092Y1084666D03*
X931628Y1091409D03*
Y1088909D03*
X936828Y1091409D03*
X934228D03*
X939428D03*
Y1088909D03*
X934228D03*
X936828D03*
X943241Y1120636D03*
X940541D03*
X937941D03*
X935341D03*
X937941Y1130336D03*
X940541D03*
X943241D03*
X932641Y1139336D03*
X935341Y1130336D03*
Y1139336D03*
X934500Y1147708D03*
X932000D03*
X935601Y1221714D03*
Y1218914D03*
Y1216114D03*
Y1213314D03*
X938601Y1221714D03*
Y1218914D03*
Y1216114D03*
Y1213314D03*
X936417Y1234483D03*
Y1236983D03*
Y1230083D03*
Y1227583D03*
X935601Y1224514D03*
X938601D03*
X941981Y1224406D03*
X936417Y1243883D03*
Y1241383D03*
Y1248283D03*
Y1250783D03*
X933254Y1308273D03*
X940848Y1310181D03*
X943891Y1306608D03*
X931137Y1375878D03*
X931159Y1383227D03*
Y1394627D03*
Y1387027D03*
Y1398427D03*
Y1402227D03*
X939559D03*
X943725Y1430744D03*
Y1427744D03*
X934725Y1430744D03*
X940725Y1427744D03*
Y1430744D03*
X934725Y1427744D03*
X937725D03*
Y1430744D03*
X943725Y1433744D03*
Y1439744D03*
Y1436744D03*
X940725Y1433744D03*
Y1439744D03*
Y1436744D03*
X934725Y1433744D03*
X937725D03*
X934725Y1439744D03*
X937725D03*
X934725Y1436744D03*
X937725D03*
X930441Y1455039D03*
Y1458039D03*
Y1464039D03*
Y1461039D03*
Y1467039D03*
X937671Y1488139D03*
X938670Y1510528D03*
X941270D03*
Y1505328D03*
X938670D03*
X940170Y1507928D03*
X943870Y1510528D03*
Y1505328D03*
X945370Y1507928D03*
X942770D03*
X935094Y1542353D03*
X932094D03*
X935094Y1545353D03*
X932094D03*
X938094Y1542353D03*
Y1545353D03*
X941094Y1542353D03*
X944094D03*
X941094Y1545353D03*
X944094D03*
X931457Y1639797D03*
X956448Y-30304D03*
Y-33204D03*
X956460Y-35982D03*
X953207Y-35996D03*
X956445Y-38497D03*
X953192Y-38511D03*
X950167Y-37191D03*
X953192Y-25085D03*
X956445Y-25099D03*
X950167Y-26405D03*
X953207Y-27600D03*
X956460Y-27614D03*
X949811Y53597D03*
X960623Y82984D03*
Y77784D03*
Y80384D03*
Y75184D03*
Y85584D03*
X960161Y95236D03*
X949861Y114655D03*
Y111255D03*
X960161Y102323D03*
X960413Y109410D03*
Y116496D03*
X947461Y116497D03*
X952161Y116496D03*
Y109410D03*
Y102323D03*
X947461Y109410D03*
X949861Y111255D03*
Y114655D03*
X949380Y106561D03*
X949861Y128828D03*
Y125428D03*
X961638Y130670D03*
X947461D03*
X952161D03*
Y123583D03*
X947461D03*
X949861Y125428D03*
Y128828D03*
X961633Y137756D03*
X952161D03*
X947906Y180347D03*
X949359Y198710D03*
X947424Y187219D03*
X949443Y208206D03*
X951040Y223885D03*
X947040D03*
X951278Y250583D03*
X946482Y255940D03*
X949974Y291554D03*
X947733Y319680D03*
X949579Y330517D03*
X949813Y336817D03*
X956348Y356371D03*
X952170Y356131D03*
X958823Y362802D03*
X954888Y369513D03*
X948400Y370045D03*
X960376Y392807D03*
X956863Y451466D03*
X950315Y464851D03*
X959816Y472905D03*
X955816Y473419D03*
X949823Y487982D03*
X949876Y478486D03*
X949823Y483982D03*
X962563Y485128D03*
X954182Y481467D03*
X949823Y499982D03*
X958974Y504825D03*
X956474D03*
X953974D03*
X949823Y491982D03*
Y495982D03*
X958915Y517401D03*
X956415D03*
X953915D03*
X959466Y522569D03*
Y525369D03*
X958081Y531882D03*
X955581D03*
X961166Y529169D03*
X952531Y531948D03*
X960581Y531882D03*
X953816Y555194D03*
X951016D03*
X958016D03*
X960816D03*
X953816Y571194D03*
X951016D03*
X953816Y563194D03*
X951016D03*
X958016D03*
X960816D03*
Y571194D03*
X958016D03*
X946625Y581222D03*
X949425D03*
X959573D03*
X962373D03*
X949425Y591215D03*
X946625D03*
X959573D03*
X962373D03*
X948427Y611091D03*
X962545Y607762D03*
X959745D03*
Y610562D03*
X962545D03*
X950865Y641817D03*
X949137Y666660D03*
X954526Y666671D03*
X957551Y698251D03*
X947556Y699550D03*
X954023Y725336D03*
X951195Y727165D03*
X952681Y735256D03*
X951151Y730111D03*
X959950Y734178D03*
X956323Y748412D03*
X957474Y764426D03*
X955086Y779798D03*
X956017Y770300D03*
X957500Y780800D03*
X956051Y793937D03*
X955076Y784861D03*
X950475Y789361D03*
X955225Y788984D03*
X951461Y812223D03*
X951791Y808121D03*
X947735Y824921D03*
X957379Y826586D03*
X954760Y826734D03*
X951708Y818894D03*
X956239Y829577D03*
X948935Y835800D03*
X954700Y842700D03*
X960100Y846665D03*
X954700Y837700D03*
X961175Y838525D03*
X947735Y854935D03*
X953091Y857440D03*
X953217Y861440D03*
X955967Y860376D03*
X946700Y849200D03*
X955850Y862902D03*
X957900Y856300D03*
X950251Y874268D03*
X950291Y870240D03*
Y866240D03*
X953145Y874240D03*
X950300Y877800D03*
X953240Y876834D03*
X949382Y886737D03*
X952738Y886624D03*
X949382Y886737D03*
X953587Y902814D03*
X950567Y927654D03*
X961479Y927643D03*
X954567Y927654D03*
X947029Y915242D03*
X946642Y991361D03*
X961671Y991564D03*
X953671D03*
X949671D03*
X948864Y1026762D03*
X954864D03*
X951864Y1023208D03*
X957864D03*
X957678Y1018555D03*
X961208Y1018592D03*
X960636Y1021917D03*
X959371Y1026985D03*
X948975Y1021325D03*
X951956Y1071604D03*
X949356D03*
X954556D03*
Y1074104D03*
X949356D03*
X951956D03*
X946756Y1071604D03*
Y1074104D03*
X961033Y1091391D03*
X946592Y1084666D03*
X948883Y1102760D03*
X948867Y1098724D03*
X955032Y1095407D03*
X961033Y1095984D03*
X956833Y1102760D03*
X950326Y1114103D03*
Y1123803D03*
X952926D03*
X955526D03*
Y1114103D03*
X958226D03*
X952926D03*
X958226Y1123803D03*
X956552Y1132870D03*
X959252D03*
X962255Y1136426D03*
X962024Y1145169D03*
X959524D03*
X957305Y1212887D03*
X957167Y1208069D03*
X958864Y1227209D03*
X950865Y1263058D03*
X953365D03*
X955865D03*
X953365Y1260558D03*
X950865D03*
X955865D03*
X948259Y1295965D03*
X949970Y1321749D03*
X952070Y1367717D03*
X949070D03*
X948832Y1371654D03*
X951832D03*
X952561Y1383465D03*
X952417Y1379528D03*
X949469D03*
X949385Y1375591D03*
X952385D03*
X952514Y1391339D03*
X952716Y1387402D03*
X952180Y1407087D03*
X950239Y1409555D03*
X948235Y1406262D03*
X946725Y1427744D03*
Y1430744D03*
X949725D03*
Y1427744D03*
X960883Y1427997D03*
Y1430997D03*
X946725Y1433744D03*
X949725D03*
X946725Y1439744D03*
X949725D03*
X946725Y1436744D03*
X949725D03*
X960883Y1433997D03*
Y1436997D03*
Y1439997D03*
X952695Y1444139D03*
X956238Y1455139D03*
Y1458139D03*
Y1461139D03*
Y1464139D03*
X952676Y1461039D03*
Y1464039D03*
Y1458039D03*
Y1455039D03*
X956238Y1467139D03*
Y1469902D03*
X952676Y1467039D03*
X946470Y1510528D03*
Y1505328D03*
X956035Y1545333D03*
X959035D03*
X953035D03*
X950035D03*
X959035Y1542333D03*
X956035D03*
X953035D03*
X950035D03*
X947094Y1545353D03*
Y1542353D03*
X951457Y1639797D03*
X978036Y-77691D03*
Y-64265D03*
X978051Y-75176D03*
X975011Y-76371D03*
Y-65585D03*
X978051Y-66780D03*
X969811Y53597D03*
X963177Y92849D03*
X970094Y95236D03*
X978271Y109410D03*
Y102323D03*
X970137Y103037D03*
X970271Y116496D03*
Y109410D03*
X978271Y116496D03*
X970271Y130670D03*
Y123583D03*
X978271Y130670D03*
Y123583D03*
X963360Y121459D03*
X966347Y137756D03*
X978271D03*
X978051Y162368D03*
X968906Y207978D03*
Y212978D03*
Y215478D03*
Y210478D03*
Y223726D03*
Y228726D03*
Y231226D03*
Y226226D03*
X970865Y264068D03*
X973365D03*
X972160Y258880D03*
X974952Y293796D03*
X972452D03*
X976763Y307303D03*
X972147Y323681D03*
X977150Y328472D03*
X973338Y345018D03*
X977150Y335472D03*
Y331972D03*
Y338972D03*
X975631Y346612D03*
X969623Y405614D03*
X971721Y407762D03*
X968348Y402369D03*
X963577Y426391D03*
X975932Y437508D03*
X971932D03*
X971826Y430187D03*
X966694Y427599D03*
X968462Y429368D03*
X962769Y458466D03*
X973695Y448874D03*
X969109Y449352D03*
X970840Y457339D03*
X968340D03*
X962816Y442919D03*
X967816Y472905D03*
X972397Y472954D03*
X970840Y459839D03*
Y462339D03*
X968340D03*
Y459839D03*
X963816Y472905D03*
X976397Y473045D03*
X965412Y485138D03*
X969297Y478625D03*
Y475825D03*
X970997Y482425D03*
X970412Y485138D03*
X967912D03*
X976873Y491214D03*
X973843Y500086D03*
X978723Y504699D03*
X976223D03*
X973723D03*
X976873Y493714D03*
X978425Y516979D03*
X973425D03*
X974406Y521804D03*
X975925Y516979D03*
X978668Y527449D03*
X974406Y524304D03*
X970713Y531378D03*
Y528878D03*
X970745Y539731D03*
X967042Y537658D03*
X964012Y546830D03*
X970745Y542231D03*
X978303Y541895D03*
X975803D03*
X967042Y540458D03*
X975503Y544895D03*
X978581Y572975D03*
Y582747D03*
X965173Y581222D03*
Y591215D03*
X976962Y608311D03*
X976027Y620653D03*
Y617853D03*
X968145Y610562D03*
X965345Y607762D03*
Y610562D03*
X968145Y607762D03*
X977857Y605443D03*
X973857D03*
X967302Y627948D03*
X969491Y629362D03*
X978865Y642184D03*
X963187Y667620D03*
X973138Y667621D03*
X966797Y667653D03*
X970197D03*
X965774Y706907D03*
X973712Y722064D03*
X968589Y722434D03*
X970839Y729923D03*
X965042Y722234D03*
X971081Y722637D03*
X978352Y730766D03*
X963950Y734178D03*
X978059Y747438D03*
X965983Y763567D03*
X966127Y776382D03*
X976764Y786563D03*
X968094Y799792D03*
X976186Y789819D03*
X964070Y807686D03*
Y813006D03*
X977218Y802178D03*
X967562Y802982D03*
X964036Y818961D03*
X968319Y826191D03*
X978214Y821224D03*
X967337Y828901D03*
X976635Y835018D03*
X976800Y838011D03*
X974282D03*
X976902Y847135D03*
X970040Y842903D03*
X969309Y839334D03*
X971808Y851242D03*
X975925Y854783D03*
X967510Y868971D03*
X978201Y897500D03*
X971144Y908972D03*
X972278Y934429D03*
X968507Y937615D03*
X971443Y938828D03*
X969806Y993033D03*
X965671Y991564D03*
X963864Y1026762D03*
Y1023208D03*
X965716Y1091346D03*
X965671Y1095940D03*
X972776Y1096659D03*
X967148Y1123803D03*
X969748D03*
X969648Y1114103D03*
X967048D03*
X972348Y1123803D03*
X975048D03*
X972248Y1114103D03*
X974948D03*
X965405Y1136426D03*
X970485Y1132870D03*
X967885D03*
X968874Y1145169D03*
X966374D03*
X978614Y1210568D03*
Y1214838D03*
X978169Y1221268D03*
X965917Y1236799D03*
Y1229899D03*
Y1232399D03*
Y1246199D03*
Y1243699D03*
Y1239299D03*
X978727Y1284908D03*
X978857Y1360945D03*
X963883Y1430997D03*
Y1427997D03*
X966883Y1430997D03*
Y1427997D03*
X969883D03*
Y1430997D03*
X975883Y1427997D03*
Y1430997D03*
X972883D03*
Y1427997D03*
X963883Y1433997D03*
X966883D03*
X969883D03*
X963883Y1436997D03*
Y1439997D03*
X966883Y1436997D03*
Y1439997D03*
X969883Y1436997D03*
Y1439997D03*
X975883Y1433997D03*
X972883D03*
X975883Y1436997D03*
X972883D03*
X975883Y1439997D03*
X972883D03*
X971467Y1509515D03*
X974067D03*
X972567Y1512115D03*
X969967D03*
X976667Y1509515D03*
X977767Y1506915D03*
X975167D03*
X969967D03*
X972567D03*
X975167Y1512115D03*
X977767D03*
X971140Y1514693D03*
X968540D03*
X973740D03*
X976340D03*
X977547Y1546081D03*
X974547D03*
X971547D03*
X971457Y1639797D03*
X981289Y-77677D03*
Y-64279D03*
X981292Y-69484D03*
Y-72384D03*
X981304Y-75162D03*
Y-66794D03*
X988606Y5374D03*
X987919Y24773D03*
Y44773D03*
X978958Y85193D03*
Y82593D03*
Y77393D03*
Y74793D03*
Y79993D03*
X983554Y94017D03*
X987554D03*
X991554D03*
X987283Y101701D03*
Y98551D03*
X990178Y111223D03*
Y114623D03*
D03*
Y111223D03*
X987682Y115401D03*
X992674D03*
Y110445D03*
X987682D03*
X994833Y103783D03*
X990833D03*
X981029Y104249D03*
Y107649D03*
X990178Y125396D03*
Y128796D03*
D03*
Y125396D03*
X992674Y124618D03*
X987682D03*
Y129574D03*
X992674D03*
X985595Y147540D03*
X989367Y141247D03*
X985595Y151540D03*
X980651Y162368D03*
X987751Y162793D03*
Y165393D03*
Y167993D03*
Y170493D03*
X989959Y181366D03*
X986748Y181426D03*
X992754Y181009D03*
X989245Y191941D03*
X986956Y184221D03*
X989573Y184012D03*
X994695Y213132D03*
X979362Y208213D03*
Y210713D03*
Y213213D03*
X983434Y208695D03*
X985934Y211695D03*
X990992Y213859D03*
Y211359D03*
X983434Y211695D03*
X987331Y229286D03*
X991024Y224712D03*
Y222212D03*
X983069Y226141D03*
X979362Y231461D03*
Y228961D03*
Y226461D03*
Y215713D03*
X994695Y215632D03*
X987331Y231786D03*
X985812Y236611D03*
X988312D03*
X983312D03*
X983014Y248891D03*
X988014D03*
X985514D03*
X990939Y256535D03*
X994939Y256303D03*
X986429Y270026D03*
X983929D03*
X981129D03*
X983929Y267526D03*
X986429D03*
X981129D03*
X985766Y288190D03*
X982966D03*
X985766Y285690D03*
X982966D03*
X980466Y288190D03*
Y285690D03*
X993992Y290755D03*
X989992D03*
X993132Y310942D03*
X993243Y321325D03*
X987055Y320273D03*
X993920Y335454D03*
X993420Y337954D03*
X990420Y340454D03*
Y337954D03*
X992045Y366559D03*
X984045D03*
X988045D03*
X980045D03*
X991392Y409230D03*
X979932Y437508D03*
X982792Y447269D03*
X982670Y450201D03*
X980397Y473045D03*
X985303Y464652D03*
Y462152D03*
Y459652D03*
X987803Y464652D03*
Y462152D03*
Y459652D03*
X992206Y478586D03*
Y481086D03*
X980544Y482134D03*
Y484634D03*
X992206Y476086D03*
X988499Y480705D03*
X983989Y475946D03*
Y478446D03*
X992206Y491133D03*
Y498633D03*
X988134Y495151D03*
X985634D03*
X980576Y492987D03*
Y495487D03*
X988134Y498151D03*
X992206Y493633D03*
Y496133D03*
X982375Y522129D03*
X989936Y519531D03*
X987436D03*
X982436D03*
X984936D03*
X982375Y527129D03*
Y524629D03*
X989068Y532949D03*
X982375Y537877D03*
X992306Y555897D03*
Y553297D03*
X989888Y548366D03*
X987388D03*
X982388D03*
X984888D03*
X982375Y542877D03*
Y545377D03*
Y540377D03*
X981795Y572842D03*
X992306Y561097D03*
Y563697D03*
Y558497D03*
X986301Y570686D03*
X989096Y570478D03*
X985903Y579475D03*
X985357Y585507D03*
X989950D03*
X989513Y576484D03*
X989156Y573689D03*
X986510Y573303D03*
X985401Y590145D03*
X989995Y590190D03*
X981857Y597232D03*
X989857Y605443D03*
X983843Y619513D03*
Y616713D03*
Y613913D03*
X993857Y605443D03*
X981857Y605637D03*
X983843Y633205D03*
Y636005D03*
X980703Y625013D03*
X983843Y638805D03*
X983712Y722064D03*
X984307Y748432D03*
X981876Y745179D03*
X988371Y764143D03*
X983786Y765647D03*
X985030Y781204D03*
X988329Y781445D03*
X991990Y773974D03*
X984963Y785387D03*
X979313Y814316D03*
X987501Y812573D03*
X987903Y818645D03*
X979203Y829159D03*
X982300Y821200D03*
X993061Y833135D03*
X979203Y837159D03*
X989700Y846500D03*
X987202Y846395D03*
X987319Y843589D03*
X979203Y833159D03*
X989800Y843900D03*
X987200Y848940D03*
X988820Y858903D03*
X990457Y852043D03*
X983269Y853883D03*
X981700Y856300D03*
X980529Y879097D03*
X988231Y878203D03*
X984892Y868720D03*
X979891Y876589D03*
X987790Y896596D03*
X995133Y888503D03*
X988054Y888283D03*
X990300Y897500D03*
X982787Y899757D03*
X979592Y902849D03*
X982783Y909995D03*
X979498Y907500D03*
X989311Y920364D03*
X983227Y968565D03*
X988461Y1013841D03*
X988240Y1020015D03*
Y1016923D03*
Y1023968D03*
X980726Y1080659D03*
Y1088659D03*
X984909Y1081071D03*
X983751Y1078675D03*
X980969Y1076659D03*
X980726Y1084659D03*
X981087Y1101902D03*
X980852Y1098643D03*
X980726Y1104659D03*
Y1092664D03*
X986645Y1108465D03*
X989513Y1097683D03*
X995009Y1131223D03*
X991763Y1140378D03*
Y1128378D03*
Y1134378D03*
X984558Y1140774D03*
X988112Y1137774D03*
X984558Y1128774D03*
Y1134774D03*
X987804Y1131619D03*
X988389Y1302558D03*
X984817Y1303297D03*
X979001Y1288925D03*
X990613Y1324248D03*
Y1327048D03*
X993413Y1324248D03*
Y1327048D03*
X990501Y1320756D03*
X981857Y1360945D03*
X988784Y1361974D03*
X980501Y1369685D03*
X983501D03*
X980139Y1381496D03*
X980166Y1373622D03*
X980203Y1377559D03*
X980047Y1397245D03*
X980092Y1389370D03*
X980139Y1393308D03*
X978944Y1413859D03*
X981944D03*
X984136Y1401636D03*
X987136D03*
X986949Y1430997D03*
Y1427997D03*
X983949D03*
X989949Y1430997D03*
Y1427997D03*
X983949Y1430997D03*
X992949Y1427997D03*
Y1430997D03*
X986949Y1433997D03*
X983949D03*
X989949D03*
X992949D03*
X986949Y1436997D03*
X983949D03*
X986949Y1439997D03*
X983949D03*
X989949Y1436997D03*
Y1439997D03*
X992949Y1436997D03*
Y1439997D03*
X978934Y1444392D03*
X979538Y1464039D03*
Y1461039D03*
Y1458039D03*
Y1455039D03*
Y1467039D03*
Y1469802D03*
X978987Y1489832D03*
X979267Y1509515D03*
X984467D03*
X981867D03*
X985567Y1512115D03*
Y1506915D03*
X980367D03*
X982967D03*
Y1512115D03*
X980367D03*
X989667Y1509515D03*
X992267D03*
X987067D03*
X988167Y1512115D03*
X990767D03*
Y1506915D03*
X988167D03*
X984140Y1514693D03*
X981540D03*
X978940D03*
X986740D03*
X989340D03*
X986773Y1546081D03*
X983773D03*
X980773D03*
X991457Y1639797D03*
X1011187Y-43526D03*
X1005256Y-48539D03*
X1002003D03*
X1005241Y-46024D03*
X1001988D03*
X1008281Y-47219D03*
X1011187Y-33526D03*
Y-40126D03*
Y-30126D03*
X1002000Y-40834D03*
X1005256Y-38239D03*
X1002003Y-38225D03*
X1002000Y-43334D03*
X1005241Y-35724D03*
X1002000Y-32720D03*
X1001988Y-35710D03*
X1002000Y-30120D03*
X1008281Y-36919D03*
X1011187Y-33526D03*
Y-30126D03*
Y-43526D03*
Y-40126D03*
X1005256Y-25113D03*
X1002003Y-25027D03*
X1005241Y-27628D03*
X1001988Y-27542D03*
X1008281Y-26433D03*
X1007508Y3000D03*
X1011284Y68581D03*
X1000631Y84140D03*
Y76140D03*
Y80140D03*
X1011297Y80581D03*
X1003379Y72615D03*
Y76587D03*
X995563Y94017D03*
X1000580Y118335D03*
X1006000Y103621D03*
X1003076Y117557D03*
X998084D03*
X997768Y106186D03*
X1009191Y112083D03*
X1000580Y132509D03*
Y121735D03*
Y135909D03*
Y121735D03*
Y118335D03*
Y132509D03*
X1003076Y122513D03*
Y131731D03*
X998084Y122513D03*
Y131731D03*
X1000580Y135909D03*
X1001175Y146461D03*
X1003076Y136687D03*
X998084D03*
X1000077Y152367D03*
X1001777Y180572D03*
X1006460Y180527D03*
X997929Y168697D03*
X1010183Y192421D03*
X1001777Y185165D03*
X1006415Y185121D03*
X995745Y184619D03*
X999017Y191941D03*
X1003029Y192300D03*
X997725Y206760D03*
X1003526Y206767D03*
X1006026D03*
X1001026D03*
X1010291Y199582D03*
X1002271Y228221D03*
Y231021D03*
X1010506Y221642D03*
X1003656Y221708D03*
X1006156D03*
X1000571Y224421D03*
X1001156Y221708D03*
X1002822Y236189D03*
X1005322D03*
X1007822D03*
X998939Y256535D03*
X1002763Y248765D03*
X1005263D03*
X1007763D03*
X999826Y278734D03*
X1008260Y268195D03*
X1005460D03*
X1002960D03*
X1008260Y270695D03*
X1002960D03*
X1005460D03*
X1008563Y293645D03*
X1006063D03*
Y290845D03*
Y288345D03*
X1008563Y290845D03*
Y288345D03*
X1004635Y300276D03*
X1008635D03*
X1000698D03*
X1010499Y309062D03*
X998667Y322239D03*
X1004544Y318050D03*
X1004933Y314535D03*
X997921Y333654D03*
X1009770Y344486D03*
X997020Y345354D03*
X1003076Y332496D03*
X1000420Y348954D03*
Y353954D03*
X996024Y352132D03*
X1001825Y581659D03*
X997857Y605443D03*
X995913Y619758D03*
Y616958D03*
Y614158D03*
X1001857Y605443D03*
X995913Y633450D03*
Y636250D03*
X1003900Y628700D03*
X1001605Y627605D03*
X1005800Y637600D03*
X1002883Y622521D03*
X995913Y639050D03*
X1001676Y678015D03*
X1011185Y724519D03*
X1009562Y722438D03*
X1008342Y761735D03*
X1003539Y762632D03*
X1003990Y765899D03*
X1002751Y757169D03*
X1002834Y777394D03*
X1007027Y792973D03*
X998376Y810970D03*
X999825Y819488D03*
X1002699Y819475D03*
X1002887Y834342D03*
X1000369D03*
X1011144Y844340D03*
X1010977Y841737D03*
X1004577Y853679D03*
X1005607Y874859D03*
Y877859D03*
X1004713Y871389D03*
X998313Y888295D03*
X1002930Y906785D03*
X1004953Y923995D03*
X1008935Y924007D03*
X1010119Y933822D03*
X1004994Y955372D03*
X1007919Y948822D03*
X1011019D03*
X1004719D03*
X1006222Y980337D03*
X1010009Y998100D03*
X1005301Y1006560D03*
X999879Y998507D03*
X999700Y1018400D03*
X1008759Y1023900D03*
X995317Y1137378D03*
X996213Y1324248D03*
Y1327048D03*
X1009333Y1346693D03*
Y1343293D03*
X1008312Y1363533D03*
X1008452Y1376752D03*
X1008483Y1372734D03*
X1008387Y1380797D03*
X998600Y1373400D03*
X997401Y1381200D03*
X1007850Y1368835D03*
X1006211Y1397662D03*
X1009338Y1391597D03*
Y1388597D03*
X1008138Y1407186D03*
Y1409986D03*
X1005338Y1407186D03*
Y1409986D03*
X1008138Y1415586D03*
Y1412786D03*
X1005338Y1415586D03*
Y1412786D03*
X1008138Y1418386D03*
X1005338D03*
X998949Y1427997D03*
Y1430997D03*
X995949D03*
Y1427997D03*
X1009981Y1431097D03*
Y1428097D03*
X1006981D03*
Y1431097D03*
X998949Y1433997D03*
X995949D03*
X998949Y1436997D03*
X995949D03*
X998949Y1439997D03*
X995949D03*
X1009981Y1434097D03*
X1006981D03*
X1009981Y1437097D03*
X1006981D03*
X1009981Y1440097D03*
X1006981D03*
X1002194Y1444392D03*
X1002538Y1463939D03*
Y1460939D03*
Y1457939D03*
Y1454939D03*
Y1466939D03*
Y1469702D03*
X1008549Y1509815D03*
X1007049Y1507215D03*
X1011149Y1509815D03*
X1009649Y1507215D03*
Y1512415D03*
X1007049D03*
X1008222Y1514993D03*
X1005622D03*
X1010822D03*
X1010606Y1547824D03*
X1007611Y1561247D03*
Y1558247D03*
Y1555247D03*
Y1552247D03*
X1004611Y1561247D03*
Y1558247D03*
Y1555247D03*
Y1552247D03*
X1010659Y1568771D03*
Y1565771D03*
X1010653Y1571669D03*
X1013683Y-44304D03*
Y-39348D03*
Y-29348D03*
Y-34304D03*
X1027508Y3000D03*
X1023373Y60922D03*
X1018209Y55513D03*
X1015059D03*
X1020519Y60438D03*
X1020254Y97068D03*
X1015402Y91951D03*
X1026200Y94374D03*
X1015427Y88801D03*
X1018344Y94351D03*
X1021341Y86046D03*
X1014006Y117261D03*
X1021537Y113394D03*
X1025755Y102249D03*
X1024186Y110784D03*
X1021537Y116594D03*
X1024289Y130898D03*
X1021537Y119594D03*
X1025927Y134579D03*
X1020378Y161306D03*
X1012134Y152562D03*
X1017629Y157370D03*
X1021713Y180665D03*
Y172665D03*
Y176665D03*
Y168665D03*
X1027055Y195176D03*
X1013812Y186629D03*
X1021713Y196665D03*
Y192665D03*
X1026915Y203393D03*
X1021745Y212864D03*
Y200864D03*
Y204864D03*
Y208864D03*
Y221864D03*
Y216864D03*
X1026794Y218085D03*
X1017386Y219379D03*
X1023502Y252371D03*
Y248371D03*
X1014420Y265897D03*
X1011920D03*
X1027216Y289440D03*
X1022604Y290262D03*
X1016635Y300276D03*
X1012635D03*
X1025749D03*
X1020635D03*
X1022435Y312865D03*
X1021848Y310396D03*
X1013354Y323362D03*
X1021451Y322879D03*
X1026032Y322906D03*
X1013327Y327453D03*
X1013318Y333190D03*
X1022845Y340944D03*
X1013313Y339909D03*
X1015195Y428305D03*
X1012188Y443421D03*
X1018238Y678647D03*
X1018155Y684132D03*
X1015659Y679654D03*
Y683054D03*
X1025116Y698332D03*
X1022937Y691421D03*
X1024932Y717856D03*
X1014641Y724436D03*
X1012851Y722417D03*
X1026916Y719769D03*
X1013486Y750773D03*
X1015804Y760454D03*
X1024684Y756485D03*
X1026090Y770943D03*
X1021895Y771974D03*
X1019375Y783056D03*
X1018044Y793592D03*
X1014064Y793660D03*
X1015800Y807535D03*
X1014587Y802788D03*
X1025859Y802275D03*
X1013821Y813520D03*
X1014781Y810319D03*
X1016320Y828481D03*
X1021895Y818974D03*
X1020703Y833659D03*
X1025219Y842155D03*
X1025239Y845070D03*
X1020703Y837659D03*
X1013918Y851306D03*
X1016973Y877196D03*
X1016574Y874537D03*
X1016798Y890299D03*
X1012842Y910685D03*
X1026340Y917761D03*
X1018419Y917575D03*
X1019519Y937922D03*
X1023319D03*
X1017619Y932122D03*
X1014719Y938322D03*
X1027319D03*
X1023519Y951522D03*
X1018919D03*
X1014009Y980356D03*
X1018009D03*
X1014009Y988813D03*
X1021924Y980456D03*
X1022009Y988813D03*
Y997860D03*
X1018009D03*
X1026009D03*
X1025448Y1008262D03*
X1014009Y997860D03*
X1017998Y1009655D03*
X1015198D03*
X1025448Y1011762D03*
X1011782Y1016591D03*
X1022594Y1035114D03*
X1022143Y1030672D03*
X1019143D03*
X1016143D03*
X1017297Y1102091D03*
X1026606Y1102591D03*
X1023106Y1102091D03*
X1017297Y1114691D03*
X1023106D03*
X1026606D03*
X1017297Y1109564D03*
X1023144Y1122164D03*
X1017297D03*
X1023106Y1127291D03*
X1026606D03*
X1017297Y1139891D03*
X1023106D03*
X1026606D03*
X1017297Y1127291D03*
X1023144Y1134764D03*
X1017297D03*
X1026606Y1152491D03*
X1017297D03*
X1023106D03*
X1023144Y1147364D03*
X1017297D03*
Y1165091D03*
X1023106D03*
X1026606D03*
X1023144Y1159964D03*
X1017297D03*
Y1172564D03*
Y1177691D03*
X1023106D03*
X1026606D03*
X1023162Y1174445D03*
X1017297Y1185164D03*
X1020434Y1205579D03*
X1026968Y1223749D03*
X1025434Y1320606D03*
X1011829Y1347471D03*
Y1342515D03*
X1015286Y1344924D03*
X1023358Y1363921D03*
X1013991Y1360842D03*
X1021623Y1373216D03*
X1012338Y1388597D03*
Y1391597D03*
X1015338D03*
Y1388597D03*
X1021338D03*
Y1391597D03*
X1018338D03*
Y1388597D03*
X1027338D03*
Y1391597D03*
X1024338D03*
Y1388597D03*
X1012981Y1431097D03*
Y1428097D03*
X1015981D03*
Y1431097D03*
X1021981Y1428097D03*
Y1431097D03*
X1018981D03*
Y1428097D03*
X1012981Y1434097D03*
X1015981D03*
X1012981Y1437097D03*
Y1440097D03*
X1015981Y1437097D03*
Y1440097D03*
X1021981Y1434097D03*
X1018981D03*
X1021981Y1437097D03*
X1018981D03*
X1021981Y1440097D03*
X1018981D03*
X1025615Y1444492D03*
X1025138Y1463839D03*
Y1460839D03*
Y1457839D03*
Y1454839D03*
Y1466839D03*
Y1469602D03*
X1020023Y1489637D03*
X1013749Y1509815D03*
X1016349D03*
X1021549D03*
X1018949D03*
X1024149D03*
X1022649Y1507215D03*
X1025249D03*
X1017449D03*
X1020049D03*
X1014849D03*
X1012249D03*
X1026749Y1509815D03*
X1012249Y1512415D03*
X1014849D03*
X1025249D03*
X1022649D03*
X1020049D03*
X1017449D03*
X1013422Y1514993D03*
X1023822D03*
X1021222D03*
X1018622D03*
X1016022D03*
X1026422D03*
X1013606Y1547824D03*
X1016606D03*
X1019606D03*
X1013659Y1568771D03*
X1016659D03*
X1019659D03*
X1013659Y1565771D03*
X1016659D03*
X1019659D03*
X1013653Y1571669D03*
X1016653D03*
X1019653D03*
X1011457Y1639797D03*
X1043492Y4469D03*
X1044923Y118342D03*
X1036772Y109172D03*
X1039772D03*
X1038779Y106495D03*
X1029755Y102249D03*
X1042523Y116497D03*
X1033506Y116594D03*
X1038779Y102495D03*
X1044923Y121742D03*
Y132515D03*
Y135915D03*
X1031780Y133298D03*
X1042523Y130670D03*
Y123584D03*
X1033506Y119594D03*
X1038513Y146012D03*
X1040419Y141228D03*
X1042523Y137757D03*
X1038513Y142862D03*
X1043307Y150847D03*
X1032055Y195176D03*
X1031674Y198883D03*
X1029555Y195176D03*
X1042102D03*
X1033103Y206838D03*
X1035603D03*
X1029415Y203393D03*
X1042183Y210509D03*
X1029594Y218085D03*
X1036107Y221970D03*
X1036173Y226320D03*
X1036107Y219470D03*
Y216970D03*
X1033394Y216385D03*
X1038065Y236121D03*
X1035099Y238589D03*
X1042860Y242078D03*
X1038091Y232971D03*
X1037984Y253198D03*
X1030184Y288709D03*
X1037290Y296293D03*
X1033890D03*
X1038068Y298789D03*
X1033112D03*
X1041496Y300276D03*
X1029639Y300141D03*
X1031354Y325901D03*
Y322905D03*
X1030220Y313554D03*
X1031382Y340947D03*
X1031310Y337888D03*
X1031377Y333671D03*
X1031362Y329268D03*
X1042948Y333696D03*
X1043106Y340230D03*
X1029885Y711762D03*
X1030753Y732213D03*
X1033200Y731700D03*
X1038796Y763272D03*
X1035619Y755809D03*
X1038344Y756476D03*
X1038678Y776750D03*
X1042880Y794924D03*
X1039251Y812340D03*
X1042414Y801443D03*
X1041100Y838500D03*
X1035185Y862793D03*
X1037685Y862789D03*
X1028155Y879413D03*
X1030300Y881400D03*
X1037709Y886209D03*
X1043252Y902501D03*
X1033019Y933022D03*
Y935822D03*
X1030819Y938422D03*
X1031219Y949922D03*
X1033370Y953994D03*
X1038009Y988813D03*
X1030009D03*
Y997860D03*
X1034009D03*
X1038252Y1009354D03*
X1034752D03*
X1028943D03*
X1042009Y997860D03*
X1038009D03*
X1034752Y1021954D03*
X1028943Y1016827D03*
X1034790D03*
X1043553Y1035384D03*
X1028943Y1029427D03*
X1034790D03*
X1039499Y1098758D03*
X1039053Y1105091D03*
Y1117691D03*
Y1130291D03*
Y1142891D03*
Y1155491D03*
Y1168091D03*
Y1180691D03*
X1040600Y1210600D03*
X1035384Y1215195D03*
X1029797Y1220921D03*
X1043588Y1227300D03*
X1034513Y1333665D03*
X1042586Y1345824D03*
X1030338Y1391597D03*
Y1388597D03*
X1032867Y1431213D03*
Y1428213D03*
X1029867D03*
X1035867Y1431213D03*
Y1428213D03*
X1029867Y1431213D03*
X1038867Y1428213D03*
Y1431213D03*
X1041867D03*
Y1428213D03*
X1032867Y1434213D03*
X1029867D03*
X1035867D03*
X1038867D03*
X1032867Y1437213D03*
X1029867D03*
X1032867Y1440213D03*
X1029867D03*
X1035867Y1437213D03*
Y1440213D03*
X1038867Y1437213D03*
Y1440213D03*
X1041867Y1434213D03*
Y1437213D03*
Y1440213D03*
X1029349Y1509815D03*
X1027849Y1507215D03*
Y1512415D03*
X1031457Y1639797D03*
X1044853Y24773D03*
Y44773D03*
X1052174Y53597D03*
X1047373Y95111D03*
X1052223Y114655D03*
Y111255D03*
X1049823Y109410D03*
X1054523Y116496D03*
Y109410D03*
Y102323D03*
X1049823Y116497D03*
X1047323D03*
X1052223Y111255D03*
Y114655D03*
X1051742Y106561D03*
X1052223Y128828D03*
Y125428D03*
X1049823Y130670D03*
X1047323D03*
Y123584D03*
X1049823Y123583D03*
X1054523Y130670D03*
Y123583D03*
X1044923Y118342D03*
X1052223Y125428D03*
Y128828D03*
X1044923Y132515D03*
Y121742D03*
X1054523Y137756D03*
X1047323Y137757D03*
X1044923Y135915D03*
X1047102Y195176D03*
X1046120Y199248D03*
X1044602Y195176D03*
X1049602D03*
X1051055Y213539D03*
X1046120Y201748D03*
X1049120Y202048D03*
X1044683Y210509D03*
X1046456Y206806D03*
X1043956D03*
X1044501Y238689D03*
X1045275Y247292D03*
X1052736Y238714D03*
X1048736D03*
X1048217Y246874D03*
X1050437Y244297D03*
X1048695Y280161D03*
X1045364Y279895D03*
X1051796Y279965D03*
X1050164Y302748D03*
X1050076Y305512D03*
X1046674Y340031D03*
X1045966Y346808D03*
X1054863Y401513D03*
Y398113D03*
X1052463Y412287D03*
X1052367Y402291D03*
X1057359D03*
X1052367Y397335D03*
X1057359D03*
X1054863Y401513D03*
Y398113D03*
X1052463Y426460D03*
Y415687D03*
X1054959Y411509D03*
X1049967Y416465D03*
Y411509D03*
X1054959Y425682D03*
X1049967D03*
X1054959Y416465D03*
X1052463Y412287D03*
Y415687D03*
Y426460D03*
Y440633D03*
Y429860D03*
Y444033D03*
X1049967Y439855D03*
X1054959Y430638D03*
X1049967D03*
X1054959Y439855D03*
X1052463Y440633D03*
Y429860D03*
X1049967Y444811D03*
X1050777Y450750D03*
X1054959Y444811D03*
X1052463Y444033D03*
Y472787D03*
Y469387D03*
X1049967Y468609D03*
X1054959D03*
X1049967Y473565D03*
X1054959D03*
X1052463Y469387D03*
Y472787D03*
Y483560D03*
Y486960D03*
X1049967Y487738D03*
X1054959D03*
X1049967Y482782D03*
X1054959D03*
X1052463Y486960D03*
Y483560D03*
Y513521D03*
Y516921D03*
X1054959Y517699D03*
X1049967Y512743D03*
X1054959D03*
X1049967Y517699D03*
X1052463Y513521D03*
Y516921D03*
Y531094D03*
Y527694D03*
X1049967Y526916D03*
X1054959Y531872D03*
X1049967D03*
X1054959Y526916D03*
X1054876Y536382D03*
X1052463Y531094D03*
Y527694D03*
X1055885Y554555D03*
X1059843Y597580D03*
X1059782Y594668D03*
X1044112Y778835D03*
X1046068Y792742D03*
X1046930Y796557D03*
X1045744Y800835D03*
X1048328Y808166D03*
X1055700Y840900D03*
X1053913Y837718D03*
X1045300Y872352D03*
X1054900Y879321D03*
X1058155Y887635D03*
X1050295Y891100D03*
X1057961Y931919D03*
X1054009Y988813D03*
X1046009D03*
Y997860D03*
X1054009D03*
X1050009D03*
X1058009D03*
X1059689Y1012354D03*
Y1024954D03*
X1050699D03*
Y1012354D03*
X1046485Y1034538D03*
X1048043Y1105091D03*
Y1117691D03*
Y1130291D03*
Y1155491D03*
Y1142891D03*
Y1168091D03*
Y1180691D03*
X1050605Y1224472D03*
X1051249Y1290288D03*
X1052660Y1293257D03*
X1050002Y1293283D03*
X1054713Y1348187D03*
X1058113D03*
X1052221Y1336984D03*
X1058891Y1345691D03*
Y1350683D03*
X1053935Y1345691D03*
Y1350683D03*
X1049204Y1337377D03*
X1058113Y1348187D03*
X1054713D03*
X1049670Y1347462D03*
X1046075Y1350650D03*
X1049493Y1350694D03*
X1058113Y1360099D03*
X1054713D03*
X1058891Y1362595D03*
X1053935D03*
X1058891Y1357603D03*
X1053935D03*
X1058113Y1360099D03*
X1054713D03*
X1058113Y1384297D03*
X1054713D03*
Y1372385D03*
X1058113D03*
X1058891Y1381801D03*
Y1374881D03*
Y1369889D03*
X1053935Y1381801D03*
Y1374881D03*
Y1369889D03*
X1058113Y1372385D03*
X1054713D03*
Y1384297D03*
X1058113D03*
X1058891Y1386793D03*
X1053935D03*
X1044867Y1428213D03*
Y1431213D03*
Y1434213D03*
Y1437213D03*
Y1440213D03*
X1048403Y1444608D03*
X1051457Y1639797D03*
X1075256Y-77419D03*
X1072003Y-77405D03*
X1071988Y-85290D03*
X1075241D03*
X1072000Y-82600D03*
X1072003Y-87805D03*
X1075256D03*
X1072000Y-80100D03*
Y-72000D03*
Y-69400D03*
X1071988Y-66722D03*
X1075241Y-66808D03*
X1072003Y-64207D03*
X1075256Y-64293D03*
X1075241Y-74904D03*
X1071988Y-74890D03*
X1072174Y53597D03*
X1062985Y82984D03*
Y75184D03*
Y77784D03*
Y80384D03*
X1065539Y92849D03*
X1062985Y85584D03*
X1072456Y95236D03*
X1062523D03*
X1072499Y103037D03*
X1062523Y102323D03*
X1062775Y109410D03*
Y116496D03*
X1072633D03*
Y109410D03*
X1062947Y124576D03*
X1072633Y130670D03*
Y123583D03*
X1064000Y130670D03*
X1069224Y137756D03*
X1063995D03*
X1071268Y207978D03*
Y212978D03*
Y215478D03*
Y210478D03*
Y226226D03*
Y223726D03*
Y228726D03*
Y231226D03*
X1074597Y264180D03*
X1074522Y258880D03*
X1074814Y293796D03*
X1061325Y339509D03*
X1060679Y360151D03*
Y364276D03*
Y368276D03*
X1062865Y391001D03*
Y394401D03*
X1060369Y390223D03*
X1065361D03*
X1062865Y391001D03*
X1062234Y378600D03*
Y382600D03*
X1062865Y405174D03*
Y408574D03*
X1060369Y395179D03*
Y404396D03*
Y409352D03*
X1065361Y395179D03*
Y404396D03*
Y409352D03*
X1062865Y408574D03*
Y405174D03*
Y394401D03*
Y419347D03*
Y422747D03*
X1060369Y418569D03*
Y423525D03*
X1065361D03*
Y418569D03*
X1062865Y422747D03*
Y419347D03*
Y433521D03*
Y436921D03*
X1060369Y432743D03*
Y437699D03*
X1065361Y432743D03*
Y437699D03*
X1062865Y436921D03*
Y433521D03*
X1062349Y458711D03*
X1064876Y453682D03*
X1063113Y455921D03*
X1062865Y476499D03*
X1061693Y463600D03*
X1062865Y479899D03*
Y490673D03*
X1065361Y489895D03*
X1060369D03*
Y480677D03*
Y475721D03*
X1065361Y480677D03*
Y475721D03*
X1062865Y476499D03*
Y479899D03*
Y490673D03*
Y494073D03*
X1060369Y494851D03*
X1065361D03*
X1062865Y494073D03*
Y524033D03*
Y520633D03*
X1060369Y519855D03*
X1065361D03*
X1062865Y520633D03*
Y524033D03*
Y538206D03*
Y534806D03*
X1065361Y524811D03*
X1060369D03*
Y538984D03*
Y534028D03*
X1065361Y538984D03*
Y534028D03*
X1062865Y534806D03*
Y538206D03*
X1071548Y555234D03*
X1071263Y562003D03*
X1062066Y599588D03*
X1061328Y589556D03*
X1061267Y592354D03*
X1062069Y596095D03*
X1062098Y603600D03*
X1062066Y607588D03*
X1061342Y610269D03*
X1061496Y612786D03*
X1062098Y619600D03*
X1066559Y634946D03*
X1062098Y623600D03*
X1060698Y931619D03*
X1069685Y933391D03*
X1066878Y931909D03*
X1070009Y988813D03*
X1069607Y980131D03*
X1066009Y980330D03*
X1062009Y988813D03*
X1066009Y997860D03*
X1062009D03*
X1074009D03*
X1070778Y1012252D03*
X1073525Y1012428D03*
X1066933Y1040567D03*
X1076110Y1029535D03*
X1071641Y1058029D03*
X1060172Y1050481D03*
X1071348Y1050503D03*
X1074232Y1055836D03*
X1060768Y1053457D03*
X1074650Y1070006D03*
X1070353Y1348187D03*
X1066953D03*
X1066175Y1350683D03*
Y1345691D03*
X1071131Y1350683D03*
Y1345691D03*
X1066953Y1348187D03*
X1070353D03*
Y1360099D03*
X1066953D03*
X1066175Y1357603D03*
Y1362595D03*
X1071131Y1357603D03*
Y1362595D03*
X1066953Y1360099D03*
X1070353D03*
Y1384297D03*
Y1372385D03*
X1066953D03*
Y1384297D03*
X1066175Y1381801D03*
Y1369795D03*
Y1374881D03*
X1071131Y1381801D03*
Y1369795D03*
Y1374881D03*
X1066953Y1384297D03*
Y1372385D03*
X1070353D03*
Y1384297D03*
Y1396583D03*
X1066953D03*
X1066175Y1393993D03*
Y1399079D03*
Y1386793D03*
X1071131Y1399079D03*
Y1393993D03*
Y1386793D03*
X1070353Y1396583D03*
X1066953D03*
Y1408495D03*
X1070353D03*
X1066175Y1405999D03*
Y1410991D03*
X1071131Y1405999D03*
Y1410991D03*
X1066953Y1408495D03*
X1070353D03*
X1071457Y1639797D03*
X1081187Y-79306D03*
Y-82706D03*
X1078281Y-86399D03*
X1083683Y-78528D03*
Y-83484D03*
X1081187Y-79306D03*
Y-82706D03*
Y-72706D03*
Y-69306D03*
X1078281Y-65613D03*
Y-76099D03*
X1083683Y-73484D03*
Y-68528D03*
X1081187Y-72706D03*
Y-69306D03*
X1090280Y44773D03*
X1081320Y85193D03*
Y82593D03*
Y79993D03*
Y77393D03*
Y74793D03*
X1089916Y94017D03*
X1085916D03*
X1089645Y101701D03*
Y98551D03*
X1092540Y111223D03*
Y114623D03*
Y111223D03*
X1090044Y110445D03*
Y115401D03*
X1080633Y102323D03*
Y116496D03*
Y109410D03*
X1092540Y114623D03*
X1083391Y104249D03*
Y107649D03*
X1092540Y125396D03*
Y128796D03*
D03*
X1080633Y130670D03*
Y123583D03*
X1090044Y124618D03*
Y129574D03*
X1092540Y125396D03*
X1080633Y137756D03*
X1087957Y147540D03*
X1091729Y141247D03*
X1087957Y151540D03*
X1083013Y162368D03*
X1090113Y165393D03*
Y162793D03*
X1080413Y162368D03*
X1090113Y170493D03*
Y167993D03*
X1092321Y181366D03*
X1089110Y181426D03*
X1091607Y191941D03*
X1091935Y184012D03*
X1089318Y184221D03*
X1081724Y208213D03*
X1085796Y208695D03*
Y211695D03*
X1081724Y210713D03*
Y213213D03*
X1088296Y211695D03*
X1085431Y226141D03*
X1081724Y226461D03*
X1089693Y229286D03*
X1081724Y231461D03*
Y228961D03*
Y215713D03*
X1089693Y231786D03*
X1085674Y236611D03*
X1088174D03*
X1090674D03*
X1090376Y248891D03*
X1087876D03*
X1085376D03*
X1077097Y264180D03*
X1083491Y267526D03*
X1088791D03*
X1086291D03*
X1083491Y270026D03*
X1086291D03*
X1088791D03*
X1088128Y285690D03*
Y288190D03*
X1085328D03*
X1082828Y285690D03*
X1085328D03*
X1082828Y288190D03*
X1077314Y293796D03*
X1092354Y290755D03*
X1077855Y327478D03*
X1077252Y323521D03*
Y318565D03*
X1077602Y314060D03*
X1080351Y328256D03*
X1079748Y322743D03*
Y319343D03*
X1077855Y332434D03*
X1080351Y331656D03*
X1082297Y340770D03*
X1085615Y339815D03*
X1079863Y345660D03*
X1092561Y353374D03*
X1082787Y348501D03*
X1091031Y374810D03*
X1091542Y389154D03*
Y410413D03*
Y396240D03*
Y403327D03*
Y417500D03*
Y424587D03*
Y431673D03*
Y438760D03*
Y445847D03*
Y467539D03*
Y474626D03*
Y488799D03*
Y481713D03*
Y495886D03*
Y511673D03*
Y518760D03*
Y525847D03*
Y532933D03*
Y540020D03*
Y547106D03*
X1089788Y550907D03*
X1087288D03*
X1089788Y553407D03*
X1087288D03*
X1089096Y541863D03*
Y545263D03*
X1091558Y566929D03*
X1091272Y569426D03*
X1088949Y568475D03*
X1089206Y570962D03*
X1086859Y569928D03*
X1085512Y572070D03*
X1090823Y602197D03*
X1091287Y595108D03*
X1078920Y856700D03*
X1090375Y899047D03*
X1076800Y1012900D03*
X1079809Y1034386D03*
X1078755Y1031518D03*
X1079178Y1037884D03*
X1076868Y1047293D03*
X1079910Y1045264D03*
X1079193Y1348187D03*
X1082593D03*
X1091433D03*
X1090655Y1350683D03*
Y1345691D03*
X1083371D03*
Y1350683D03*
X1078415Y1345691D03*
Y1350683D03*
X1091433Y1348187D03*
X1082593D03*
X1079193D03*
X1091433Y1360099D03*
X1079193D03*
X1082593D03*
X1090655Y1357603D03*
Y1362595D03*
X1083371Y1357603D03*
Y1362595D03*
X1078415D03*
Y1357603D03*
X1091433Y1360099D03*
X1082593D03*
X1079193D03*
Y1384297D03*
X1082593D03*
Y1372385D03*
X1079193D03*
X1091433Y1384297D03*
Y1372385D03*
X1090655Y1381801D03*
Y1374881D03*
Y1369889D03*
X1083371D03*
Y1374881D03*
Y1381801D03*
X1078415Y1369889D03*
Y1374881D03*
Y1381801D03*
X1079193Y1372385D03*
X1082593D03*
Y1384297D03*
X1079193D03*
X1091433D03*
Y1372385D03*
Y1396583D03*
X1079193D03*
X1082593D03*
X1090655Y1394087D03*
Y1399079D03*
Y1386793D03*
X1083371D03*
Y1399079D03*
Y1394087D03*
X1078415Y1386793D03*
Y1394087D03*
Y1399079D03*
X1091433Y1396583D03*
X1082593D03*
X1079193D03*
Y1408495D03*
X1082593D03*
X1091433D03*
X1090655Y1405999D03*
Y1410991D03*
X1083371Y1405999D03*
Y1410991D03*
X1078415Y1405999D03*
Y1410991D03*
X1091433Y1408495D03*
X1082593D03*
X1079193D03*
X1083483Y1523433D03*
X1083283Y1526583D03*
X1090876Y1554183D03*
X1086469Y1588435D03*
X1082176Y1600598D03*
X1090904Y1599047D03*
X1090747Y1617415D03*
X1085474Y1629028D03*
X1092000Y1644980D03*
X1102993Y84140D03*
Y76140D03*
Y80140D03*
X1105741Y76587D03*
Y72615D03*
X1097925Y94017D03*
X1093916D03*
X1102942Y118335D03*
X1100446Y117557D03*
X1095036Y115401D03*
Y110445D03*
X1105438Y117557D03*
X1097195Y103783D03*
X1108362Y103621D03*
X1100130Y106186D03*
X1093195Y103783D03*
X1102942Y121735D03*
Y132509D03*
Y135909D03*
Y118335D03*
Y132509D03*
Y121735D03*
X1095036Y129574D03*
Y124618D03*
X1105438Y131731D03*
Y122513D03*
X1100446Y131731D03*
Y122513D03*
X1102942Y135909D03*
X1103537Y146461D03*
X1100446Y136687D03*
X1105438D03*
X1102439Y152367D03*
X1104139Y180572D03*
X1108822Y180527D03*
X1095116Y181009D03*
X1100291Y168697D03*
X1104139Y185165D03*
X1108777Y185121D03*
X1098107Y184619D03*
X1101379Y191941D03*
X1100087Y206760D03*
X1105888Y206767D03*
X1108388D03*
X1103388D03*
X1093354Y213859D03*
Y211359D03*
X1097057Y213132D03*
X1093386Y224712D03*
Y222212D03*
X1104633Y228221D03*
X1106018Y221708D03*
X1108518D03*
X1102933Y224421D03*
X1103518Y221708D03*
X1104633Y231021D03*
X1097057Y215632D03*
X1105184Y236189D03*
X1107684D03*
X1101301Y256535D03*
X1093301D03*
X1105125Y248765D03*
X1107625D03*
X1097301Y256303D03*
X1102331Y279208D03*
X1107822Y268195D03*
X1105322D03*
Y270695D03*
X1107822D03*
X1108425Y293645D03*
Y290845D03*
Y288345D03*
X1096354Y290755D03*
X1093478Y310305D03*
X1108779Y327705D03*
X1100703Y340560D03*
X1103432Y340544D03*
X1097976Y340477D03*
X1101999Y353495D03*
X1098845Y353404D03*
X1093994Y374003D03*
X1093841Y371335D03*
X1099342Y389154D03*
X1106161D03*
X1099342Y396240D03*
X1100621Y404911D03*
X1104691Y396240D03*
X1099575Y412571D03*
X1108776Y422864D03*
X1100762Y426299D03*
X1108846Y429832D03*
X1108451Y436447D03*
X1101073Y445847D03*
X1099342Y467539D03*
Y474626D03*
X1108395Y472772D03*
X1099603Y480828D03*
X1101553Y498834D03*
X1105002Y516841D03*
X1108253Y510565D03*
X1099342Y518760D03*
Y511673D03*
Y525847D03*
X1099949Y550123D03*
X1099827Y552872D03*
X1101581Y572334D03*
X1099272Y562443D03*
X1101040Y560675D03*
X1099813Y574102D03*
X1108236Y577716D03*
X1105298Y598400D03*
Y602400D03*
Y594400D03*
Y614400D03*
Y606400D03*
Y610400D03*
X1108045Y677843D03*
X1092769Y936975D03*
X1094833Y1348187D03*
X1103673D03*
X1107073D03*
X1107851Y1345691D03*
X1102895Y1350683D03*
Y1345691D03*
X1107851Y1350683D03*
X1095611D03*
Y1345691D03*
X1094833Y1348187D03*
X1107073D03*
X1103673D03*
X1107073Y1360099D03*
X1094833D03*
X1103673D03*
X1107851Y1357603D03*
X1102895Y1362595D03*
Y1357603D03*
X1107851Y1362595D03*
X1095611Y1357603D03*
Y1362595D03*
X1094833Y1360099D03*
X1103673D03*
X1107073D03*
X1094833Y1384297D03*
Y1372385D03*
X1103673Y1384297D03*
X1107073D03*
X1103673Y1372385D03*
X1107073D03*
X1107851Y1369889D03*
Y1374881D03*
Y1381801D03*
X1102895Y1374881D03*
Y1369889D03*
Y1381801D03*
X1095611D03*
Y1374881D03*
Y1369889D03*
X1107073Y1372385D03*
X1103673D03*
X1107073Y1384297D03*
X1103673D03*
X1094833D03*
Y1372385D03*
X1107073Y1396583D03*
X1094833D03*
X1103673D03*
X1107851Y1386793D03*
Y1394087D03*
Y1399079D03*
X1102895Y1386793D03*
Y1394087D03*
Y1399079D03*
X1095611D03*
Y1394087D03*
Y1386793D03*
X1094833Y1396583D03*
X1107073D03*
X1103673D03*
X1094833Y1408495D03*
X1103673D03*
X1107073D03*
X1107851Y1405999D03*
Y1410991D03*
X1102895Y1405999D03*
Y1410991D03*
X1095611Y1405999D03*
Y1410991D03*
X1094833Y1408495D03*
X1107073D03*
X1103673D03*
X1095080Y1513398D03*
X1099900Y1535700D03*
X1095250Y1531600D03*
X1096264Y1562285D03*
X1100876Y1554183D03*
X1093713Y1585583D03*
X1093682Y1582433D03*
X1098498Y1590435D03*
X1104233Y1587983D03*
X1107620Y1606752D03*
Y1603602D03*
X1101474Y1637820D03*
X1093474Y1638213D03*
X1123052Y57511D03*
X1114781Y58013D03*
X1113646Y68581D03*
X1122881Y60438D03*
X1113659Y80581D03*
X1122613Y97042D03*
X1117764Y91951D03*
X1117789Y88801D03*
X1123703Y86046D03*
X1120706Y94351D03*
X1116368Y117261D03*
X1123899Y113394D03*
Y116594D03*
X1111553Y112083D03*
X1123899Y119594D03*
X1122740Y161306D03*
X1114496Y152562D03*
X1119991Y157370D03*
X1124075Y180665D03*
Y172665D03*
Y168665D03*
Y176665D03*
X1112545Y192421D03*
X1116174Y186629D03*
X1124075Y196665D03*
X1114708Y190185D03*
X1124188Y186778D03*
X1124107Y200864D03*
Y212864D03*
Y204864D03*
Y216864D03*
Y221864D03*
X1112868Y221642D03*
X1119748Y219379D03*
X1110184Y236189D03*
X1110125Y248765D03*
X1116782Y265897D03*
X1114282D03*
X1110622Y268195D03*
Y270695D03*
X1110925Y293645D03*
Y290845D03*
Y288345D03*
X1123500Y329000D03*
X1115000D03*
X1123500Y339000D03*
Y334000D03*
X1115000D03*
Y339000D03*
X1117453Y389154D03*
X1124753Y389153D03*
X1119853Y401482D03*
Y398082D03*
Y412255D03*
X1122253Y396240D03*
X1124753D03*
X1122253Y403327D03*
X1124753Y403326D03*
X1122253Y410413D03*
X1124753D03*
X1117453Y396240D03*
Y403327D03*
Y410413D03*
X1119853Y398082D03*
Y401482D03*
Y415655D03*
Y426428D03*
X1109468Y414823D03*
X1122253Y424586D03*
X1124753D03*
X1117453Y417500D03*
Y424586D03*
X1122253Y417500D03*
X1124753Y417499D03*
X1119853Y412255D03*
Y426428D03*
Y415655D03*
Y429828D03*
Y440602D03*
Y444002D03*
X1122253Y438760D03*
X1124753D03*
Y431673D03*
X1117453D03*
Y438760D03*
X1122253Y431673D03*
X1119853Y440602D03*
Y429828D03*
X1110486Y447953D03*
X1122253Y445847D03*
X1117453D03*
X1119853Y444002D03*
Y476468D03*
X1109653Y467539D03*
X1124753D03*
X1117453D03*
X1122253Y474626D03*
X1124753D03*
X1117453D03*
X1119853Y479868D03*
Y490641D03*
X1122253Y488799D03*
X1124753D03*
X1117453D03*
X1109129Y487711D03*
X1109242Y479104D03*
X1124753Y481712D03*
X1122253D03*
X1117453Y481713D03*
X1119853Y490641D03*
Y476468D03*
Y479868D03*
Y494041D03*
X1122253Y495886D03*
X1117453D03*
X1109653D03*
X1119853Y494041D03*
Y524002D03*
Y520602D03*
X1124753Y518760D03*
X1122253D03*
X1124753Y511673D03*
X1117453D03*
Y518760D03*
X1119853Y524002D03*
Y520602D03*
Y538175D03*
Y534775D03*
X1124753Y532933D03*
X1122253D03*
Y540020D03*
Y525846D03*
X1124753D03*
X1117453Y525847D03*
Y532933D03*
Y540020D03*
X1119853Y538175D03*
Y534775D03*
X1117453Y554193D03*
Y547106D03*
X1117913Y565414D03*
Y567914D03*
Y570414D03*
X1118847Y561420D03*
Y558917D03*
X1117913Y572914D03*
Y575414D03*
X1122705Y588515D03*
X1114668Y577937D03*
X1117453Y602205D03*
Y595118D03*
X1122718Y598857D03*
X1122705Y591015D03*
X1121191Y612555D03*
X1120512Y617332D03*
X1121022Y607750D03*
X1115320Y646449D03*
X1118863Y662981D03*
X1112839Y668885D03*
X1115054Y662981D03*
X1113244Y691851D03*
X1116296D03*
X1111785Y686971D03*
X1118855Y705043D03*
X1118105Y707592D03*
X1115913Y1348187D03*
X1119313D03*
X1115135Y1345691D03*
Y1350683D03*
X1120091Y1345691D03*
Y1350683D03*
X1115913Y1348187D03*
X1119313D03*
X1115913Y1360099D03*
X1119313D03*
X1115135Y1357603D03*
Y1362595D03*
X1120091Y1357603D03*
Y1362595D03*
X1115913Y1360099D03*
X1119313D03*
Y1384297D03*
X1115913Y1372385D03*
X1119313D03*
X1115913Y1384297D03*
X1115135Y1374881D03*
Y1381801D03*
Y1369889D03*
X1120091D03*
Y1374881D03*
Y1381801D03*
X1119313Y1384297D03*
X1115913Y1372385D03*
X1119313D03*
X1115913Y1384297D03*
Y1396583D03*
X1119313D03*
X1115135Y1394087D03*
Y1399079D03*
Y1386793D03*
X1120091Y1399079D03*
Y1394087D03*
Y1386793D03*
X1115913Y1396583D03*
X1119313D03*
X1115913Y1408495D03*
X1119313D03*
X1115913D03*
X1115135Y1405999D03*
Y1410991D03*
X1120091Y1405999D03*
Y1410991D03*
X1119313Y1408495D03*
X1112000Y1644980D03*
X1125735Y60922D03*
X1128562Y94374D03*
X1139134Y109172D03*
X1141141Y106495D03*
X1132117Y102249D03*
X1128117D03*
X1126548Y110784D03*
X1135868Y116594D03*
X1141141Y102495D03*
X1134142Y133298D03*
X1126142D03*
X1135868Y119594D03*
X1140875Y146012D03*
X1128289Y134579D03*
X1140875Y142862D03*
X1134036Y198883D03*
X1134417Y195176D03*
X1131917D03*
X1129417D03*
X1137965Y206838D03*
X1131777Y203393D03*
X1129277D03*
X1135465Y206838D03*
X1129156Y218085D03*
X1131956D03*
X1138469Y221970D03*
X1138535Y226320D03*
X1138469Y219470D03*
Y216970D03*
X1135756Y216385D03*
X1137461Y238589D03*
X1140427Y236121D03*
X1140453Y232971D03*
X1140346Y253198D03*
X1125864Y252371D03*
Y248371D03*
X1127153Y390995D03*
Y394395D03*
X1129553Y389153D03*
X1127153Y390995D03*
Y405168D03*
Y408568D03*
X1129553Y396240D03*
Y403326D03*
Y410413D03*
X1127153Y408568D03*
Y405168D03*
Y394395D03*
Y419341D03*
Y422741D03*
X1129553Y424586D03*
Y417499D03*
X1127153Y422741D03*
Y419341D03*
Y433515D03*
Y436915D03*
X1129553Y431673D03*
Y438760D03*
X1127153Y436915D03*
Y433515D03*
X1126931Y453564D03*
X1130355Y453483D03*
X1127153Y472781D03*
Y469381D03*
X1129553Y467539D03*
X1125178Y459792D03*
X1129553Y474626D03*
X1127153Y472781D03*
Y469381D03*
X1134629Y465551D03*
X1127153Y483554D03*
Y486954D03*
X1129553Y488799D03*
Y481712D03*
X1127153Y486954D03*
Y483554D03*
X1126622Y506256D03*
X1127153Y516915D03*
Y513515D03*
X1129553Y518760D03*
Y511673D03*
X1127153Y516915D03*
Y513515D03*
Y527688D03*
Y531088D03*
X1129553Y532933D03*
Y525846D03*
X1138166Y534759D03*
X1127153Y527688D03*
Y531088D03*
X1139673Y530000D03*
X1138098Y543925D03*
X1138673Y555000D03*
X1139173Y540500D03*
X1138373Y549800D03*
X1138173Y547075D03*
X1126633Y560500D03*
X1138213Y558800D03*
X1138277Y562800D03*
X1125287Y592897D03*
X1129471Y732571D03*
X1128153Y1348187D03*
X1131553D03*
X1140393D03*
X1139615Y1350683D03*
Y1345691D03*
X1132331D03*
Y1350683D03*
X1127375D03*
Y1345691D03*
X1140393Y1348187D03*
X1131553D03*
X1128153D03*
X1140393Y1360099D03*
X1128153D03*
X1131553D03*
X1140393D03*
X1139615Y1357603D03*
Y1362595D03*
X1132331D03*
Y1357603D03*
X1127375D03*
Y1362595D03*
X1131553Y1360099D03*
X1128153D03*
X1131553Y1372385D03*
X1128153D03*
X1131553Y1384297D03*
X1128153D03*
X1140393D03*
Y1372385D03*
X1128153Y1384297D03*
X1131553D03*
X1139615Y1374881D03*
Y1369889D03*
Y1381801D03*
X1132331Y1369889D03*
Y1381801D03*
Y1374881D03*
X1127375Y1369889D03*
Y1381801D03*
Y1374881D03*
X1128153Y1372385D03*
X1131553D03*
X1140393Y1384297D03*
Y1372385D03*
Y1396583D03*
X1128153D03*
X1131553D03*
X1139615Y1394087D03*
Y1399079D03*
Y1386793D03*
X1132331D03*
Y1394087D03*
Y1399079D03*
X1127375Y1386793D03*
Y1394087D03*
Y1399079D03*
X1140393Y1396583D03*
X1131553D03*
X1128153D03*
X1131553Y1408495D03*
X1128153D03*
X1140393D03*
X1139615Y1405999D03*
Y1410991D03*
X1132331Y1405999D03*
Y1410991D03*
X1127375Y1405999D03*
Y1410991D03*
X1140393Y1408495D03*
X1128153D03*
X1131553D03*
X1129637Y1465913D03*
Y1461182D03*
Y1456451D03*
X1138298Y1465513D03*
Y1460782D03*
X1129637Y1476536D03*
Y1481267D03*
X1138298Y1476136D03*
Y1470244D03*
Y1480867D03*
X1129637Y1471805D03*
Y1496621D03*
X1138298Y1491490D03*
Y1485598D03*
Y1496221D03*
X1129637Y1491890D03*
Y1487159D03*
X1138298Y1500952D03*
Y1511576D03*
X1129637Y1507245D03*
Y1502514D03*
Y1511976D03*
X1138298Y1506845D03*
Y1516307D03*
X1129637Y1563544D03*
Y1558813D03*
X1138298Y1563144D03*
Y1572606D03*
X1129637Y1568275D03*
Y1578898D03*
Y1574167D03*
X1138298Y1567875D03*
Y1578498D03*
X1129637Y1583629D03*
Y1594253D03*
Y1589522D03*
X1138298Y1583229D03*
Y1593853D03*
Y1587960D03*
Y1598584D03*
Y1603315D03*
X1129637Y1609607D03*
Y1598984D03*
Y1604876D03*
X1138298Y1609207D03*
X1129637Y1614338D03*
X1138298Y1613938D03*
Y1618669D03*
X1132000Y1644980D03*
X1147214Y44773D03*
X1154535Y53597D03*
X1149735Y95111D03*
X1154585Y111255D03*
Y114655D03*
X1147285Y118342D03*
X1142134Y109172D03*
X1156885Y116496D03*
Y102323D03*
Y109410D03*
X1152185D03*
Y116497D03*
X1149685D03*
X1144885D03*
X1154585Y114655D03*
Y111255D03*
X1154104Y106561D03*
X1154585Y128828D03*
Y125428D03*
X1147285Y132515D03*
Y121742D03*
Y135915D03*
X1152185Y130670D03*
X1149685D03*
Y123584D03*
X1152185Y123583D03*
X1144885Y130670D03*
Y123584D03*
X1156885Y130670D03*
Y123583D03*
X1154585Y128828D03*
X1147285Y118342D03*
Y121742D03*
Y132515D03*
X1154585Y125428D03*
X1142781Y141228D03*
X1156885Y137756D03*
X1149685Y137757D03*
X1144885D03*
X1147285Y135915D03*
X1145669Y150847D03*
X1149464Y195176D03*
X1148482Y199248D03*
X1144464Y195176D03*
X1146964D03*
X1151964D03*
X1153417Y213539D03*
X1151482Y202048D03*
X1146318Y206806D03*
X1144545Y210509D03*
X1147045D03*
X1148818Y206806D03*
X1148482Y201748D03*
X1146863Y238689D03*
X1155098Y238714D03*
X1147637Y247292D03*
X1151098Y238714D03*
X1145222Y242078D03*
X1150579Y246874D03*
X1152799Y244297D03*
X1145761Y324148D03*
X1142440Y392718D03*
Y400718D03*
Y408718D03*
Y396718D03*
X1157451Y618288D03*
X1156275Y656321D03*
X1156023Y678462D03*
X1155146Y699491D03*
X1149437Y728541D03*
X1152512Y728543D03*
X1152316Y746625D03*
X1148962Y747253D03*
X1149345Y771517D03*
X1145910Y794217D03*
X1151277Y790996D03*
X1154652Y791056D03*
X1149627Y813323D03*
X1146985Y812642D03*
X1145910Y803642D03*
X1152510Y844642D03*
X1143793Y1348187D03*
X1152633D03*
X1156033D03*
X1156811Y1350683D03*
Y1345691D03*
X1151855D03*
Y1350683D03*
X1144571D03*
Y1345691D03*
X1143793Y1348187D03*
X1156033D03*
X1152633D03*
X1156033Y1360099D03*
X1143793D03*
X1152633D03*
X1143793D03*
X1156811Y1357603D03*
Y1362595D03*
X1151855D03*
Y1357603D03*
X1144571D03*
Y1362595D03*
X1152633Y1360099D03*
X1156033D03*
X1143793Y1372385D03*
Y1384297D03*
X1152633Y1372385D03*
X1156033D03*
X1152633Y1384297D03*
X1156033D03*
D03*
X1152633D03*
X1156811Y1374881D03*
Y1369889D03*
Y1381801D03*
X1151855Y1374881D03*
Y1369889D03*
Y1381801D03*
X1144571Y1369889D03*
Y1381801D03*
Y1374881D03*
X1156033Y1372385D03*
X1152633D03*
X1143793D03*
Y1384297D03*
X1156033Y1396583D03*
X1143793D03*
X1152633D03*
X1156811Y1386793D03*
Y1399079D03*
Y1394087D03*
X1151855Y1386793D03*
Y1399079D03*
Y1394087D03*
X1144571D03*
Y1399079D03*
Y1386793D03*
X1143793Y1396583D03*
X1156033D03*
X1152633D03*
X1143793Y1408495D03*
X1156033D03*
X1152633D03*
X1143793D03*
X1156811Y1405999D03*
Y1410991D03*
X1151855Y1405999D03*
Y1410991D03*
X1144571Y1405999D03*
Y1410991D03*
X1152633Y1408495D03*
X1156033D03*
X1146960Y1465913D03*
Y1461182D03*
X1155621Y1465513D03*
Y1460782D03*
X1146960Y1456451D03*
X1155621Y1480867D03*
X1146960Y1471805D03*
Y1476536D03*
Y1481267D03*
X1155621Y1476136D03*
Y1470244D03*
Y1491490D03*
Y1485598D03*
Y1496221D03*
X1146960Y1487159D03*
Y1491890D03*
Y1496621D03*
Y1507245D03*
Y1502514D03*
X1155621Y1506845D03*
Y1500952D03*
Y1511576D03*
X1146960Y1511976D03*
X1155621Y1516307D03*
X1146960Y1563544D03*
X1155621Y1563144D03*
X1146960Y1558813D03*
X1155621Y1572606D03*
X1146960Y1568275D03*
X1155621Y1567875D03*
X1146960Y1574167D03*
Y1578898D03*
X1155621Y1578498D03*
X1146960Y1594253D03*
X1155621Y1593853D03*
Y1587960D03*
X1146960Y1583629D03*
X1155621Y1583229D03*
X1146960Y1589522D03*
Y1609607D03*
Y1604876D03*
Y1598984D03*
X1155621Y1609207D03*
Y1598584D03*
Y1603315D03*
X1146960Y1614338D03*
X1155621Y1613938D03*
Y1618669D03*
X1152000Y1644980D03*
X1165347Y82984D03*
Y75184D03*
Y77784D03*
Y80384D03*
X1167756Y92734D03*
X1165347Y85584D03*
X1164885Y95236D03*
Y102323D03*
X1165137Y109410D03*
Y116496D03*
X1165309Y124576D03*
X1166362Y130670D03*
X1171586Y137756D03*
X1166357D03*
X1173630Y207978D03*
Y210478D03*
Y212978D03*
Y215478D03*
Y226226D03*
Y223726D03*
Y228726D03*
Y231226D03*
X1173559Y304948D03*
X1171445Y422088D03*
X1168902Y431029D03*
X1167931Y435029D03*
X1169173Y427017D03*
X1168685Y438323D03*
X1168851Y449873D03*
X1171255Y456287D03*
X1168398Y456309D03*
X1168851Y445873D03*
X1170878Y474424D03*
X1173278Y472579D03*
X1168478D03*
X1170878Y474424D03*
Y477824D03*
Y488597D03*
Y491997D03*
X1173278Y479666D03*
X1168478D03*
Y486752D03*
X1173278D03*
X1170878Y477824D03*
Y488597D03*
X1168478Y493839D03*
X1173278D03*
X1170878Y491997D03*
Y518558D03*
Y521958D03*
X1168478Y523800D03*
Y516713D03*
X1173278D03*
Y523800D03*
X1170878Y518558D03*
Y521958D03*
Y532731D03*
Y536131D03*
X1173278Y537973D03*
X1168478D03*
X1173278Y530886D03*
X1168478D03*
X1170878Y532731D03*
Y536131D03*
X1161274Y550462D03*
X1159535Y546712D03*
Y542712D03*
X1165400Y553300D03*
X1167900D03*
X1170878Y571997D03*
Y568597D03*
X1173278Y566752D03*
X1168478D03*
X1170878Y571997D03*
Y568597D03*
Y586171D03*
Y582771D03*
X1168478Y580926D03*
X1173278D03*
Y588013D03*
X1168478D03*
X1173278Y573839D03*
X1168478D03*
X1170878Y586171D03*
Y582771D03*
Y596944D03*
Y600344D03*
X1168478Y602186D03*
X1173278D03*
Y595099D03*
X1168478D03*
X1170878Y596944D03*
Y600344D03*
Y614517D03*
Y611117D03*
X1173278Y609272D03*
X1168478D03*
Y616359D03*
X1173278D03*
X1170878Y614517D03*
Y611117D03*
X1161451Y618288D03*
X1163157Y638125D03*
X1160275Y656321D03*
X1164275D03*
X1162863Y678519D03*
X1159173Y678462D03*
X1170465Y677836D03*
X1157646Y699491D03*
X1162646D03*
X1160146D03*
X1169256Y694983D03*
X1170603Y715281D03*
X1163774Y713347D03*
X1166115Y718469D03*
X1163751Y719498D03*
X1168577Y733812D03*
X1171934Y733857D03*
X1173034Y765060D03*
X1157985Y791142D03*
X1161291Y791662D03*
X1173697Y791911D03*
X1169697Y791935D03*
X1164925Y791607D03*
X1160516Y800900D03*
X1169266Y800799D03*
X1159887Y869106D03*
X1168273Y1348187D03*
X1164873D03*
X1169051Y1345597D03*
Y1350683D03*
X1164095D03*
Y1345597D03*
X1168273Y1348187D03*
X1164873D03*
Y1360099D03*
X1168273D03*
X1164873D03*
X1169051Y1357603D03*
Y1362595D03*
X1164095Y1357603D03*
Y1362595D03*
X1168273Y1360099D03*
Y1384297D03*
X1164873D03*
X1168273Y1372385D03*
X1164873D03*
X1169051Y1381801D03*
Y1374881D03*
Y1369889D03*
X1164095D03*
Y1381801D03*
Y1374881D03*
X1168273Y1384297D03*
X1164873D03*
X1168273Y1372385D03*
X1164873D03*
Y1396583D03*
X1168273D03*
X1169051Y1393993D03*
Y1399079D03*
Y1386793D03*
X1164095Y1393993D03*
Y1399079D03*
Y1386793D03*
X1164873Y1396583D03*
X1168273D03*
Y1408495D03*
X1164873D03*
X1168273D03*
X1169051Y1410991D03*
Y1405999D03*
X1164095D03*
Y1410991D03*
X1164873Y1408495D03*
X1164283Y1465913D03*
Y1456451D03*
Y1461182D03*
X1172944Y1465513D03*
Y1460782D03*
Y1470244D03*
Y1480867D03*
X1164283Y1471805D03*
Y1476536D03*
Y1481267D03*
X1172944Y1476136D03*
X1164283Y1487159D03*
Y1491890D03*
Y1496621D03*
X1172944Y1491490D03*
Y1485598D03*
Y1496221D03*
X1164283Y1507245D03*
Y1502514D03*
X1172944Y1506845D03*
Y1500952D03*
Y1511576D03*
X1164283Y1511976D03*
X1172944Y1516307D03*
X1164283Y1558813D03*
Y1563544D03*
X1172944Y1563144D03*
Y1567875D03*
X1164283Y1574167D03*
Y1578898D03*
X1172944Y1578498D03*
Y1572606D03*
X1164283Y1568275D03*
Y1583629D03*
X1172944Y1583229D03*
X1164283Y1589522D03*
Y1594253D03*
X1172944Y1593853D03*
Y1587960D03*
Y1598584D03*
Y1603315D03*
X1164283Y1609607D03*
Y1604876D03*
Y1598984D03*
X1172944Y1609207D03*
X1164283Y1614338D03*
X1172944Y1613938D03*
Y1618669D03*
X1172000Y1644980D03*
X1174535Y53597D03*
X1183682Y85193D03*
Y82593D03*
Y74793D03*
Y79993D03*
Y77393D03*
X1188278Y94017D03*
X1174818Y95236D03*
X1174861Y103037D03*
X1174995Y116496D03*
Y109410D03*
X1182995Y116496D03*
Y109410D03*
Y102323D03*
X1185753Y107649D03*
Y104249D03*
X1174995Y130670D03*
Y123583D03*
X1182995Y130670D03*
Y123583D03*
Y137756D03*
X1182775Y162368D03*
X1185375D03*
X1188158Y211695D03*
X1184086Y210713D03*
Y213213D03*
Y208213D03*
X1188158Y208695D03*
X1184086Y231461D03*
Y228961D03*
X1187793Y226141D03*
X1184086Y226461D03*
Y215713D03*
X1188036Y236611D03*
X1187738Y248891D03*
X1176959Y264180D03*
X1179459D03*
X1177035Y257919D03*
X1185853Y267526D03*
X1188653D03*
X1185853Y270026D03*
X1188653D03*
X1179676Y293796D03*
X1187690Y288190D03*
X1185190Y285690D03*
X1187690D03*
X1185190Y288190D03*
X1177176Y293796D03*
X1176858Y306534D03*
X1179901Y306366D03*
X1181706Y310131D03*
X1178045Y312193D03*
X1181379Y316049D03*
X1174929Y319167D03*
X1182911Y336516D03*
X1177036Y334148D03*
X1179761Y336380D03*
X1187996Y331992D03*
X1188598Y390500D03*
Y381500D03*
X1179184Y410394D03*
X1180118Y430098D03*
Y440098D03*
Y437598D03*
Y435098D03*
Y432598D03*
X1178083Y442856D03*
X1189122Y442606D03*
X1180578Y458406D03*
Y451319D03*
X1179184Y453881D03*
Y446595D03*
X1188739Y446606D03*
X1178178Y467337D03*
Y470737D03*
X1188378Y466027D03*
X1180402Y462264D03*
X1175778Y465492D03*
X1180578D03*
X1188520Y475262D03*
X1175778Y472579D03*
X1180578D03*
X1178178Y467337D03*
Y470737D03*
X1190046Y463479D03*
X1178178Y481510D03*
Y484910D03*
X1188520Y489435D03*
Y482666D03*
X1175778Y479666D03*
X1180578Y479665D03*
Y486752D03*
X1175778D03*
X1178178Y484910D03*
Y481510D03*
X1180578Y493839D03*
X1188336Y495088D03*
X1178178Y511471D03*
Y514871D03*
Y525644D03*
X1175778Y509626D03*
X1180578Y523799D03*
Y516713D03*
Y509626D03*
X1175778Y516713D03*
Y523800D03*
X1189071Y514608D03*
X1188993Y522134D03*
X1188378Y509626D03*
X1178178Y511471D03*
Y514871D03*
Y529044D03*
X1180578Y537973D03*
X1175778Y530886D03*
X1180578D03*
X1189475Y535677D03*
X1189636Y529136D03*
X1178178Y529044D03*
Y525644D03*
Y564910D03*
Y561510D03*
X1180578Y559665D03*
Y566752D03*
X1175778D03*
Y559665D03*
X1188378D03*
X1188759Y565574D03*
X1178178Y564910D03*
Y561510D03*
Y575684D03*
Y579084D03*
Y589857D03*
X1175778Y580926D03*
X1180578D03*
Y588012D03*
X1175778D03*
X1180578Y573839D03*
X1175778D03*
X1188406Y574338D03*
X1178178Y579084D03*
Y575684D03*
Y604030D03*
Y593257D03*
X1175778Y602185D03*
X1180578D03*
X1175778Y595099D03*
X1180578D03*
X1178178Y604030D03*
Y593257D03*
Y589857D03*
Y607430D03*
X1175778Y609272D03*
X1180578Y616358D03*
Y609272D03*
X1188505Y616358D03*
X1178178Y607430D03*
X1177745Y771744D03*
X1174595D03*
X1176500Y784933D03*
X1190062Y844378D03*
X1187703Y849734D03*
X1186742Y855466D03*
X1183431Y868340D03*
X1187431D03*
X1180239Y868430D03*
X1177775Y894053D03*
X1176577Y885974D03*
X1179858Y883455D03*
X1179727Y886197D03*
X1181654Y894671D03*
X1185058Y883475D03*
X1178480Y915220D03*
X1187151Y921000D03*
X1178000Y936500D03*
X1188431Y936568D03*
X1182000Y936500D03*
X1189219Y940703D03*
X1187200Y963400D03*
X1180513Y1348187D03*
X1177113D03*
X1181291Y1350683D03*
Y1345691D03*
X1176335D03*
Y1350683D03*
X1177113Y1348187D03*
X1180513D03*
Y1360099D03*
X1177113D03*
X1181291Y1362595D03*
Y1357603D03*
X1176335Y1362595D03*
Y1357603D03*
X1177113Y1360099D03*
X1180513D03*
Y1372385D03*
X1177113D03*
X1180513Y1384297D03*
X1177113D03*
D03*
X1181291Y1369889D03*
Y1381801D03*
Y1374881D03*
X1176335Y1369889D03*
Y1381801D03*
Y1374881D03*
X1180513Y1384297D03*
X1177113Y1372385D03*
X1180513D03*
X1177113Y1396583D03*
X1180513D03*
X1181291Y1386793D03*
Y1399079D03*
Y1394087D03*
X1176335Y1386793D03*
Y1399079D03*
Y1394087D03*
X1180513Y1396583D03*
X1177113D03*
X1180513Y1408495D03*
X1177113D03*
X1181291Y1405999D03*
Y1410991D03*
X1176335Y1405999D03*
Y1410991D03*
X1177113Y1408495D03*
X1180513D03*
X1181605Y1465913D03*
Y1456451D03*
Y1461182D03*
Y1471805D03*
Y1476536D03*
Y1481267D03*
Y1487159D03*
Y1491890D03*
Y1496621D03*
Y1507245D03*
Y1502514D03*
Y1511976D03*
Y1558813D03*
Y1563544D03*
Y1568275D03*
Y1574167D03*
Y1578898D03*
Y1583629D03*
Y1589522D03*
Y1594253D03*
Y1598984D03*
Y1609607D03*
Y1604876D03*
Y1614338D03*
X1193330Y5374D03*
X1192643Y24773D03*
Y44773D03*
X1205355Y84140D03*
Y76140D03*
Y80140D03*
X1196278Y94017D03*
X1200287D03*
X1192278D03*
X1192007Y101701D03*
Y98551D03*
X1194902Y111223D03*
Y114623D03*
X1205304Y118335D03*
X1194902Y114623D03*
Y111223D03*
X1202808Y117557D03*
X1197398Y110445D03*
Y115401D03*
X1192406Y110445D03*
Y115401D03*
X1199557Y103783D03*
X1195557D03*
X1202492Y106186D03*
X1205304Y132509D03*
Y121735D03*
X1194902Y125396D03*
Y128796D03*
X1205304Y135909D03*
Y118335D03*
Y121735D03*
X1194902Y128796D03*
X1205304Y132509D03*
X1197398Y129574D03*
Y124618D03*
X1192406D03*
Y129574D03*
X1202808Y122513D03*
Y131731D03*
X1194902Y125396D03*
X1205304Y135909D03*
X1205899Y146461D03*
X1202808Y136687D03*
X1190319Y147540D03*
X1194091Y141247D03*
X1204801Y152367D03*
X1190319Y151540D03*
X1192475Y165393D03*
Y162793D03*
Y167993D03*
Y170493D03*
X1194683Y181366D03*
X1191472Y181426D03*
X1197478Y181009D03*
X1202653Y168697D03*
X1200469Y184619D03*
X1193969Y191941D03*
X1203741D03*
X1194297Y184012D03*
X1191680Y184221D03*
X1202449Y206760D03*
X1205750Y206767D03*
X1195716Y211359D03*
Y213859D03*
X1199419Y213132D03*
X1190658Y211695D03*
X1192055Y229286D03*
X1195748Y224712D03*
Y222212D03*
X1205295Y224421D03*
X1205880Y221708D03*
X1199419Y215632D03*
X1192055Y231786D03*
X1190536Y236611D03*
X1193036D03*
X1192738Y248891D03*
X1190238D03*
X1203663Y256535D03*
X1195663D03*
X1199663Y256303D03*
X1204693Y279208D03*
X1191153Y267526D03*
Y270026D03*
X1194716Y290755D03*
X1190490Y285690D03*
Y288190D03*
X1198716Y290755D03*
X1192500Y322400D03*
X1201113Y315039D03*
X1190127Y324142D03*
X1198248Y381500D03*
X1198468Y430760D03*
X1198489Y433570D03*
X1198305Y437072D03*
X1198346Y439963D03*
X1198552Y452018D03*
X1198590Y443180D03*
X1198610Y454744D03*
X1193000Y444841D03*
X1192686Y449961D03*
X1198689Y465492D03*
X1198655Y460250D03*
X1196420Y470136D03*
X1198689Y472579D03*
Y486752D03*
Y479665D03*
Y493839D03*
Y509626D03*
Y516713D03*
X1195149Y537973D03*
X1197629Y525483D03*
X1197550Y532756D03*
X1198689Y559665D03*
Y566752D03*
X1198539Y579978D03*
X1198689Y573839D03*
X1198753Y608117D03*
X1198997Y790610D03*
X1192431Y868620D03*
X1192152Y884399D03*
X1192367Y903785D03*
X1190210Y900909D03*
X1192990Y914873D03*
X1195118Y936296D03*
X1191151D03*
X1193219Y940703D03*
X1197173Y940645D03*
X1199615Y950670D03*
X1196352Y951033D03*
X1191219Y967757D03*
X1201794Y985289D03*
X1191928Y987314D03*
X1198644Y985289D03*
X1195757Y988131D03*
X1198845Y998504D03*
X1203419Y1011161D03*
X1200008D03*
X1196300Y998600D03*
X1202028Y998349D03*
X1204919Y1021860D03*
X1202268Y1013551D03*
X1199700Y1013661D03*
X1201800Y1019431D03*
X1190267Y1465513D03*
Y1460782D03*
X1198928Y1465914D03*
Y1456452D03*
Y1461183D03*
Y1481268D03*
X1190267Y1476136D03*
Y1470244D03*
Y1480867D03*
X1198928Y1476537D03*
Y1471806D03*
X1190267Y1485598D03*
Y1496221D03*
X1198928Y1491891D03*
Y1487160D03*
Y1496622D03*
X1190267Y1491490D03*
Y1506845D03*
Y1500952D03*
Y1511576D03*
X1198928Y1507246D03*
Y1502515D03*
Y1511977D03*
X1190267Y1516307D03*
X1198928Y1558813D03*
X1190267Y1563144D03*
X1198928Y1563544D03*
X1190267Y1567875D03*
X1198928Y1568275D03*
X1190267Y1578498D03*
Y1572606D03*
X1198928Y1578898D03*
Y1574167D03*
X1190267Y1583229D03*
X1198928Y1583629D03*
X1190267Y1593853D03*
Y1587960D03*
X1198928Y1594253D03*
Y1589522D03*
X1190267Y1609207D03*
Y1598584D03*
Y1603315D03*
X1198928Y1609607D03*
Y1598984D03*
Y1604876D03*
X1190267Y1613938D03*
Y1618669D03*
X1198928Y1614338D03*
X1192000Y1644980D03*
X1212232Y3000D03*
X1219783Y55513D03*
X1216008Y68581D03*
X1216021Y80581D03*
X1208103Y72615D03*
Y76587D03*
X1220126Y91951D03*
X1220151Y88801D03*
X1218730Y117261D03*
X1207800Y117557D03*
X1210724Y103621D03*
X1213915Y112083D03*
X1207800Y122513D03*
Y131731D03*
Y136687D03*
X1216858Y152562D03*
X1222353Y157370D03*
X1206501Y180572D03*
X1211184Y180527D03*
X1214907Y192421D03*
X1206501Y185165D03*
X1211139Y185121D03*
X1218536Y186629D03*
X1210268Y198671D03*
X1217070Y190185D03*
X1207753Y192300D03*
X1208250Y206767D03*
X1210750D03*
X1215230Y221642D03*
X1206995Y228221D03*
X1208380Y221708D03*
X1210880D03*
X1206995Y231021D03*
X1222110Y219379D03*
X1207546Y236189D03*
X1210046D03*
X1212546D03*
X1207487Y248765D03*
X1209987D03*
X1212487D03*
X1219144Y265897D03*
X1216644D03*
X1212984Y268195D03*
X1210184D03*
X1207684D03*
X1212984Y270695D03*
X1207684D03*
X1210184D03*
X1213287Y293645D03*
Y290845D03*
Y288345D03*
X1210787Y293645D03*
Y290845D03*
Y288345D03*
X1217139Y324139D03*
X1220723Y324466D03*
X1221337Y332017D03*
X1220985Y342319D03*
X1215776Y331072D03*
X1217177Y369925D03*
X1206693Y384410D03*
X1206673Y410394D03*
Y403307D03*
X1209426Y433069D03*
Y430469D03*
Y435669D03*
Y440869D03*
Y438269D03*
X1206626Y433069D03*
Y430469D03*
Y435669D03*
Y440869D03*
Y438269D03*
X1206489Y458406D03*
X1212680Y445908D03*
X1216630Y445787D03*
X1209980Y451677D03*
X1207480Y454177D03*
X1209980D03*
X1207480Y451677D03*
X1206489Y465492D03*
Y472579D03*
X1209184Y463618D03*
Y460218D03*
X1206489Y479665D03*
Y486752D03*
Y493839D03*
Y523799D03*
Y516713D03*
Y509626D03*
Y537973D03*
Y530886D03*
Y566752D03*
Y559665D03*
Y580925D03*
Y588012D03*
Y573839D03*
Y602185D03*
Y595099D03*
Y616358D03*
Y609272D03*
X1212000Y1644980D03*
X1225405Y-82678D03*
Y-79278D03*
X1231351Y-77080D03*
X1234592Y-79984D03*
X1234604Y-77094D03*
X1231336Y-87691D03*
X1234589Y-87777D03*
X1231351Y-85176D03*
X1234604Y-85262D03*
X1234592Y-82584D03*
X1228311Y-86371D03*
X1222909Y-83456D03*
Y-78500D03*
X1225405Y-79278D03*
Y-82678D03*
Y-72678D03*
Y-69278D03*
X1234592Y-71970D03*
X1231336Y-74565D03*
X1234589Y-74579D03*
X1231336Y-64265D03*
X1234589D03*
X1234592Y-69470D03*
X1231351Y-66780D03*
X1234604D03*
X1228311Y-65585D03*
Y-75885D03*
X1222909Y-68500D03*
Y-73456D03*
X1225405Y-72678D03*
Y-69278D03*
X1230761Y-43628D03*
X1236692Y-48727D03*
X1236707Y-46212D03*
X1233667Y-47421D03*
X1228265Y-44406D03*
X1230761Y-30228D03*
Y-40228D03*
Y-33628D03*
X1236692Y-35515D03*
X1236707Y-38030D03*
X1233667Y-36835D03*
X1228265Y-39450D03*
Y-29450D03*
Y-34406D03*
X1230761Y-33628D03*
Y-30228D03*
Y-43628D03*
Y-40228D03*
X1236692Y-25215D03*
X1236707Y-27730D03*
X1233667Y-26535D03*
X1232232Y3000D03*
X1222933Y55513D03*
X1228097Y60922D03*
X1225243Y60438D03*
X1225041Y97080D03*
X1230924Y94374D03*
X1226065Y86046D03*
X1223068Y94351D03*
X1230479Y102249D03*
X1234479D03*
X1228910Y110784D03*
X1226261Y113394D03*
X1238230Y116594D03*
X1226261D03*
X1229195Y130898D03*
X1236504Y133298D03*
X1238230Y119594D03*
X1226261D03*
X1230651Y134579D03*
X1225102Y161306D03*
X1226437Y180665D03*
Y172665D03*
Y176665D03*
Y168665D03*
X1236779Y195176D03*
X1236398Y198883D03*
X1234279Y195176D03*
X1231779D03*
X1226437Y192665D03*
X1226550Y186778D03*
X1234139Y203393D03*
X1231639D03*
X1226469Y200864D03*
Y212864D03*
X1237827Y206838D03*
X1226469Y204864D03*
Y216864D03*
Y221864D03*
X1231518Y218085D03*
X1234318D03*
X1238118Y216385D03*
X1228226Y252371D03*
Y248371D03*
X1238055Y303839D03*
X1229028Y311740D03*
X1234100Y322924D03*
X1224186Y316731D03*
X1229922Y324550D03*
X1234904Y316942D03*
X1232197Y316964D03*
X1238293Y317296D03*
X1230077Y336324D03*
X1229438Y332584D03*
X1234656Y353506D03*
X1231506Y353470D03*
X1223431Y377912D03*
X1225755Y369391D03*
X1229122Y369355D03*
X1222601Y369251D03*
X1223431Y393924D03*
Y389912D03*
Y385912D03*
Y381912D03*
Y409924D03*
Y405924D03*
Y401924D03*
Y397912D03*
X1235166Y467306D03*
Y470706D03*
X1232670Y466528D03*
X1237662D03*
X1232670Y471484D03*
X1237662D03*
X1235166Y470706D03*
Y467306D03*
Y481479D03*
Y484879D03*
X1237662Y480701D03*
X1232670D03*
Y485657D03*
X1237662D03*
X1235166Y484879D03*
Y481479D03*
Y514839D03*
Y511439D03*
Y525613D03*
X1232670Y515617D03*
X1237662D03*
X1232670Y510661D03*
X1237662D03*
X1235166Y514839D03*
Y511439D03*
Y529013D03*
X1237662Y524835D03*
Y529791D03*
X1232670Y524835D03*
Y529791D03*
X1235166Y529013D03*
Y525613D03*
X1232833Y539315D03*
X1232149Y550137D03*
X1234941D03*
X1235166Y564879D03*
Y561479D03*
X1232670Y565657D03*
Y560701D03*
X1237662Y565657D03*
Y560701D03*
X1235166Y564879D03*
Y561479D03*
Y575652D03*
Y579052D03*
Y589825D03*
X1232670Y579830D03*
X1237662Y589047D03*
X1232670D03*
X1237662Y574874D03*
X1232670D03*
X1237662Y579830D03*
X1235166Y575652D03*
Y579052D03*
Y603999D03*
Y593225D03*
X1237662Y603221D03*
X1232670D03*
Y594003D03*
X1237662D03*
X1235166Y593225D03*
Y603999D03*
Y589825D03*
Y607399D03*
X1237662Y608177D03*
X1232670D03*
X1235166Y607399D03*
X1235930Y626229D03*
X1235292Y622912D03*
X1237500Y632405D03*
X1238034Y629961D03*
X1238695Y627313D03*
X1230326Y1348187D03*
X1233726D03*
X1229548Y1350683D03*
Y1345691D03*
X1234504D03*
Y1350683D03*
X1230326Y1348187D03*
X1233726D03*
X1230326Y1360099D03*
X1233726D03*
X1229548Y1362595D03*
Y1357603D03*
X1234504D03*
Y1362595D03*
X1230326Y1360099D03*
X1233726D03*
X1230326Y1372385D03*
X1233726D03*
X1230326Y1384297D03*
X1233726D03*
X1230326Y1372385D03*
X1229548Y1369889D03*
Y1374881D03*
Y1381801D03*
X1234504Y1369889D03*
Y1374881D03*
Y1381801D03*
X1233726Y1372385D03*
X1230326Y1384297D03*
X1233726D03*
X1229548Y1386793D03*
X1234504D03*
X1232000Y1644980D03*
X1239945Y-48727D03*
X1239960Y-46212D03*
X1239948Y-32920D03*
X1239945Y-35529D03*
X1239948Y-30420D03*
Y-40934D03*
X1239960Y-38044D03*
X1239948Y-43534D03*
X1239945Y-25215D03*
X1239960Y-27730D03*
X1248216Y4469D03*
X1249577Y24773D03*
Y44773D03*
X1252097Y95111D03*
X1256947Y111255D03*
Y114655D03*
X1249647Y118342D03*
X1243503Y106495D03*
X1244496Y109172D03*
X1241496D03*
X1247247Y116497D03*
X1254547Y109410D03*
Y116497D03*
X1252047D03*
X1243503Y102495D03*
X1256947Y125428D03*
Y128828D03*
X1249647Y121742D03*
Y132515D03*
Y135915D03*
X1247247Y123584D03*
Y130670D03*
X1252047Y123584D03*
X1254547Y123583D03*
Y130670D03*
X1252047D03*
X1249647Y118342D03*
Y132515D03*
Y121742D03*
X1243237Y146012D03*
X1245143Y141228D03*
X1247247Y137757D03*
X1252047D03*
X1250307Y140296D03*
X1249647Y135915D03*
X1243237Y142862D03*
X1248031Y150847D03*
X1251826Y195176D03*
X1254326D03*
X1249326D03*
X1250844Y199248D03*
X1246826Y195176D03*
X1240327Y206838D03*
X1249407Y210509D03*
X1253844Y202048D03*
X1250844Y201748D03*
X1251180Y206806D03*
X1248680D03*
X1246907Y210509D03*
X1240831Y221970D03*
X1240897Y226320D03*
X1240831Y219470D03*
Y216970D03*
X1249999Y247292D03*
X1239823Y238589D03*
X1242789Y236121D03*
X1253460Y238714D03*
X1247584Y242078D03*
X1252941Y246874D03*
X1242815Y232971D03*
X1242708Y253198D03*
X1253245Y416888D03*
Y419488D03*
Y422088D03*
X1245568Y474418D03*
X1243072Y473640D03*
X1248064D03*
X1245568Y474418D03*
Y477818D03*
Y488591D03*
Y491991D03*
X1243072Y487813D03*
X1248064D03*
X1243072Y478596D03*
X1248064D03*
X1245568Y488591D03*
Y477818D03*
X1243072Y492769D03*
X1248064D03*
X1245568Y491991D03*
Y521952D03*
Y518552D03*
X1243072Y522730D03*
X1248064Y517774D03*
Y522730D03*
X1243072Y517774D03*
X1245568Y521952D03*
Y518552D03*
Y536125D03*
Y532725D03*
X1248064Y531947D03*
Y536903D03*
X1243072D03*
Y531947D03*
X1245568Y536125D03*
Y532725D03*
X1253087Y553101D03*
X1241629Y550065D03*
X1245568Y568591D03*
Y571991D03*
X1248064Y567813D03*
X1241752Y564843D03*
X1243072Y567813D03*
X1248064Y572769D03*
X1243072D03*
X1245568Y568591D03*
Y571991D03*
Y582765D03*
Y586165D03*
X1248064Y581987D03*
Y586943D03*
X1243072D03*
Y581987D03*
X1245568Y582765D03*
Y586165D03*
Y596938D03*
Y600338D03*
X1243072Y601116D03*
X1248064D03*
X1243072Y596160D03*
X1248064D03*
X1245568Y596938D03*
Y600338D03*
Y611111D03*
Y614511D03*
X1243072Y610333D03*
Y615289D03*
X1248064D03*
Y610333D03*
X1245568Y611111D03*
Y614511D03*
X1246800Y1001600D03*
X1248106Y1004700D03*
X1245400Y1003700D03*
X1249200Y1014000D03*
X1248721Y1025864D03*
X1246000Y1014800D03*
X1252148Y1026223D03*
X1252500Y1014288D03*
X1246300Y1027800D03*
X1253424Y1138130D03*
X1249363Y1173065D03*
X1251802Y1186071D03*
X1253056Y1194917D03*
X1254806Y1348187D03*
X1242566D03*
X1245966D03*
D03*
X1242566D03*
X1254028Y1350683D03*
Y1345691D03*
X1241788D03*
Y1350683D03*
X1246744Y1345691D03*
Y1350683D03*
X1254806Y1348187D03*
Y1360099D03*
X1245966D03*
X1242566D03*
X1254028Y1357603D03*
Y1362595D03*
X1241788D03*
Y1357603D03*
X1246744Y1362595D03*
Y1357603D03*
X1254806Y1360099D03*
X1242566D03*
X1245966D03*
X1254806Y1372385D03*
Y1384297D03*
X1245966D03*
X1242566D03*
X1245966Y1372385D03*
X1242566D03*
X1254806D03*
X1254028Y1381801D03*
Y1374881D03*
Y1369889D03*
X1241788Y1374881D03*
Y1369795D03*
Y1381801D03*
X1246744Y1374881D03*
Y1369795D03*
Y1381801D03*
X1242566Y1372385D03*
X1245966D03*
X1242566Y1384297D03*
X1245966D03*
X1254806D03*
Y1396583D03*
X1242566D03*
X1245966D03*
D03*
X1254028Y1386793D03*
Y1399079D03*
Y1394087D03*
X1241788Y1399079D03*
Y1393993D03*
Y1386793D03*
X1246744Y1393993D03*
Y1399079D03*
Y1386793D03*
X1254806Y1396583D03*
X1242566D03*
X1254806Y1408495D03*
X1245966D03*
X1242566D03*
X1254028Y1410991D03*
Y1405999D03*
X1241788Y1410991D03*
Y1405999D03*
X1246744Y1410991D03*
Y1405999D03*
X1254806Y1408495D03*
X1242566D03*
X1245966D03*
X1245900Y1528000D03*
X1256898Y53597D03*
X1267709Y82984D03*
Y75184D03*
Y77784D03*
Y80384D03*
X1270263Y92849D03*
X1267709Y85584D03*
X1267247Y95236D03*
X1267499Y116496D03*
X1259247D03*
Y102323D03*
Y109410D03*
X1267247Y102323D03*
X1267499Y109410D03*
X1256947Y114655D03*
Y111255D03*
X1256466Y106561D03*
X1267671Y124576D03*
X1268724Y130670D03*
X1259247D03*
Y123583D03*
X1256947Y128828D03*
Y125428D03*
X1268719Y137756D03*
X1259247D03*
X1255779Y213539D03*
X1257460Y238714D03*
X1255161Y244297D03*
X1264481Y300223D03*
X1266962Y302167D03*
X1262665Y302730D03*
X1263328Y309003D03*
X1258925Y324075D03*
X1262075D03*
X1261659Y318258D03*
X1264088Y320382D03*
X1259500Y330000D03*
X1257000Y333500D03*
X1264215Y333215D03*
X1262500Y330655D03*
X1256000Y338000D03*
X1259991Y340691D03*
X1256000Y340500D03*
X1266219Y374300D03*
X1268659Y377173D03*
X1264659D03*
X1267944Y371767D03*
X1261764Y391533D03*
X1264336Y412106D03*
X1268328Y421489D03*
Y418889D03*
Y416289D03*
X1261623Y447486D03*
X1259223Y458334D03*
X1270397Y447081D03*
X1259223Y454334D03*
X1267843Y473571D03*
Y488618D03*
Y491118D03*
Y481071D03*
Y478571D03*
Y476071D03*
Y493618D03*
X1270951Y491870D03*
X1269629Y848124D03*
X1270892Y856343D03*
X1271121Y892513D03*
X1270276Y897062D03*
X1269221Y894760D03*
X1270515Y908277D03*
X1269876Y1132319D03*
X1260539Y1134729D03*
X1267921D03*
X1263921D03*
X1263873Y1148000D03*
X1266709Y1160168D03*
X1258736Y1188223D03*
X1271246Y1178240D03*
X1268573Y1193019D03*
X1264573D03*
X1268571Y1201043D03*
X1264575D03*
X1261538Y1199814D03*
X1255296Y1196056D03*
X1263449Y1217228D03*
X1266113Y1219895D03*
X1269388Y1223170D03*
X1270446Y1348187D03*
X1267046D03*
X1258206D03*
X1267046D03*
X1270446D03*
X1266268Y1345691D03*
Y1350683D03*
X1258984D03*
Y1345691D03*
X1258206Y1348187D03*
X1270446Y1360099D03*
X1267046D03*
X1258206D03*
X1266268Y1362595D03*
Y1357603D03*
X1258984Y1362595D03*
Y1357603D03*
X1258206Y1360099D03*
X1270446D03*
X1267046D03*
Y1384297D03*
X1270446D03*
X1267046Y1372385D03*
X1270446D03*
X1258206D03*
Y1384297D03*
Y1372385D03*
X1266268Y1369889D03*
Y1374881D03*
Y1381801D03*
X1258984D03*
Y1369889D03*
Y1374881D03*
X1270446Y1372385D03*
X1267046D03*
X1270446Y1384297D03*
X1267046D03*
X1258206D03*
X1270446Y1396583D03*
X1267046D03*
X1258206D03*
X1267046D03*
X1270446D03*
X1266268Y1399079D03*
Y1394087D03*
Y1386793D03*
X1258984Y1394087D03*
Y1386793D03*
Y1399079D03*
X1258206Y1396583D03*
X1267046Y1408495D03*
X1270446D03*
X1258206D03*
X1266268Y1410991D03*
Y1405999D03*
X1258984D03*
Y1410991D03*
X1258206Y1408495D03*
X1270446D03*
X1267046D03*
X1263242Y1523458D03*
X1262985Y1519459D03*
X1260260Y1546500D03*
X1276898Y53597D03*
X1286044Y85539D03*
Y82939D03*
Y75139D03*
Y80339D03*
Y77739D03*
X1272809Y90615D03*
X1277180Y95236D03*
X1277223Y103037D03*
X1277357Y116496D03*
Y109410D03*
X1285357Y116496D03*
Y109410D03*
Y102323D03*
Y123583D03*
X1277357Y130670D03*
Y123583D03*
X1285357Y130670D03*
X1273555Y137756D03*
X1285357D03*
X1285137Y162368D03*
X1275992Y215478D03*
Y212978D03*
Y210478D03*
Y207978D03*
X1286448Y213213D03*
Y210713D03*
Y208213D03*
X1275992Y223726D03*
Y226226D03*
Y231226D03*
Y228726D03*
X1286448Y226461D03*
Y228961D03*
Y231461D03*
Y215713D03*
X1281821Y264180D03*
X1279321D03*
X1279246Y258880D03*
X1279538Y293796D03*
X1282038D03*
X1271571Y281185D03*
X1283494Y339495D03*
X1284419Y359377D03*
X1281834Y374839D03*
X1280699Y377173D03*
X1284659D03*
X1274436Y377350D03*
X1275940Y392228D03*
X1271346Y392183D03*
X1276659Y385123D03*
X1275407Y402867D03*
X1271391Y396866D03*
X1275984D03*
X1278724Y409032D03*
X1282760Y401066D03*
X1272421Y403300D03*
X1271828Y405889D03*
Y408489D03*
Y413689D03*
Y411089D03*
Y416289D03*
Y421489D03*
Y418889D03*
Y424089D03*
X1272215Y442518D03*
Y439718D03*
Y432718D03*
Y435518D03*
X1282092Y442118D03*
Y439318D03*
X1271828Y426689D03*
X1279127Y450091D03*
X1282092Y449118D03*
Y446318D03*
X1281737Y452740D03*
X1272927Y450091D03*
X1275927D03*
X1273397Y447081D03*
X1283455Y468088D03*
Y465288D03*
X1280616Y472189D03*
X1272927Y462060D03*
X1275927D03*
X1279505Y487570D03*
Y490070D03*
X1286005Y485580D03*
X1280631Y480194D03*
Y477694D03*
X1277897Y478876D03*
Y476376D03*
X1274415Y477053D03*
X1271915D03*
X1276060Y496258D03*
X1273451Y491870D03*
X1276060Y493758D03*
X1283400Y715500D03*
Y719700D03*
X1279539Y748576D03*
X1282539Y751076D03*
X1279539Y763576D03*
X1282539Y766076D03*
X1279539Y758576D03*
X1282539Y761076D03*
X1279539Y753576D03*
Y772576D03*
Y768576D03*
Y780576D03*
Y784576D03*
X1285092Y819500D03*
X1285500Y827500D03*
X1281388Y827388D03*
X1281331Y843331D03*
X1285500Y835500D03*
X1283025Y848305D03*
X1274417Y861964D03*
X1271438Y861846D03*
X1285500Y863500D03*
Y859500D03*
Y855500D03*
X1282317Y880193D03*
X1285500Y867500D03*
X1279460Y869487D03*
X1285302Y877283D03*
X1282285Y865602D03*
X1285493Y892175D03*
X1285302Y885783D03*
Y881783D03*
X1281075Y911075D03*
X1282184Y898854D03*
X1283494Y907176D03*
X1277039Y916484D03*
X1275493Y929858D03*
X1279493D03*
X1284021Y940008D03*
X1281400Y940256D03*
X1281733Y949475D03*
X1275788Y1124088D03*
X1273865Y1132497D03*
X1282421Y1137129D03*
X1271921Y1134729D03*
X1275794D03*
X1282830Y1146937D03*
Y1150087D03*
X1272120Y1159455D03*
X1280306Y1162817D03*
Y1170767D03*
X1276573Y1193019D03*
X1280573D03*
X1272573D03*
X1272541Y1201043D03*
X1276575Y1201039D03*
X1280575Y1200969D03*
X1277108Y1211664D03*
X1279402Y1213958D03*
X1284198Y1218754D03*
X1280694Y1208993D03*
X1274446Y1228226D03*
X1272235Y1226016D03*
X1282686Y1348187D03*
X1279286D03*
X1283464Y1345691D03*
Y1350683D03*
X1278508Y1345691D03*
Y1350683D03*
X1271224Y1345691D03*
Y1350683D03*
X1282686Y1348187D03*
X1279286D03*
Y1360099D03*
X1282686D03*
X1283464Y1362595D03*
Y1357603D03*
X1278508D03*
Y1362595D03*
X1271224D03*
Y1357603D03*
X1279286Y1360099D03*
X1282686D03*
X1279286Y1372385D03*
X1282686D03*
Y1384297D03*
X1279286D03*
Y1372385D03*
X1283464Y1381801D03*
Y1369889D03*
Y1374881D03*
X1278508Y1381801D03*
Y1369889D03*
Y1374881D03*
X1271224Y1369889D03*
Y1374881D03*
Y1381801D03*
X1282686Y1372385D03*
Y1384297D03*
X1279286D03*
Y1396583D03*
X1282686D03*
X1283464Y1386793D03*
Y1399079D03*
Y1394087D03*
X1278508Y1386793D03*
Y1399079D03*
Y1394087D03*
X1271224D03*
Y1399079D03*
Y1386793D03*
X1279286Y1396583D03*
X1282686D03*
X1279286Y1408495D03*
X1282686D03*
X1283464Y1410991D03*
Y1405999D03*
X1278508Y1410991D03*
Y1405999D03*
X1271224Y1410991D03*
Y1405999D03*
X1279286Y1408495D03*
X1282686D03*
X1297687Y-43656D03*
X1291756Y-48669D03*
X1288503D03*
X1291741Y-46154D03*
X1288488D03*
X1294781Y-47349D03*
X1300183Y-44434D03*
X1297687Y-33656D03*
Y-30256D03*
Y-40256D03*
X1288500Y-40964D03*
X1291756Y-38369D03*
X1288503Y-38355D03*
X1288500Y-43464D03*
X1291741Y-35854D03*
X1288500Y-32950D03*
X1288488Y-35840D03*
X1288500Y-30350D03*
X1294781Y-37049D03*
X1300183Y-29478D03*
Y-34434D03*
Y-39478D03*
X1297687Y-33656D03*
Y-40256D03*
Y-30256D03*
Y-43656D03*
X1291756Y-25143D03*
X1288503Y-25157D03*
X1291741Y-27658D03*
X1288488Y-27672D03*
X1294781Y-26463D03*
X1302232Y3000D03*
X1295692Y5374D03*
X1303229Y23274D03*
X1295005Y24773D03*
X1297785Y30618D03*
Y33768D03*
X1302785Y31168D03*
X1295005Y44773D03*
X1302649Y94017D03*
X1298640D03*
X1290640D03*
X1294369Y101701D03*
X1294640Y94017D03*
X1294369Y98551D03*
X1297264Y111223D03*
Y114623D03*
D03*
Y111223D03*
X1301919Y103783D03*
X1299760Y110445D03*
Y115401D03*
X1294768Y110445D03*
Y115401D03*
X1297919Y103783D03*
X1288115Y104249D03*
Y107649D03*
X1297264Y125396D03*
Y128796D03*
D03*
Y125396D03*
X1294768Y129574D03*
X1299760D03*
Y124618D03*
X1294768D03*
X1294837Y162793D03*
X1287737Y162368D03*
X1294837Y165393D03*
Y167993D03*
Y170493D03*
X1299840Y181009D03*
X1293834Y181426D03*
X1297045Y181366D03*
X1296331Y191941D03*
X1302831Y184619D03*
X1294042Y184221D03*
X1296659Y184012D03*
X1301781Y213132D03*
X1298078Y211359D03*
Y213859D03*
X1290520Y211695D03*
X1293020D03*
X1290520Y208695D03*
X1290155Y226141D03*
X1294417Y229286D03*
X1298110Y222212D03*
Y224712D03*
X1301781Y215632D03*
X1290398Y236611D03*
X1295398D03*
X1292898D03*
X1294417Y231786D03*
X1298025Y256535D03*
X1290100Y248891D03*
X1292600D03*
X1295100D03*
X1302025Y256303D03*
X1293515Y270026D03*
X1291015D03*
X1288215D03*
Y267526D03*
X1293515D03*
X1291015D03*
X1290052Y288190D03*
X1292852D03*
Y285690D03*
X1297078Y290755D03*
X1301078D03*
X1287552Y288190D03*
X1290052Y285690D03*
X1287552D03*
X1301500Y329000D03*
X1294425Y321425D03*
X1294000Y324000D03*
X1303000Y326692D03*
X1292731Y331820D03*
X1300400Y339619D03*
Y344575D03*
X1293000Y338500D03*
X1303000Y331000D03*
X1302896Y343797D03*
Y340397D03*
X1299959Y351454D03*
X1294080Y349820D03*
X1303158Y371043D03*
X1291410Y371060D03*
X1295410Y371076D03*
X1291165Y395248D03*
X1293100Y409539D03*
X1296100D03*
Y407039D03*
X1295764Y401981D03*
X1298264D03*
X1300037Y398278D03*
X1297537D03*
X1292618Y413611D03*
X1295118D03*
X1300118D03*
X1297618D03*
X1292383Y424067D03*
X1294883D03*
X1299883D03*
X1297383D03*
X1299757Y438293D03*
Y441093D03*
X1290092Y442118D03*
Y439318D03*
Y449118D03*
Y446318D03*
X1299757Y450041D03*
Y452841D03*
Y455641D03*
X1290272Y458309D03*
Y454309D03*
X1299757Y443893D03*
X1290272Y462309D03*
X1287719Y470001D03*
X1290219D03*
X1288144Y489036D03*
X1291005Y485580D03*
X1288505D03*
X1301314Y484882D03*
X1290380Y495636D03*
Y492836D03*
X1296783Y511956D03*
X1300817Y568635D03*
X1289317Y706932D03*
X1295491Y798821D03*
X1290066Y804246D03*
X1289730Y806845D03*
X1300516Y832047D03*
X1300504Y835985D03*
X1300204Y859088D03*
X1300097Y851193D03*
X1300091Y854824D03*
X1293500Y879800D03*
Y871800D03*
Y875800D03*
X1288164Y892354D03*
X1296866Y894993D03*
X1293272Y887800D03*
X1293500Y883800D03*
X1291955Y901295D03*
X1294264Y905595D03*
X1301657Y899129D03*
X1288500Y901254D03*
X1298966Y899610D03*
X1296466D03*
X1289547Y928047D03*
X1298000Y917000D03*
X1294075D03*
X1292500Y928000D03*
X1298090Y940852D03*
X1295453Y940953D03*
X1302500Y939500D03*
X1296500Y961500D03*
X1289500Y949500D03*
X1300500Y960000D03*
X1290792Y961363D03*
X1300500Y970187D03*
X1292836Y975244D03*
X1292631Y979845D03*
X1299717Y1024136D03*
X1297852Y1014475D03*
X1295815Y1124943D03*
X1295893Y1122182D03*
X1294926Y1348187D03*
X1291526D03*
X1303766D03*
X1291526D03*
X1302988Y1345691D03*
Y1350683D03*
X1290748D03*
Y1345691D03*
X1295704Y1350683D03*
Y1345691D03*
X1294926Y1348187D03*
X1303766Y1360099D03*
X1294926D03*
X1291526D03*
X1302988Y1362595D03*
Y1357603D03*
X1290748Y1362595D03*
Y1357603D03*
X1295704Y1362595D03*
Y1357603D03*
X1291526Y1360099D03*
X1294926D03*
Y1384297D03*
X1291526D03*
X1294926Y1372385D03*
X1291526D03*
X1303766D03*
Y1384297D03*
X1302988Y1374881D03*
Y1381801D03*
Y1369889D03*
X1290748D03*
Y1381801D03*
Y1374881D03*
X1295704Y1381801D03*
Y1374881D03*
Y1369889D03*
X1291526Y1372385D03*
X1294926D03*
X1291526Y1384297D03*
X1294926D03*
X1303766Y1396583D03*
X1291526D03*
X1294926D03*
D03*
X1291526D03*
X1302988Y1386793D03*
Y1399079D03*
Y1394087D03*
X1290748Y1399079D03*
Y1394087D03*
Y1386793D03*
X1295704Y1394087D03*
Y1399079D03*
Y1386793D03*
X1294926Y1408495D03*
X1291526D03*
X1303766D03*
X1302988Y1410991D03*
Y1405999D03*
X1290748Y1410991D03*
Y1405999D03*
X1295704Y1410991D03*
Y1405999D03*
X1291526Y1408495D03*
X1294926D03*
X1302866Y1461182D03*
Y1456451D03*
Y1465913D03*
Y1476536D03*
Y1471805D03*
Y1481267D03*
Y1491890D03*
Y1487159D03*
Y1496621D03*
Y1507245D03*
Y1502514D03*
Y1511976D03*
Y1558813D03*
Y1563544D03*
Y1578898D03*
Y1574167D03*
Y1568275D03*
Y1594253D03*
Y1589522D03*
Y1583629D03*
Y1609607D03*
Y1598984D03*
Y1604876D03*
Y1614338D03*
X1292000Y1644980D03*
X1310853Y37543D03*
X1318859Y45448D03*
X1307717Y84140D03*
Y76140D03*
Y80140D03*
X1307666Y118335D03*
X1310162Y117557D03*
X1305170D03*
X1313086Y103621D03*
X1304854Y106186D03*
X1316277Y112083D03*
X1307666Y121735D03*
Y132509D03*
Y135909D03*
Y118335D03*
Y132509D03*
Y121735D03*
X1310162Y122513D03*
Y131731D03*
X1305170Y122513D03*
Y131731D03*
X1307666Y135909D03*
X1310162Y136687D03*
X1305170D03*
X1313546Y180527D03*
X1308863Y180572D03*
X1305015Y168697D03*
X1308863Y185165D03*
X1317269Y192421D03*
X1313501Y185121D03*
X1306103Y191941D03*
X1319432Y190185D03*
X1310115Y192300D03*
X1304811Y206760D03*
X1308112Y206767D03*
X1313112D03*
X1310612D03*
X1313242Y221708D03*
X1310742D03*
X1309357Y228221D03*
X1317592Y221642D03*
X1308242Y221708D03*
X1307657Y224421D03*
X1309908Y236189D03*
X1314908D03*
X1312408D03*
X1306025Y256535D03*
X1312349Y248765D03*
X1309849D03*
X1314849D03*
X1307055Y279208D03*
X1310046Y268195D03*
X1312546D03*
X1315346D03*
X1319006Y265897D03*
X1312546Y270695D03*
X1310046D03*
X1315346D03*
X1313149Y288345D03*
Y290845D03*
Y293645D03*
X1315649Y288345D03*
Y290845D03*
Y293645D03*
X1318362Y310562D03*
X1314569Y318013D03*
X1312069D03*
X1317584Y313058D03*
X1305928Y318250D03*
X1308428D03*
X1315256Y336510D03*
X1315397Y333709D03*
X1316017Y349889D03*
X1308410Y370899D03*
X1305910Y377581D03*
X1310172Y367956D03*
X1311283Y370801D03*
X1308826Y389402D03*
X1306113Y383817D03*
X1312626Y387702D03*
X1315426D03*
X1306113Y386317D03*
Y388817D03*
X1313691Y402642D03*
X1316191D03*
X1310546Y409904D03*
X1309117Y398949D03*
X1306617Y401949D03*
X1310866Y413611D03*
X1313366D03*
X1315866D03*
X1315806Y423944D03*
X1313306D03*
X1310806D03*
X1309750Y438293D03*
Y441093D03*
Y455641D03*
Y450041D03*
Y452841D03*
Y443893D03*
X1308010Y466409D03*
X1311488Y471560D03*
X1307835Y470382D03*
X1307996Y487382D03*
X1311488Y479560D03*
X1307919Y478382D03*
X1307825Y482382D03*
X1311488Y475560D03*
X1318160Y520053D03*
X1317945Y523058D03*
X1319000Y566500D03*
Y562500D03*
Y558500D03*
Y582500D03*
Y586500D03*
Y574500D03*
Y578500D03*
Y605000D03*
Y590500D03*
Y613000D03*
Y621000D03*
Y609000D03*
Y629000D03*
Y633000D03*
Y625000D03*
Y637000D03*
Y653500D03*
Y649500D03*
Y657500D03*
Y669500D03*
Y665500D03*
Y673500D03*
Y681500D03*
Y677500D03*
Y696500D03*
Y700500D03*
Y704500D03*
Y712500D03*
Y716500D03*
Y720500D03*
Y724500D03*
Y728500D03*
Y732500D03*
X1305412Y799061D03*
X1317000Y788000D03*
X1313000D03*
X1305134Y812065D03*
X1319000Y811620D03*
X1317000Y804000D03*
X1313000D03*
X1313756Y829871D03*
X1310715Y820491D03*
Y822991D03*
Y817991D03*
X1316906Y829871D03*
X1310687Y830206D03*
Y832706D03*
Y827706D03*
X1308857Y836076D03*
X1316906Y842470D03*
Y833021D03*
Y848769D03*
X1310971Y842319D03*
X1313756Y833021D03*
Y836170D03*
X1316906Y839320D03*
X1310555Y848675D03*
X1313756Y848769D03*
X1316906Y836170D03*
X1313756Y842470D03*
Y858218D03*
X1316906Y855068D03*
X1313756Y855066D03*
X1316906Y858218D03*
Y867665D03*
X1305786Y867704D03*
X1310994Y866859D03*
X1309753Y877589D03*
X1305740Y877534D03*
X1310535Y870775D03*
X1316906Y883413D03*
Y892862D03*
X1308220Y889253D03*
X1311061Y889361D03*
X1309856Y899161D03*
X1305761D03*
X1313756D03*
X1319500Y901500D03*
X1305356Y902597D03*
X1319500Y905000D03*
X1316893Y925603D03*
X1313867Y925605D03*
X1311325Y928918D03*
X1319554Y925585D03*
X1318375Y943951D03*
X1309103Y936559D03*
X1306500Y936500D03*
X1315779Y943743D03*
X1303907Y960093D03*
X1311000Y961500D03*
X1307000Y970000D03*
X1307580Y990314D03*
X1317254Y990777D03*
X1317053Y988111D03*
X1319874Y989856D03*
X1304664Y1023462D03*
X1309937Y1037038D03*
X1319326Y1040723D03*
X1315606Y1042825D03*
X1312873Y1036543D03*
X1319221Y1058097D03*
Y1060697D03*
X1313459Y1081599D03*
X1310589Y1097278D03*
X1313089D03*
X1316869Y1107997D03*
X1319069Y1112397D03*
X1318969Y1109397D03*
X1316869Y1113797D03*
Y1110897D03*
X1317437Y1152684D03*
Y1160834D03*
X1318178Y1198321D03*
Y1200821D03*
Y1192621D03*
Y1190121D03*
X1319237Y1221428D03*
X1311237D03*
X1315237D03*
X1311237Y1233428D03*
Y1229428D03*
Y1225428D03*
X1315237Y1237428D03*
Y1233428D03*
Y1229428D03*
Y1225428D03*
X1319237Y1237428D03*
Y1233428D03*
Y1229428D03*
X1307167Y1245696D03*
X1315237Y1241428D03*
X1319237D03*
X1308276Y1276446D03*
X1308107Y1283395D03*
X1310773Y1282411D03*
X1303900Y1288000D03*
X1318287Y1295381D03*
X1316006Y1348187D03*
X1319406D03*
X1307166D03*
X1319406D03*
X1316006D03*
X1315228Y1345691D03*
Y1350683D03*
X1307944D03*
Y1345691D03*
X1307166Y1348187D03*
X1303766D03*
X1319406Y1360099D03*
X1316006D03*
X1307166D03*
X1319406D03*
X1315228Y1362595D03*
Y1357603D03*
X1307944D03*
Y1362595D03*
X1316006Y1360099D03*
X1307166D03*
X1303766D03*
X1319406Y1384297D03*
X1316006D03*
X1319406Y1372385D03*
X1316006D03*
X1307166D03*
Y1384297D03*
X1316006Y1372385D03*
X1307166D03*
X1303766D03*
Y1384297D03*
X1315228Y1381801D03*
Y1369889D03*
Y1374881D03*
X1307944D03*
Y1381801D03*
Y1369889D03*
X1307166Y1384297D03*
X1319406Y1372385D03*
X1316006Y1384297D03*
X1319406D03*
Y1396583D03*
X1316006D03*
X1307166D03*
X1319406D03*
X1316006D03*
X1315228Y1399079D03*
Y1394087D03*
Y1386793D03*
X1307944D03*
Y1399079D03*
Y1394087D03*
X1303766Y1396583D03*
X1307166D03*
X1319406Y1408495D03*
X1316006D03*
X1307166D03*
X1315228Y1410991D03*
Y1405999D03*
X1307944Y1410991D03*
Y1405999D03*
X1316006Y1408495D03*
X1319406D03*
X1307166D03*
X1303766D03*
X1311527Y1465513D03*
Y1460782D03*
Y1480867D03*
Y1476136D03*
Y1470244D03*
Y1491490D03*
Y1485598D03*
Y1496221D03*
Y1506845D03*
Y1500952D03*
Y1511576D03*
Y1516307D03*
Y1563144D03*
Y1567875D03*
Y1578498D03*
Y1572606D03*
Y1583229D03*
Y1593853D03*
Y1587960D03*
Y1609207D03*
Y1598584D03*
Y1603315D03*
Y1613938D03*
Y1618669D03*
X1312000Y1644980D03*
X1337687Y-82706D03*
Y-79306D03*
X1328500Y-80100D03*
X1331756Y-77419D03*
X1328503Y-77405D03*
X1331756Y-87805D03*
X1328503D03*
X1328500Y-82600D03*
X1331741Y-85290D03*
X1328488D03*
X1334781Y-86499D03*
X1337687Y-69306D03*
Y-72706D03*
X1331741Y-74904D03*
X1328500Y-72000D03*
X1328488Y-74890D03*
X1331756Y-64193D03*
X1328503Y-64207D03*
X1331741Y-66708D03*
X1328488Y-66722D03*
X1328500Y-69400D03*
X1334781Y-76099D03*
Y-65513D03*
X1322232Y3000D03*
X1334223Y33425D03*
X1331073Y33400D03*
X1322853Y37530D03*
X1321092Y117261D03*
X1328799Y172665D03*
Y180665D03*
Y168665D03*
Y176665D03*
X1320898Y186629D03*
X1328799Y192665D03*
Y196665D03*
X1328912Y186778D03*
X1328831Y212864D03*
Y200864D03*
Y204864D03*
Y221864D03*
Y216864D03*
X1324472Y219379D03*
X1321506Y265897D03*
X1330414Y310058D03*
X1325458D03*
X1334110Y310562D03*
X1321762D03*
X1329636Y307562D03*
X1326236D03*
X1322540Y313058D03*
X1333332D03*
X1332563Y326356D03*
X1325573Y326719D03*
X1331085Y334347D03*
X1323816D03*
Y341615D03*
X1331085Y348868D03*
X1323816D03*
X1326489Y356945D03*
X1331005Y356670D03*
X1320903Y370995D03*
X1333331Y370905D03*
X1329064Y370951D03*
X1325007D03*
X1334109Y373401D03*
X1334285Y386567D03*
X1331606D03*
X1328896D03*
X1320594Y387151D03*
Y382151D03*
Y384651D03*
X1333049Y399268D03*
Y401768D03*
Y396768D03*
X1321016Y399161D03*
Y401661D03*
Y396661D03*
X1325941Y408240D03*
X1328441D03*
X1323441D03*
X1326059Y420393D03*
X1326020Y424240D03*
X1323559Y420393D03*
X1328559D03*
X1326020Y426740D03*
X1329097Y435321D03*
Y438121D03*
X1326297Y435321D03*
Y438121D03*
X1329097Y440921D03*
X1326297D03*
X1329626Y455039D03*
X1329097Y443721D03*
X1326297D03*
X1332927Y468607D03*
X1325927Y474513D03*
X1329606Y459170D03*
X1326912Y493153D03*
X1325630Y513238D03*
X1321450Y520268D03*
X1321164Y523130D03*
X1331096Y549931D03*
X1335000Y586500D03*
Y594500D03*
X1327000Y609000D03*
Y621000D03*
X1335000Y637000D03*
Y641000D03*
X1327011Y646064D03*
X1335000Y677500D03*
Y681500D03*
Y685500D03*
Y724500D03*
Y728500D03*
Y732500D03*
X1326970Y736464D03*
X1330324Y779030D03*
X1333000Y788000D03*
X1329000D03*
X1321000D03*
X1325000D03*
X1331000Y811620D03*
X1327000D03*
X1329000Y804000D03*
X1325000D03*
X1333000D03*
X1323000Y811620D03*
X1335000D03*
X1335803Y826500D03*
Y829871D03*
X1323205D03*
X1332654Y836170D03*
X1326355Y839320D03*
X1335803D03*
X1329504Y833021D03*
X1332654Y842470D03*
X1329504Y845619D03*
X1332654D03*
X1326355Y836170D03*
X1335803Y842470D03*
X1329504Y836170D03*
X1335803Y845619D03*
Y848769D03*
X1329504Y839320D03*
X1323205Y836170D03*
X1335803D03*
X1329504Y842470D03*
X1335803Y833021D03*
X1323205D03*
X1320055Y845619D03*
X1326355D03*
X1320055Y836170D03*
X1326355Y842470D03*
X1320055Y848769D03*
X1323205Y845619D03*
X1332654Y848769D03*
X1320055Y839320D03*
X1326355Y848769D03*
X1323205D03*
X1329504D03*
X1323204Y839319D03*
X1332654Y839320D03*
X1320055Y842470D03*
X1323205D03*
Y861367D03*
X1335803Y851918D03*
X1329504Y855068D03*
Y858218D03*
X1320055Y851918D03*
X1332654Y855068D03*
X1326355D03*
Y858218D03*
X1329504Y861367D03*
X1323205Y858218D03*
X1320055D03*
X1332654Y861367D03*
X1329504Y851918D03*
X1323205D03*
X1326355Y861367D03*
X1320055Y855068D03*
X1332654Y858218D03*
X1335803Y855068D03*
Y858218D03*
Y861367D03*
X1320055D03*
X1323204Y855067D03*
X1326355Y851918D03*
X1332654D03*
X1335803Y877114D03*
X1326355Y880263D03*
X1329504Y877114D03*
X1335803Y880263D03*
X1326355Y867665D03*
Y870814D03*
X1323205D03*
X1320055D03*
X1329504Y867665D03*
X1326355Y873964D03*
X1332654Y880263D03*
X1329504D03*
X1332654Y877114D03*
X1326355D03*
X1329504Y870814D03*
X1320055Y873964D03*
X1332654Y870814D03*
X1323204Y873965D03*
X1332654Y867665D03*
X1320055Y880263D03*
Y867665D03*
X1323205Y880263D03*
Y877114D03*
X1320055D03*
X1335803Y867665D03*
Y873964D03*
Y870814D03*
X1332654Y873964D03*
X1329504D03*
X1335802Y896011D03*
X1326355Y886562D03*
X1323205D03*
X1326355Y889712D03*
X1335803Y883413D03*
X1329504Y892862D03*
X1332654Y889712D03*
X1335803Y892862D03*
Y889712D03*
X1326355Y892862D03*
X1329504Y889712D03*
X1320055Y892862D03*
X1323205D03*
X1329504Y886562D03*
X1332654Y883413D03*
X1320055Y886562D03*
X1326355Y883413D03*
X1323205D03*
X1332654Y892862D03*
X1320055Y883413D03*
X1332654Y886562D03*
X1335803D03*
X1320055Y889712D03*
X1323204Y889713D03*
X1329504Y883413D03*
X1331056Y904557D03*
X1336000Y900500D03*
X1324000Y901000D03*
X1331078Y900500D03*
X1330500Y925500D03*
X1334500D03*
X1333425Y930925D03*
X1324000D03*
X1329199Y933825D03*
X1328457Y959986D03*
X1335343Y961727D03*
X1321028Y961749D03*
X1332500Y961500D03*
X1321104Y964398D03*
X1323554Y967623D03*
X1332000Y969500D03*
X1327000D03*
X1329503Y991088D03*
X1334909Y990340D03*
X1332404Y988215D03*
X1329834Y988132D03*
X1324735Y989966D03*
X1327267Y988271D03*
X1322427Y988221D03*
X1333974Y1033483D03*
X1320549Y1037876D03*
X1322773Y1040599D03*
X1331890Y1051919D03*
X1329221Y1058097D03*
X1321721D03*
X1324221D03*
X1326721D03*
Y1060697D03*
X1329221D03*
X1321721D03*
X1324221D03*
X1326163Y1082501D03*
X1326189Y1085205D03*
X1329163Y1082501D03*
X1329189Y1085205D03*
X1326189Y1088205D03*
X1326471Y1091227D03*
X1323189Y1085205D03*
Y1087705D03*
X1323163Y1082501D03*
X1323021Y1090956D03*
X1331359Y1098898D03*
X1334956Y1105552D03*
X1321069Y1107997D03*
X1323021Y1093956D03*
X1331162Y1104792D03*
X1332355Y1113822D03*
Y1119422D03*
X1334835Y1113822D03*
Y1119422D03*
X1333905Y1123101D03*
X1331405D03*
X1323405D03*
X1321169Y1110597D03*
X1321954Y1113648D03*
X1326254D03*
X1328754D03*
X1323405Y1118801D03*
Y1116101D03*
X1320279Y1131935D03*
Y1134435D03*
Y1136935D03*
Y1139435D03*
X1334305Y1129301D03*
X1331805D03*
X1329305D03*
X1326805D03*
X1324305D03*
X1321805D03*
X1334305Y1125801D03*
X1331805D03*
X1323405D03*
X1320279Y1141935D03*
Y1146935D03*
Y1144435D03*
X1326269Y1152713D03*
Y1155213D03*
X1325635Y1172384D03*
Y1162384D03*
Y1164884D03*
Y1167384D03*
Y1169884D03*
X1323135Y1172384D03*
Y1162384D03*
Y1164884D03*
Y1167384D03*
Y1169884D03*
X1334793Y1179421D03*
Y1181921D03*
Y1184421D03*
Y1186921D03*
X1320493Y1186709D03*
Y1184209D03*
Y1181709D03*
Y1179209D03*
X1325635Y1174884D03*
X1323135D03*
X1320493Y1204405D03*
X1334793Y1204617D03*
X1331643Y1200821D03*
Y1198321D03*
Y1192621D03*
Y1190121D03*
X1320493Y1206905D03*
Y1211905D03*
Y1209405D03*
X1334793Y1207117D03*
Y1209617D03*
Y1212117D03*
X1327237Y1221428D03*
X1331237D03*
X1335237D03*
X1323237D03*
X1327237Y1237428D03*
Y1233428D03*
Y1229428D03*
Y1225428D03*
X1331237Y1237428D03*
Y1233428D03*
Y1225428D03*
X1335237Y1233428D03*
Y1229428D03*
Y1225428D03*
X1323237Y1233428D03*
Y1229428D03*
Y1225428D03*
X1335237Y1241428D03*
X1323237Y1245428D03*
Y1241428D03*
X1327237Y1245428D03*
Y1241428D03*
X1331237Y1245428D03*
Y1241428D03*
X1335237Y1245428D03*
X1333876Y1257160D03*
Y1260160D03*
X1330070Y1297498D03*
X1335470D03*
X1328246Y1348187D03*
X1331646D03*
X1332424Y1345691D03*
Y1350683D03*
X1327468D03*
Y1345691D03*
X1320184Y1350683D03*
Y1345691D03*
X1328246Y1348187D03*
X1331646D03*
X1328246Y1360099D03*
X1331646D03*
X1332424Y1362595D03*
Y1357603D03*
X1327468D03*
Y1362595D03*
X1320184D03*
Y1357603D03*
X1328246Y1360099D03*
X1331646D03*
Y1384297D03*
Y1372385D03*
X1328246D03*
Y1384297D03*
X1331646D03*
Y1372385D03*
X1328246D03*
X1332424Y1381801D03*
Y1369889D03*
Y1374881D03*
X1327468Y1381801D03*
Y1369889D03*
Y1374881D03*
X1320184Y1381801D03*
Y1374881D03*
Y1369889D03*
X1328246Y1384297D03*
X1331646Y1396583D03*
X1328246D03*
X1332424Y1386793D03*
Y1394087D03*
Y1399079D03*
X1327468Y1386793D03*
Y1394087D03*
Y1399079D03*
X1320184D03*
Y1394087D03*
Y1386793D03*
X1331646Y1396583D03*
X1328246D03*
X1331646Y1408495D03*
X1328246D03*
X1332424Y1410991D03*
Y1405999D03*
X1327468Y1410991D03*
Y1405999D03*
X1320184Y1410991D03*
Y1405999D03*
X1331646Y1408495D03*
X1328246D03*
X1328850Y1465513D03*
Y1460782D03*
X1320189Y1465913D03*
Y1456451D03*
Y1461182D03*
X1328850Y1476136D03*
Y1470244D03*
X1320189Y1481267D03*
X1328850Y1480867D03*
X1320189Y1471805D03*
Y1476536D03*
X1328850Y1491490D03*
Y1485598D03*
X1320189Y1496621D03*
X1328850Y1496221D03*
X1320189Y1487159D03*
Y1491890D03*
Y1502514D03*
X1328850Y1506845D03*
Y1500952D03*
Y1511576D03*
X1320189Y1511976D03*
Y1507245D03*
X1328850Y1516307D03*
X1320189Y1558813D03*
Y1563544D03*
X1328850Y1563144D03*
Y1567875D03*
X1320189Y1574167D03*
Y1578898D03*
X1328850Y1578498D03*
Y1572606D03*
X1320189Y1568275D03*
X1328850Y1583229D03*
X1320189Y1589522D03*
Y1594253D03*
X1328850Y1593853D03*
Y1587960D03*
X1320189Y1583629D03*
X1328850Y1603315D03*
X1320189Y1609607D03*
Y1604876D03*
Y1598984D03*
X1328850Y1609207D03*
Y1598584D03*
Y1613938D03*
Y1618669D03*
X1320189Y1614338D03*
X1332000Y1644980D03*
X1340183Y-83484D03*
Y-78528D03*
X1337687Y-79306D03*
Y-82706D03*
X1340183Y-68528D03*
Y-73484D03*
X1337687Y-69306D03*
Y-72706D03*
X1342232Y3000D03*
X1336646Y22627D03*
X1336551Y26534D03*
X1340320Y147540D03*
X1344092Y141247D03*
X1340320Y151540D03*
X1348419Y265222D03*
X1340104Y279117D03*
X1337510Y310562D03*
X1338288Y313058D03*
X1338378Y334347D03*
X1338275Y341603D03*
X1346009Y336080D03*
X1346093Y340805D03*
X1338378Y348830D03*
X1346065Y347106D03*
X1338471Y356959D03*
X1338287Y370905D03*
X1337509Y373401D03*
X1342810Y408104D03*
X1345610D03*
X1348410D03*
X1336388Y424939D03*
X1342527Y420375D03*
X1345327D03*
X1348127D03*
X1347897Y433975D03*
X1346483Y436164D03*
X1336388Y427439D03*
X1347846Y461607D03*
X1339846D03*
X1339049Y471334D03*
X1343846Y461607D03*
X1346378Y623734D03*
X1345451Y699032D03*
X1344768Y737675D03*
Y741675D03*
Y745675D03*
Y749675D03*
Y753675D03*
Y761675D03*
Y757675D03*
X1336450Y765675D03*
X1347136Y780040D03*
X1344768Y773675D03*
Y781350D03*
X1341000Y788000D03*
X1345000D03*
X1337000D03*
X1348917D03*
X1349000Y804000D03*
X1351000Y811620D03*
X1347000D03*
X1343000D03*
X1337000Y804000D03*
X1345000D03*
X1341000D03*
X1349976Y829000D03*
X1350000Y825500D03*
X1351550Y839320D03*
X1342103Y845619D03*
X1345252Y836170D03*
X1338953Y845619D03*
X1345252Y833021D03*
X1342103Y836170D03*
X1351550D03*
X1342103Y842470D03*
X1345252Y845619D03*
X1342103Y839320D03*
X1338953Y848769D03*
X1338952Y839319D03*
X1345252Y842470D03*
X1342103Y848769D03*
X1338953Y842470D03*
X1345252Y848769D03*
X1338953Y836170D03*
X1351550Y842470D03*
Y848769D03*
Y845619D03*
X1345252Y839320D03*
X1351550Y855068D03*
X1345252D03*
X1342103D03*
Y861367D03*
X1338953D03*
Y858218D03*
X1338952Y855067D03*
X1351550Y858218D03*
X1345252D03*
Y861367D03*
X1342103Y858218D03*
X1351550Y861367D03*
X1338953Y851918D03*
X1342103D03*
X1345252D03*
X1351550D03*
X1338953Y870814D03*
X1342103Y867665D03*
X1338953D03*
X1351550Y873964D03*
X1345252D03*
X1342103D03*
X1338952Y873965D03*
X1338953Y880263D03*
X1351550D03*
X1345252D03*
X1342103Y870814D03*
X1345252D03*
Y867665D03*
X1351550Y870814D03*
Y867665D03*
X1338953Y877114D03*
X1345252D03*
X1351550D03*
X1342103Y880263D03*
X1345252Y892862D03*
X1338953Y883413D03*
X1345252Y889712D03*
Y886562D03*
X1342103Y883413D03*
X1345252D03*
X1338952Y889713D03*
X1338953Y892862D03*
X1342103Y886562D03*
Y892862D03*
Y889712D03*
X1338953Y886562D03*
X1351550Y883413D03*
Y889712D03*
Y886562D03*
Y892862D03*
X1340000Y900000D03*
X1351500Y903000D03*
Y906500D03*
X1340000Y906000D03*
Y903000D03*
X1351511Y900000D03*
X1350500Y925500D03*
X1338500D03*
X1342500D03*
X1346500D03*
X1338500Y930500D03*
X1350500D03*
X1342500D03*
X1346500D03*
X1341820Y947407D03*
X1337514Y988259D03*
X1343465Y1026123D03*
X1340665D03*
X1343465Y1028923D03*
X1340665D03*
X1347380Y1057998D03*
Y1055498D03*
X1344880D03*
Y1057998D03*
X1347380Y1060498D03*
Y1062998D03*
X1344880D03*
Y1060498D03*
X1347552Y1091816D03*
Y1089316D03*
X1345052Y1081816D03*
Y1084316D03*
Y1086816D03*
X1347552D03*
Y1084316D03*
X1350418Y1090288D03*
X1347552Y1081816D03*
X1339349Y1098767D03*
X1344241Y1106298D03*
X1348997Y1107997D03*
X1350418Y1093088D03*
X1339234Y1101917D03*
X1339169Y1106897D03*
X1337315Y1113822D03*
Y1119422D03*
X1341984Y1110092D03*
X1345650Y1115896D03*
X1348997Y1113797D03*
Y1110897D03*
X1351197Y1112397D03*
X1351097Y1109397D03*
X1345650Y1118396D03*
X1339305Y1129301D03*
X1336805D03*
X1339305Y1125801D03*
X1336805D03*
X1343505Y1136935D03*
Y1134435D03*
Y1139435D03*
Y1131935D03*
X1349907D03*
Y1134435D03*
Y1136935D03*
Y1139435D03*
X1352407Y1131935D03*
Y1134435D03*
Y1136935D03*
Y1139435D03*
X1347300Y1128332D03*
X1343725Y1128738D03*
X1343505Y1146935D03*
Y1144435D03*
Y1141935D03*
X1349907D03*
Y1146935D03*
Y1144435D03*
X1352407Y1141935D03*
Y1146935D03*
Y1144435D03*
X1336669Y1152713D03*
Y1155213D03*
X1351405Y1154902D03*
Y1152402D03*
X1343905Y1162384D03*
Y1164884D03*
Y1167384D03*
Y1169884D03*
Y1172384D03*
X1341405D03*
Y1169884D03*
Y1167384D03*
Y1164884D03*
Y1162384D03*
X1350963Y1172384D03*
Y1169884D03*
Y1167384D03*
Y1164884D03*
Y1162384D03*
X1351149Y1158200D03*
X1347423Y1186709D03*
Y1184209D03*
Y1181709D03*
Y1179209D03*
X1343905Y1174884D03*
X1341405D03*
X1350963D03*
X1347423Y1204405D03*
X1337108Y1200821D03*
Y1198321D03*
X1345108Y1200821D03*
Y1198321D03*
X1337108Y1192621D03*
Y1190121D03*
X1345108D03*
Y1192621D03*
X1347423Y1209405D03*
Y1211905D03*
Y1206905D03*
X1347237Y1221428D03*
X1343237D03*
X1339237D03*
X1347237Y1237428D03*
Y1233428D03*
Y1229428D03*
X1343237D03*
Y1233428D03*
Y1237428D03*
X1339237D03*
Y1233428D03*
Y1229428D03*
Y1225428D03*
X1347237Y1245428D03*
Y1241428D03*
X1343237Y1245428D03*
X1339237D03*
Y1241428D03*
X1339876Y1257160D03*
X1342876D03*
X1345876Y1260160D03*
Y1257160D03*
X1348876Y1260160D03*
Y1257160D03*
X1351876D03*
X1336876Y1260160D03*
Y1257160D03*
X1342876Y1260160D03*
X1339876D03*
X1340870Y1297498D03*
X1346270D03*
X1351670D03*
X1340486Y1348187D03*
X1343886D03*
X1352726D03*
X1343886D03*
X1340486D03*
X1351948Y1350683D03*
Y1345691D03*
X1339708Y1345597D03*
Y1350683D03*
X1344664Y1345597D03*
Y1350683D03*
X1352726Y1360099D03*
X1340486D03*
X1343886D03*
D03*
X1351948Y1357603D03*
Y1362595D03*
X1339708D03*
Y1357603D03*
X1344664Y1362595D03*
Y1357603D03*
X1340486Y1360099D03*
X1343886Y1384297D03*
X1340486D03*
Y1372385D03*
X1343886D03*
X1352726Y1384297D03*
Y1372385D03*
X1351948Y1374881D03*
Y1381801D03*
Y1369889D03*
X1339708Y1374881D03*
Y1381801D03*
Y1369889D03*
X1344664D03*
Y1374881D03*
Y1381801D03*
X1343886Y1372385D03*
X1340486D03*
Y1384297D03*
X1343886D03*
X1352726Y1396583D03*
X1343886D03*
X1340486D03*
D03*
X1343886D03*
X1351948Y1386793D03*
Y1394087D03*
Y1399079D03*
X1339708D03*
Y1393993D03*
Y1386793D03*
X1344664Y1393993D03*
Y1399079D03*
Y1386793D03*
X1340486Y1408495D03*
X1343886D03*
X1352726D03*
X1351948Y1410991D03*
Y1405999D03*
X1339708Y1410991D03*
Y1405999D03*
X1344664Y1410991D03*
Y1405999D03*
X1343886Y1408495D03*
X1340486D03*
X1337512Y1461182D03*
X1346173Y1465513D03*
Y1460782D03*
X1337512Y1465913D03*
Y1456451D03*
X1346173Y1476136D03*
Y1470244D03*
X1337512Y1481267D03*
X1346173Y1480867D03*
X1337512Y1471805D03*
Y1476536D03*
X1346173Y1485598D03*
Y1491490D03*
X1337512Y1487159D03*
Y1491890D03*
Y1496621D03*
X1346173Y1496221D03*
X1337512Y1507245D03*
Y1502514D03*
X1346173Y1506845D03*
Y1500952D03*
Y1511576D03*
X1337512Y1511976D03*
X1346173Y1516307D03*
X1337512Y1558813D03*
Y1563544D03*
X1346173Y1563144D03*
X1337512Y1574167D03*
Y1578898D03*
X1346173Y1578498D03*
Y1572606D03*
X1337512Y1568275D03*
X1346173Y1567875D03*
X1337512Y1583629D03*
X1346173Y1583229D03*
X1337512Y1589522D03*
Y1594253D03*
X1346173Y1593853D03*
Y1587960D03*
X1337512Y1609607D03*
Y1604876D03*
Y1598984D03*
X1346173Y1609207D03*
Y1598584D03*
Y1603315D03*
X1337512Y1614338D03*
X1346173Y1613938D03*
Y1618669D03*
X1352000Y1644980D03*
X1362232Y3000D03*
X1355900Y146461D03*
X1354802Y152367D03*
X1366859Y152562D03*
X1361039Y327099D03*
X1363535Y327877D03*
X1361039Y332055D03*
X1364039Y334973D03*
Y339929D03*
X1361039Y342847D03*
X1366535Y335751D03*
Y339151D03*
X1363535Y331277D03*
Y343625D03*
X1364039Y350721D03*
X1361039Y347803D03*
X1364039Y355677D03*
X1366535Y354899D03*
Y351499D03*
X1363535Y347025D03*
X1360719Y424601D03*
X1360352Y447101D03*
X1355255Y607532D03*
X1352817Y788000D03*
X1363000Y811620D03*
X1353000Y804000D03*
X1359000Y811620D03*
X1357000Y804000D03*
X1361000D03*
X1364148Y829871D03*
X1367298D03*
X1359425Y829000D03*
X1364148Y836170D03*
X1354699Y842470D03*
Y848769D03*
X1357849D03*
X1364148Y845619D03*
X1354699Y836170D03*
X1357849Y833021D03*
X1367298Y845619D03*
X1364148Y842470D03*
X1357850Y839319D03*
X1357849Y836170D03*
X1360999Y842470D03*
X1354699Y845619D03*
X1357849D03*
X1360999Y839320D03*
X1367298Y842470D03*
X1360999Y848769D03*
Y845619D03*
X1367298Y833021D03*
X1354699Y839320D03*
X1360999Y836170D03*
X1367298Y848769D03*
X1364148Y839320D03*
X1357849Y842470D03*
X1364148Y833021D03*
X1367298Y836170D03*
Y839320D03*
X1364148Y848769D03*
X1354699Y855068D03*
X1357849Y861367D03*
X1354699D03*
X1357849Y858218D03*
X1357850Y855067D03*
X1360999Y851918D03*
X1364148D03*
X1367298Y861367D03*
X1364148Y858218D03*
Y855068D03*
Y861367D03*
X1367298Y858218D03*
Y851918D03*
X1354699Y858218D03*
X1367298Y855068D03*
X1360999D03*
Y858218D03*
Y861367D03*
X1354699Y851918D03*
X1357849D03*
X1360999Y877114D03*
X1357850Y873965D03*
X1354699Y873964D03*
X1357849Y870814D03*
Y867665D03*
X1354699D03*
X1364148D03*
X1367298Y877114D03*
X1364148Y870814D03*
X1367298Y873964D03*
X1364148D03*
Y877114D03*
X1367298Y870814D03*
X1364148Y880263D03*
X1367298D03*
X1357849D03*
X1360999D03*
X1367298Y867665D03*
X1354699Y870814D03*
X1357849Y877114D03*
X1354699Y880263D03*
X1360999Y867665D03*
Y870814D03*
Y873964D03*
X1364148Y896011D03*
X1367298Y883413D03*
X1354699Y892862D03*
X1360999D03*
X1367298D03*
X1360999Y883413D03*
X1357850Y889713D03*
X1364148Y889712D03*
X1357849Y883413D03*
X1367298Y889712D03*
X1354699D03*
X1357849Y886562D03*
X1364148D03*
X1357849Y892862D03*
X1360999Y889712D03*
X1354699Y883413D03*
X1360999Y886562D03*
X1364148Y892862D03*
Y883413D03*
X1367298Y886562D03*
X1354699D03*
X1354185Y906498D03*
X1367000Y904500D03*
X1363000Y900500D03*
X1367000D03*
X1354500Y925500D03*
X1366500D03*
X1358500D03*
X1362500D03*
Y930500D03*
X1366500D03*
X1354500D03*
X1358500D03*
X1363173Y994483D03*
X1363905Y1000855D03*
X1366493Y1000828D03*
X1364765Y1004766D03*
X1367444Y1003763D03*
X1367884Y1018825D03*
X1357265Y1022766D03*
X1357765Y1019766D03*
X1361265D03*
X1357265Y1026266D03*
X1364237Y1043140D03*
X1357265Y1030266D03*
Y1034266D03*
X1363941Y1047047D03*
X1364418Y1090568D03*
Y1093068D03*
X1361037Y1098428D03*
X1367084Y1105552D03*
X1353197Y1107997D03*
X1363290Y1104792D03*
X1366963Y1119422D03*
Y1113822D03*
X1364483Y1119422D03*
Y1113822D03*
X1355533Y1123101D03*
X1363533D03*
X1366033D03*
X1353297Y1110597D03*
X1354082Y1113648D03*
X1355533Y1116101D03*
Y1118801D03*
X1360882Y1113648D03*
X1358382D03*
X1366433Y1129301D03*
X1355533Y1125801D03*
X1363933D03*
X1366433D03*
X1353933Y1129301D03*
X1356433D03*
X1358933D03*
X1361433D03*
X1363933D03*
X1357397Y1155213D03*
Y1152713D03*
X1366797D03*
Y1155213D03*
X1353463Y1172384D03*
Y1169884D03*
Y1167384D03*
Y1164884D03*
Y1162384D03*
X1361723Y1179421D03*
Y1181921D03*
Y1184421D03*
Y1186921D03*
X1353463Y1174884D03*
X1361723Y1204617D03*
X1364038Y1198321D03*
Y1200821D03*
Y1190121D03*
Y1192621D03*
X1361723Y1212117D03*
Y1209617D03*
Y1207117D03*
X1363876Y1260160D03*
Y1257160D03*
X1354876Y1260160D03*
X1357876D03*
X1360876Y1257160D03*
X1357876D03*
X1354876D03*
X1366876Y1260160D03*
Y1257160D03*
X1357070Y1297498D03*
X1356126Y1348187D03*
X1356904Y1345691D03*
Y1350683D03*
X1356126Y1348187D03*
X1352726D03*
X1356126Y1360099D03*
X1356904Y1357603D03*
Y1362595D03*
X1356126Y1360099D03*
X1352726D03*
X1356126Y1372385D03*
Y1384297D03*
X1352726D03*
X1356126Y1372385D03*
X1356904Y1381801D03*
Y1369889D03*
Y1374881D03*
X1356126Y1384297D03*
X1352726Y1372385D03*
X1356126Y1396583D03*
X1356904Y1386793D03*
Y1394087D03*
Y1399079D03*
X1356126Y1396583D03*
X1352726D03*
X1356126Y1408495D03*
X1356904Y1410991D03*
Y1405999D03*
X1352726Y1408495D03*
X1356126D03*
X1354834Y1465913D03*
Y1456451D03*
Y1461182D03*
X1363496Y1465513D03*
Y1460782D03*
X1354834Y1481267D03*
X1363496Y1476136D03*
Y1470244D03*
Y1480867D03*
X1354834Y1471805D03*
Y1476536D03*
Y1487159D03*
Y1496621D03*
X1363496Y1485598D03*
Y1491490D03*
Y1496221D03*
X1354834Y1491890D03*
Y1502514D03*
Y1511976D03*
X1363496Y1511576D03*
Y1506845D03*
Y1500952D03*
X1354834Y1507245D03*
X1363496Y1516307D03*
X1354834Y1558813D03*
Y1563544D03*
X1363496Y1563144D03*
Y1572606D03*
X1354834Y1568275D03*
Y1574167D03*
Y1578898D03*
X1363496Y1567875D03*
Y1578498D03*
X1354834Y1583629D03*
Y1589522D03*
Y1594253D03*
X1363496Y1583229D03*
Y1593853D03*
Y1587960D03*
X1354834Y1609607D03*
Y1604876D03*
Y1598984D03*
X1363496Y1609207D03*
Y1598584D03*
Y1603315D03*
X1354834Y1614338D03*
X1363496Y1613938D03*
Y1618669D03*
X1382232Y3000D03*
X1376262Y113394D03*
X1378911Y110784D03*
X1380480Y102249D03*
X1384480D03*
X1376262Y116594D03*
X1378505Y133298D03*
X1376262Y119594D03*
X1380652Y134579D03*
X1375103Y161306D03*
X1372354Y157370D03*
X1384280Y195176D03*
X1381780D03*
X1384140Y203393D03*
X1381640D03*
X1384319Y218085D03*
X1378227Y252371D03*
Y248371D03*
X1384265Y320871D03*
Y325371D03*
X1383551Y337808D03*
X1384265Y329871D03*
X1384253Y346826D03*
X1384447Y356871D03*
X1375073D03*
Y361371D03*
X1383505Y349437D03*
X1372232Y361298D03*
X1384174Y362641D03*
X1373748Y397758D03*
X1377024Y397713D03*
X1375171Y424741D03*
X1375375Y428995D03*
X1375400Y435192D03*
X1375360Y432234D03*
X1383556Y558338D03*
X1383608Y571927D03*
X1383184Y587653D03*
X1383000Y584500D03*
X1383556Y604838D03*
X1383425Y590425D03*
X1383608Y618427D03*
X1381118Y634033D03*
X1383425Y636925D03*
X1378957Y630957D03*
X1383425Y640075D03*
X1381244Y673623D03*
X1383425Y684140D03*
Y681425D03*
X1383000Y675500D03*
X1381932Y722547D03*
X1383425Y731575D03*
Y728425D03*
X1378957Y722457D03*
X1371000Y811620D03*
X1373000Y804000D03*
X1369000D03*
X1381428Y812287D03*
X1383046Y829871D03*
X1370447D03*
X1379896Y842470D03*
X1370447Y839320D03*
X1383046Y845619D03*
X1379896D03*
X1373597D03*
Y842470D03*
X1370447Y848769D03*
X1379896D03*
Y839320D03*
X1373597Y848769D03*
X1376747D03*
X1373597Y833021D03*
X1370447D03*
X1373597Y836170D03*
X1370447D03*
X1373598Y839319D03*
X1370447Y842470D03*
Y845619D03*
X1383046Y842470D03*
X1376747Y836170D03*
Y842470D03*
X1379896Y833021D03*
X1383046Y839320D03*
X1376747Y845619D03*
Y839320D03*
X1379896Y858218D03*
Y855068D03*
Y861367D03*
X1376747Y858218D03*
Y851918D03*
X1373597Y861367D03*
X1376747Y855068D03*
X1373597Y858218D03*
X1376747Y861367D03*
X1383046Y851918D03*
X1373597D03*
X1373598Y855067D03*
X1379896Y851918D03*
X1370447D03*
Y858218D03*
X1383046D03*
Y861367D03*
X1370447Y855068D03*
Y861367D03*
Y867665D03*
X1379896Y870814D03*
X1383046Y873964D03*
X1376747Y880263D03*
X1370447Y877114D03*
X1373598Y873965D03*
X1370447Y873964D03*
X1379896Y877114D03*
X1373597Y880263D03*
X1383046Y877114D03*
X1370447Y880263D03*
X1376747Y873964D03*
X1383046Y880263D03*
X1370447Y870814D03*
X1376747D03*
X1373597D03*
X1376747Y867665D03*
Y877114D03*
X1373597Y867665D03*
X1379896D03*
X1383046Y870814D03*
X1379896Y880263D03*
X1373597Y877114D03*
X1379896Y873964D03*
X1370447Y886562D03*
X1379896Y883413D03*
X1383046Y892862D03*
X1379896Y886562D03*
X1370447Y883413D03*
X1373598Y889713D03*
X1376747Y886562D03*
X1383046Y883413D03*
X1376747Y889712D03*
X1383046D03*
X1379896D03*
X1373597Y883413D03*
Y886562D03*
X1370447Y892862D03*
X1376747D03*
X1370447Y889712D03*
X1373597Y892862D03*
X1383046Y886562D03*
X1379896Y892862D03*
X1376747Y883413D03*
X1383046Y899161D03*
X1376708Y901000D03*
X1374369Y925499D03*
X1370500Y925500D03*
X1382500D03*
X1374500Y930500D03*
X1370500D03*
X1378500D03*
X1371379Y986717D03*
X1383162Y991829D03*
X1370384Y1004680D03*
X1383669Y1011303D03*
X1373534Y1004680D03*
X1383669Y1017303D03*
Y1023303D03*
X1374034Y1015825D03*
X1376359Y1016825D03*
X1376601Y1030218D03*
X1373874Y1035716D03*
X1374451Y1090568D03*
Y1093068D03*
X1371477Y1098767D03*
X1377087Y1106365D03*
X1371362Y1101917D03*
X1371297Y1106897D03*
X1382456Y1107997D03*
X1369443Y1119422D03*
Y1113822D03*
X1374112Y1110092D03*
X1377778Y1115896D03*
X1384656Y1112397D03*
X1382456Y1110897D03*
Y1113797D03*
X1384556Y1109397D03*
X1377778Y1118396D03*
X1375633Y1136935D03*
Y1134435D03*
Y1139435D03*
Y1131935D03*
X1383366D03*
Y1134435D03*
Y1136935D03*
Y1139435D03*
X1368933Y1125801D03*
X1371433D03*
X1368933Y1129301D03*
X1371433D03*
X1383024Y1152684D03*
X1376861D03*
X1375633Y1146935D03*
Y1144435D03*
Y1141935D03*
X1383366D03*
Y1146935D03*
Y1144435D03*
X1369233Y1169884D03*
Y1172384D03*
X1371733D03*
Y1169884D03*
Y1167384D03*
Y1164884D03*
Y1162384D03*
X1369233D03*
Y1164884D03*
Y1167384D03*
X1376861Y1160834D03*
X1383024D03*
X1369233Y1174884D03*
X1371733D03*
X1375459Y1197471D03*
Y1193471D03*
X1379959Y1197471D03*
Y1193471D03*
X1377390Y1244055D03*
Y1250760D03*
Y1254164D03*
X1372300Y1422900D03*
X1372157Y1461183D03*
Y1456452D03*
Y1465914D03*
Y1471806D03*
Y1476537D03*
Y1481268D03*
Y1487160D03*
Y1491891D03*
Y1496622D03*
Y1502515D03*
Y1507246D03*
Y1511977D03*
Y1558813D03*
Y1563544D03*
Y1568275D03*
Y1574167D03*
Y1578898D03*
Y1583629D03*
Y1589522D03*
Y1594253D03*
Y1604876D03*
Y1598984D03*
Y1609607D03*
Y1614338D03*
X1372000Y1644980D03*
X1398216Y4469D03*
X1399577Y24773D03*
Y44773D03*
X1399648Y118342D03*
X1391497Y109172D03*
X1394497D03*
X1393504Y106495D03*
X1397248Y116497D03*
X1388231Y116594D03*
X1393504Y102495D03*
X1399648Y121742D03*
Y132515D03*
Y135915D03*
X1386505Y133298D03*
X1397248Y130670D03*
Y123584D03*
X1388231Y119594D03*
X1399648Y132515D03*
Y121742D03*
Y118342D03*
X1393238Y146012D03*
X1395144Y141228D03*
X1397248Y137757D03*
X1399648Y135915D03*
X1393238Y142862D03*
X1398032Y150847D03*
X1386399Y198883D03*
X1386780Y195176D03*
X1399327D03*
X1396827D03*
X1400845Y199248D03*
X1390328Y206838D03*
X1387828D03*
X1400845Y201748D03*
X1398681Y206806D03*
X1401181D03*
X1399408Y210509D03*
X1396908D03*
X1390832Y216970D03*
Y219470D03*
X1390898Y226320D03*
X1390832Y221970D03*
X1388119Y216385D03*
X1400000Y247292D03*
X1399226Y238689D03*
X1392790Y236121D03*
X1389824Y238589D03*
X1397585Y242078D03*
X1392816Y232971D03*
X1392709Y253198D03*
X1385943Y323222D03*
X1385971Y327688D03*
X1386143Y331982D03*
X1386057Y341200D03*
X1385971Y336791D03*
X1386286Y350218D03*
X1387847Y366710D03*
X1397550Y390484D03*
X1400231Y390256D03*
X1387814Y397136D03*
X1389295Y408443D03*
X1396528Y397454D03*
X1399571Y397418D03*
X1393575Y397310D03*
X1390553Y397436D03*
X1391623Y409900D03*
X1386809Y414173D03*
X1387125Y417312D03*
X1393177Y424804D03*
X1389431Y421593D03*
X1388788Y428348D03*
X1393208Y428109D03*
X1393336Y431100D03*
X1393944Y507856D03*
X1394044Y510990D03*
X1397079Y536726D03*
Y527726D03*
Y552726D03*
Y540726D03*
Y548726D03*
X1395605Y556217D03*
X1390741Y565000D03*
X1391086Y577192D03*
X1400912Y581222D03*
X1391087Y581317D03*
X1400912Y591215D03*
X1398946Y621311D03*
X1390741Y611500D03*
Y607500D03*
Y615500D03*
X1391587Y627817D03*
X1391586Y623692D03*
X1398946Y629311D03*
Y625311D03*
X1397000Y656000D03*
X1388414Y675000D03*
X1397000Y703000D03*
X1388241Y722000D03*
X1386335Y803704D03*
X1390537Y803679D03*
X1394537Y803653D03*
X1395955Y832697D03*
X1399872Y845109D03*
X1396916Y862829D03*
X1391316Y857849D03*
X1388488Y857822D03*
X1395561Y876204D03*
X1396163Y868597D03*
X1390182Y873460D03*
X1387582Y873487D03*
X1388479Y892923D03*
X1385979D03*
X1390979D03*
X1387504Y899931D03*
X1390541Y900086D03*
X1398247Y926261D03*
X1388980Y921075D03*
X1401000Y925789D03*
X1398854Y987277D03*
X1395669Y1011303D03*
X1389669D03*
X1395669Y1017303D03*
Y1023303D03*
X1389669D03*
X1385732Y1029482D03*
X1387813Y1030952D03*
X1399852Y1039779D03*
X1390322Y1057998D03*
Y1055498D03*
X1392822D03*
Y1057998D03*
X1390322Y1060498D03*
Y1062998D03*
X1392822D03*
Y1060498D03*
X1388523Y1090090D03*
X1392691Y1089224D03*
Y1086724D03*
Y1084224D03*
Y1081724D03*
X1390191D03*
Y1084224D03*
Y1086724D03*
X1394496Y1098428D03*
X1400543Y1105552D03*
X1396749Y1104792D03*
X1388451Y1093048D03*
X1386656Y1107997D03*
X1397942Y1119422D03*
X1400422D03*
Y1113822D03*
X1397942D03*
X1388992Y1123101D03*
X1396992D03*
X1399492D03*
X1386756Y1110597D03*
X1394341Y1113648D03*
X1388992Y1118801D03*
Y1116101D03*
X1387541Y1113648D03*
X1391841D03*
X1385866Y1131935D03*
Y1134435D03*
Y1136935D03*
Y1139435D03*
X1388992Y1125801D03*
X1397392D03*
X1399892D03*
X1387392Y1129301D03*
X1389892D03*
X1392392D03*
X1394892D03*
X1397392D03*
X1399892D03*
X1391856Y1155213D03*
Y1152713D03*
X1385866Y1141935D03*
Y1146935D03*
Y1144435D03*
X1388722Y1162384D03*
Y1164884D03*
Y1167384D03*
Y1169884D03*
Y1172384D03*
X1391222Y1162384D03*
Y1164884D03*
Y1167384D03*
Y1169884D03*
Y1172384D03*
X1388722Y1174884D03*
X1391222D03*
X1393695Y1186709D03*
Y1184209D03*
Y1181709D03*
Y1179209D03*
Y1204405D03*
X1391380Y1200821D03*
Y1198321D03*
Y1190121D03*
Y1192621D03*
X1393695Y1206905D03*
Y1211905D03*
Y1209405D03*
X1385821Y1260160D03*
X1391821Y1257160D03*
X1394821D03*
X1385821D03*
X1388821D03*
X1397821Y1260160D03*
Y1257160D03*
X1400821Y1260160D03*
Y1257160D03*
X1388821Y1260160D03*
X1394821D03*
X1391821D03*
X1385992Y1285466D03*
X1390492D03*
X1385052Y1303139D03*
X1392000Y1644980D03*
X1406898Y53597D03*
X1417248Y95236D03*
X1402098Y95111D03*
X1406948Y114655D03*
Y111255D03*
X1417248Y102323D03*
X1409248Y109410D03*
Y102323D03*
X1404548Y116497D03*
X1402048D03*
X1404548Y109410D03*
X1409248Y116496D03*
X1406948Y111255D03*
Y114655D03*
X1406467Y106561D03*
X1406948Y125428D03*
Y128828D03*
X1402048Y130670D03*
Y123584D03*
X1404548Y123583D03*
X1409248Y130670D03*
Y123583D03*
X1404548Y130670D03*
X1406948Y128828D03*
Y125428D03*
X1409248Y137756D03*
X1402048Y137757D03*
X1401827Y195176D03*
X1404327D03*
X1405780Y213539D03*
X1403845Y202048D03*
X1407461Y238714D03*
X1403461D03*
X1402942Y246874D03*
X1405162Y244297D03*
X1408666Y324733D03*
X1402921Y322403D03*
X1409830Y347649D03*
X1404690Y362209D03*
X1416347Y384373D03*
X1416912Y386903D03*
X1416470Y381397D03*
X1402968Y390177D03*
X1416830Y407134D03*
X1411400Y398032D03*
X1414369Y398056D03*
X1413889Y415642D03*
X1415610Y417644D03*
X1411950Y448466D03*
X1414903Y469905D03*
X1406910Y487982D03*
Y478982D03*
Y483982D03*
X1411269Y481467D03*
X1406910Y499982D03*
X1416061Y504825D03*
X1413561D03*
X1411061D03*
X1406910Y495982D03*
Y491982D03*
X1416002Y517401D03*
X1413502D03*
X1411002D03*
X1416553Y522569D03*
Y525369D03*
X1415168Y531882D03*
X1412668D03*
X1409618Y531948D03*
X1401438Y534211D03*
X1408103Y555194D03*
X1410903D03*
X1415103D03*
X1408103Y563194D03*
X1410903D03*
X1408103Y571194D03*
X1410903D03*
X1415103Y563194D03*
Y571194D03*
X1406512Y581222D03*
X1403712D03*
X1416660D03*
X1403712Y591215D03*
X1406512D03*
X1416660D03*
X1405514Y611091D03*
X1401383Y611071D03*
X1416832Y610562D03*
Y607762D03*
X1407952Y641817D03*
X1405229Y652028D03*
X1405000Y656000D03*
Y660000D03*
X1410000Y685000D03*
Y681000D03*
X1404500Y675000D03*
X1405000Y699000D03*
X1410000Y689000D03*
Y701000D03*
Y697000D03*
Y705000D03*
Y709000D03*
Y713000D03*
X1405000Y707000D03*
Y703000D03*
X1410000Y733000D03*
X1404500Y722000D03*
X1410000Y729000D03*
Y725000D03*
Y749000D03*
Y745000D03*
Y741000D03*
Y757000D03*
Y753000D03*
Y761000D03*
X1413500Y832000D03*
Y828000D03*
Y848000D03*
Y840000D03*
Y836000D03*
Y844000D03*
Y864000D03*
Y860000D03*
Y856000D03*
Y852000D03*
Y872000D03*
Y868000D03*
Y888000D03*
X1404689Y910897D03*
X1413733Y911137D03*
X1412376Y907848D03*
X1414876D03*
X1417376D03*
X1409876D03*
X1413500Y904000D03*
Y900000D03*
X1417284Y911009D03*
X1413575Y915186D03*
X1416802Y936845D03*
X1416244Y942285D03*
X1413322Y958908D03*
X1405214Y965074D03*
X1404317Y989436D03*
X1411038Y985379D03*
X1416618Y992307D03*
X1401265Y989465D03*
X1407265D03*
X1414143Y985486D03*
X1402215Y1020440D03*
X1414851Y1058097D03*
X1412351D03*
X1407351D03*
X1409851D03*
X1417351D03*
X1414851Y1060697D03*
X1412351D03*
X1407351D03*
X1409851D03*
X1417351D03*
X1405677Y1086796D03*
X1408177D03*
X1410677D03*
X1413177D03*
X1415677D03*
Y1084296D03*
X1413177D03*
X1410677D03*
X1408177D03*
X1405677D03*
X1416005Y1090288D03*
X1404936Y1098767D03*
X1410546Y1106298D03*
X1404821Y1101917D03*
X1404756Y1106897D03*
X1416005Y1093088D03*
X1414584Y1107997D03*
X1402902Y1119422D03*
Y1113822D03*
X1411237Y1115896D03*
X1407571Y1110092D03*
X1414584Y1113797D03*
X1416784Y1112397D03*
X1414584Y1110897D03*
X1416684Y1109397D03*
X1411237Y1118396D03*
X1415494Y1139435D03*
Y1136935D03*
Y1134435D03*
Y1131935D03*
X1409092Y1136935D03*
Y1134435D03*
Y1139435D03*
Y1131935D03*
X1402392Y1125801D03*
X1404892D03*
X1402392Y1129301D03*
X1404892D03*
X1409425Y1129238D03*
X1413177Y1128894D03*
X1409092Y1141935D03*
X1416736Y1152713D03*
Y1155213D03*
X1402256D03*
Y1152713D03*
X1415494Y1144435D03*
Y1146935D03*
Y1141935D03*
X1409092Y1146935D03*
Y1144435D03*
X1409492Y1167384D03*
Y1169884D03*
Y1172384D03*
X1406992D03*
Y1169884D03*
X1416550Y1162384D03*
Y1164884D03*
Y1167384D03*
Y1169884D03*
Y1172384D03*
X1406992Y1167384D03*
Y1164884D03*
Y1162384D03*
X1409492D03*
Y1164884D03*
X1416736Y1158200D03*
X1416550Y1174884D03*
X1409492D03*
X1406992D03*
X1407995Y1179421D03*
Y1181921D03*
Y1184421D03*
Y1186921D03*
Y1204617D03*
X1410310Y1200821D03*
Y1198321D03*
X1404845D03*
Y1200821D03*
X1410310Y1192621D03*
Y1190121D03*
X1404845D03*
Y1192621D03*
X1407995Y1207117D03*
Y1209617D03*
Y1212117D03*
X1408736Y1222194D03*
X1412736D03*
X1416736D03*
X1408736Y1238194D03*
Y1234194D03*
Y1230194D03*
Y1226194D03*
X1412736Y1238194D03*
Y1234194D03*
Y1230194D03*
Y1226194D03*
X1416736Y1238194D03*
Y1234194D03*
Y1230194D03*
Y1226194D03*
X1412736Y1246194D03*
Y1242194D03*
X1416736Y1246194D03*
X1408736Y1242194D03*
Y1246194D03*
X1409821Y1260160D03*
X1412821D03*
Y1257160D03*
X1409821D03*
X1406821D03*
X1403821D03*
X1415821Y1260160D03*
Y1257160D03*
X1403821Y1260160D03*
X1406821D03*
X1415903Y1282590D03*
X1404019Y1285290D03*
X1414346Y1303020D03*
X1410817Y1305417D03*
X1407825Y1426975D03*
X1408536Y1536570D03*
X1404239Y1547755D03*
X1407747Y1549054D03*
X1408044Y1559306D03*
X1403747Y1570433D03*
X1407255Y1571732D03*
X1412000Y1644980D03*
X1426898Y53597D03*
X1417710Y82984D03*
Y75184D03*
Y77784D03*
Y80384D03*
X1420264Y92849D03*
X1417710Y85584D03*
X1427181Y95236D03*
X1427224Y103037D03*
X1417500Y109410D03*
Y116496D03*
X1427358D03*
Y109410D03*
X1421700Y122900D03*
X1427358Y130670D03*
Y123583D03*
X1418725Y130670D03*
X1423515Y137756D03*
X1418720D03*
X1425993Y212978D03*
Y207978D03*
Y210478D03*
Y215478D03*
Y231226D03*
Y228726D03*
Y226226D03*
Y223726D03*
X1429322Y264180D03*
X1431822D03*
X1429247Y258880D03*
X1429539Y293796D03*
X1432039D03*
X1421005Y407616D03*
X1431019Y434508D03*
X1427019D03*
X1417903Y439919D03*
X1424196Y446352D03*
X1428782Y445874D03*
X1417856Y455466D03*
X1423427Y456839D03*
X1425927D03*
X1423427Y454339D03*
X1425927D03*
X1427484Y470045D03*
X1422903Y469905D03*
X1423427Y459339D03*
X1425927D03*
X1418903Y469905D03*
X1431484Y470045D03*
X1422499Y485138D03*
X1419650Y485128D03*
X1426384Y478625D03*
X1428084Y482425D03*
X1427499Y485138D03*
X1424999D03*
X1426384Y476125D03*
X1430930Y500086D03*
X1433310Y504699D03*
X1430810D03*
X1433012Y516979D03*
X1430512D03*
X1431493Y521804D03*
X1432955Y527449D03*
X1431493Y524304D03*
X1427800Y531378D03*
X1418253Y529169D03*
X1417668Y531882D03*
X1424129Y537658D03*
X1427832Y539731D03*
X1424129Y540458D03*
X1432590Y544895D03*
X1427832Y542231D03*
X1432890Y541895D03*
X1417903Y555194D03*
Y563194D03*
Y571194D03*
X1422260Y581222D03*
X1419460D03*
X1422260Y591215D03*
X1419460D03*
X1431000Y591000D03*
X1433114Y620653D03*
Y617853D03*
X1419632Y607762D03*
X1422432D03*
X1425232Y610562D03*
Y607762D03*
X1422432Y610562D03*
X1419632D03*
X1430944Y605443D03*
X1427233Y628183D03*
X1424389Y627948D03*
X1430481Y658153D03*
X1418000Y685000D03*
Y681000D03*
Y689000D03*
X1426000Y709000D03*
Y713000D03*
Y717000D03*
X1418000Y705000D03*
Y733000D03*
X1417969Y720894D03*
X1426000Y757000D03*
Y753000D03*
X1427000Y766500D03*
X1426000Y761000D03*
X1418023Y765343D03*
X1427000Y774500D03*
Y781834D03*
Y770500D03*
Y790500D03*
Y794500D03*
Y810500D03*
Y814500D03*
Y802500D03*
Y818500D03*
Y830500D03*
Y826500D03*
Y834500D03*
Y842500D03*
Y838500D03*
X1422813Y910065D03*
X1424126Y900295D03*
X1429059Y908579D03*
X1426085Y910281D03*
X1427553Y939200D03*
X1420699Y958452D03*
X1427473Y965621D03*
X1420740Y1004766D03*
Y1000766D03*
Y1008766D03*
X1428740Y1000766D03*
X1420740Y996766D03*
X1428864D03*
X1420740Y1016266D03*
Y1012266D03*
X1428740Y1016266D03*
X1428823Y1020266D03*
X1420740Y1030766D03*
X1420107Y1052514D03*
X1430005Y1090568D03*
Y1093068D03*
X1431876Y1098518D03*
X1426624Y1098428D03*
X1432671Y1105552D03*
X1428877Y1104792D03*
X1418784Y1107997D03*
X1432550Y1119422D03*
Y1113822D03*
X1430070Y1119422D03*
Y1113822D03*
X1421120Y1123101D03*
X1429120D03*
X1431620D03*
X1418884Y1110597D03*
X1421120Y1116101D03*
Y1118801D03*
X1426469Y1113648D03*
X1423969D03*
X1419669D03*
X1422020Y1129301D03*
X1424520D03*
X1427020D03*
X1429520D03*
X1432020D03*
X1417994Y1139435D03*
Y1136935D03*
Y1134435D03*
Y1131935D03*
X1421120Y1125801D03*
X1429520D03*
X1432020D03*
X1419520Y1129301D03*
X1432384Y1155213D03*
Y1152713D03*
X1422984D03*
Y1155213D03*
X1417994Y1144435D03*
Y1146935D03*
Y1141935D03*
X1419050Y1162384D03*
Y1164884D03*
Y1167384D03*
Y1169884D03*
Y1172384D03*
Y1174884D03*
X1420625Y1186709D03*
Y1184209D03*
Y1181709D03*
Y1179209D03*
Y1204405D03*
X1418310Y1198321D03*
Y1200821D03*
Y1192621D03*
Y1190121D03*
X1420625Y1206905D03*
Y1209405D03*
X1420736Y1222194D03*
X1424736D03*
X1428736D03*
X1432736D03*
X1420736Y1238194D03*
Y1234194D03*
Y1230194D03*
X1424736Y1234194D03*
Y1230194D03*
Y1226194D03*
X1428736Y1238194D03*
Y1234194D03*
Y1230194D03*
Y1226194D03*
X1432736Y1234194D03*
Y1226194D03*
X1420736Y1246194D03*
Y1242194D03*
X1424736Y1246194D03*
Y1242194D03*
X1428736Y1246194D03*
Y1242194D03*
X1421821Y1257160D03*
X1418821D03*
Y1260160D03*
X1421821D03*
X1425652Y1297411D03*
X1431080Y1301702D03*
X1421238Y1301712D03*
X1428009Y1301760D03*
X1424732Y1301603D03*
X1433386Y1343309D03*
X1428840Y1407740D03*
X1432258Y1414600D03*
X1422176Y1491198D03*
X1430374Y1492474D03*
X1420877Y1494706D03*
X1423065Y1508327D03*
X1432499Y1512175D03*
X1423806Y1524252D03*
X1423930Y1520364D03*
X1429587Y1527450D03*
X1424245Y1543338D03*
X1425558Y1537432D03*
X1433405Y1546001D03*
X1425260Y1558072D03*
X1433558Y1555366D03*
X1423701Y1563978D03*
X1432913Y1568679D03*
X1432000Y1644980D03*
X1445692Y5374D03*
X1445005Y24773D03*
X1449685Y34228D03*
X1445005Y44773D03*
X1436045Y77393D03*
Y74793D03*
Y85193D03*
Y82593D03*
Y79993D03*
X1444641Y94017D03*
X1448641D03*
X1440641D03*
X1444370Y101701D03*
Y98551D03*
X1447265Y114623D03*
Y111223D03*
D03*
Y114623D03*
X1435358Y116496D03*
Y109410D03*
X1449761Y115401D03*
Y110445D03*
X1444769D03*
Y115401D03*
X1435358Y102323D03*
X1447920Y103783D03*
X1438116Y107649D03*
Y104249D03*
X1447265Y128796D03*
Y125396D03*
X1449761Y124618D03*
X1444769D03*
Y129574D03*
X1435358Y130670D03*
Y123583D03*
X1449761Y129574D03*
X1447265Y125396D03*
Y128796D03*
X1435358Y137756D03*
X1442682Y147540D03*
X1446454Y141247D03*
X1442682Y151540D03*
X1435138Y162368D03*
X1437738D03*
X1444838Y162793D03*
Y165393D03*
Y170493D03*
Y167993D03*
X1449841Y181009D03*
X1447046Y181366D03*
X1443835Y181426D03*
X1446332Y191941D03*
X1444043Y184221D03*
X1446660Y184012D03*
X1448079Y211359D03*
Y213859D03*
X1436449Y213213D03*
Y210713D03*
X1440521Y211695D03*
X1443021D03*
X1440521Y208695D03*
X1436449Y208213D03*
Y228961D03*
X1444418Y229286D03*
X1436449Y226461D03*
X1440156Y226141D03*
X1448111Y222212D03*
Y224712D03*
X1436449Y231461D03*
Y215713D03*
X1440399Y236611D03*
X1442899D03*
X1444418Y231786D03*
X1445399Y236611D03*
X1448026Y256535D03*
X1440101Y248891D03*
X1442601D03*
X1445101D03*
X1441016Y267526D03*
Y270026D03*
X1443516D03*
X1438216D03*
X1443516Y267526D03*
X1438216D03*
X1440053Y285690D03*
X1437553D03*
X1440053Y288190D03*
X1442853D03*
Y285690D03*
X1447079Y290755D03*
X1437553Y288190D03*
X1448948Y326448D03*
X1448822Y345324D03*
X1448734Y332910D03*
X1449060Y356861D03*
Y352361D03*
X1447502Y360785D03*
X1434697Y347125D03*
X1439719Y350387D03*
X1440568Y369566D03*
X1449619Y363290D03*
X1437758Y362584D03*
X1434608D03*
X1438768Y371655D03*
X1445906Y366030D03*
X1438588Y380589D03*
X1435019Y434508D03*
X1435424Y430361D03*
X1437757Y447201D03*
X1437879Y444269D03*
X1440390Y456652D03*
X1442890D03*
X1435484Y470045D03*
X1442890Y459152D03*
Y461652D03*
X1440390Y459152D03*
Y461652D03*
X1442786Y480705D03*
X1437631Y482134D03*
Y484634D03*
X1449293Y476086D03*
X1445586Y480705D03*
X1441076Y475946D03*
Y478446D03*
X1449293Y478586D03*
Y481086D03*
Y483886D03*
X1433960Y491214D03*
X1449293Y491133D03*
X1435810Y504699D03*
X1442721Y495151D03*
X1437663Y492987D03*
X1442421Y498151D03*
X1433960Y493714D03*
X1437663Y495487D03*
X1445221Y498151D03*
X1449293Y493633D03*
Y496133D03*
Y498633D03*
X1445221Y495151D03*
X1447036Y519518D03*
X1435512Y516979D03*
X1439462Y522129D03*
X1444536Y519518D03*
X1439536D03*
X1442036D03*
X1435755Y527449D03*
X1439462Y527129D03*
Y524629D03*
X1443555Y532949D03*
X1446355D03*
X1439462Y537877D03*
X1449393Y553297D03*
Y555897D03*
X1446988Y548418D03*
X1439462Y540377D03*
X1435390Y541895D03*
X1444488Y548418D03*
X1439488D03*
X1441988D03*
X1439462Y542877D03*
Y545377D03*
X1438882Y572842D03*
X1449393Y558497D03*
Y563697D03*
Y561097D03*
X1443388Y570686D03*
X1446183Y570478D03*
X1447037Y585507D03*
X1442444D03*
X1442990Y579475D03*
X1435668Y572975D03*
Y582747D03*
X1446600Y576484D03*
X1446243Y573689D03*
X1443597Y573303D03*
X1442488Y590145D03*
X1447082Y590190D03*
X1435241Y593796D03*
X1438944Y597232D03*
X1434049Y608311D03*
X1446944Y605443D03*
X1440930Y613913D03*
Y616713D03*
Y619513D03*
X1434944Y605443D03*
X1438944Y605637D03*
X1440930Y636005D03*
Y633205D03*
X1437790Y625013D03*
X1440930Y638805D03*
X1435952Y642184D03*
X1437784Y683532D03*
X1446323Y673183D03*
X1448991Y694392D03*
X1436567Y727532D03*
X1446538Y719548D03*
X1446717Y735536D03*
X1443000Y798500D03*
Y794500D03*
Y802500D03*
X1435000Y818500D03*
X1443000Y842500D03*
Y838500D03*
Y846500D03*
X1435000Y834500D03*
X1435212Y854042D03*
X1448726Y864400D03*
X1438188Y867633D03*
X1443041Y873683D03*
X1437703Y880067D03*
X1439891Y873821D03*
X1449072Y892581D03*
X1435288Y897500D03*
X1445367Y891888D03*
X1441223Y891957D03*
X1435745Y901500D03*
X1443231Y899006D03*
X1439103Y898564D03*
X1447261Y898571D03*
X1446022Y927000D03*
X1444453Y938806D03*
X1448137Y949440D03*
X1439449Y979009D03*
X1433996Y981437D03*
X1435669Y1005366D03*
X1440610Y1021567D03*
X1435266Y1031522D03*
X1435197Y1028372D03*
X1437064Y1098767D03*
X1442674Y1106365D03*
X1436949Y1101917D03*
X1436884Y1106897D03*
X1435030Y1119422D03*
Y1113822D03*
X1439699Y1110092D03*
X1443365Y1115896D03*
Y1118396D03*
X1441220Y1131935D03*
Y1139435D03*
Y1134435D03*
Y1136935D03*
X1434520Y1125801D03*
X1437020D03*
X1434520Y1129301D03*
X1437020D03*
X1441220Y1141935D03*
Y1144435D03*
Y1146935D03*
X1442448Y1152684D03*
Y1160834D03*
X1434820Y1162384D03*
Y1164884D03*
Y1167384D03*
Y1169884D03*
Y1172384D03*
X1437320D03*
Y1169884D03*
Y1167384D03*
Y1164884D03*
Y1162384D03*
X1434925Y1179421D03*
Y1181921D03*
Y1184421D03*
Y1186921D03*
X1434820Y1174884D03*
X1437320D03*
X1434925Y1204617D03*
X1437240Y1200821D03*
Y1198321D03*
Y1192621D03*
Y1190121D03*
X1434925Y1207117D03*
Y1209617D03*
Y1212117D03*
X1436736Y1222194D03*
Y1226194D03*
X1436408Y1303462D03*
X1444438Y1308312D03*
X1439482D03*
X1443660Y1310698D03*
X1440260D03*
X1441286Y1335776D03*
X1446817Y1335846D03*
X1441200Y1338700D03*
X1435900Y1340800D03*
X1439258Y1414600D03*
X1446135Y1530876D03*
X1443103Y1527201D03*
X1437293Y1546125D03*
X1441145Y1540415D03*
X1440153Y1563093D03*
X1436801Y1568803D03*
X1464594Y3000D03*
X1462675Y14334D03*
X1452717Y34052D03*
X1455013Y43128D03*
X1457718Y84140D03*
Y76140D03*
Y80140D03*
X1460466Y76587D03*
Y72615D03*
X1452650Y94017D03*
X1457667Y118335D03*
X1460163Y117557D03*
X1455171D03*
X1463087Y103621D03*
X1451920Y103783D03*
X1454855Y106186D03*
X1457667Y132509D03*
Y121735D03*
Y135909D03*
X1455171Y122513D03*
X1460163Y131731D03*
Y122513D03*
X1455171Y131731D03*
X1457667Y118335D03*
Y121735D03*
Y132509D03*
X1458262Y146461D03*
X1460163Y136687D03*
X1455171D03*
X1457667Y135909D03*
X1457164Y152367D03*
X1463547Y180527D03*
X1458864Y180572D03*
X1455016Y168697D03*
X1464628Y171523D03*
X1458864Y185165D03*
X1463502Y185121D03*
X1452832Y184619D03*
X1456104Y191941D03*
X1454812Y206760D03*
X1458113Y206767D03*
X1463113D03*
X1460613D03*
X1451782Y213132D03*
X1463243Y221708D03*
X1460743D03*
X1458243D03*
X1457658Y224421D03*
X1459358Y231021D03*
Y228221D03*
X1451782Y215632D03*
X1459909Y236189D03*
X1464909D03*
X1462409D03*
X1456026Y256535D03*
X1459850Y248765D03*
X1464850D03*
X1462350D03*
X1452026Y256303D03*
X1457056Y279208D03*
X1460047Y270695D03*
Y268195D03*
X1462547Y270695D03*
Y268195D03*
X1465347Y270695D03*
Y268195D03*
X1465650Y293645D03*
X1451079Y290755D03*
X1465650Y288345D03*
Y290845D03*
X1463150Y288345D03*
Y290845D03*
Y293645D03*
X1451215Y323193D03*
X1451330Y327588D03*
X1459060Y320861D03*
Y325361D03*
X1451272Y340971D03*
X1451344Y336620D03*
X1451300Y332225D03*
X1459060Y329861D03*
Y338861D03*
Y343361D03*
Y334361D03*
X1451387Y345609D03*
X1451186Y350447D03*
X1458982Y356861D03*
X1459060Y347861D03*
Y352361D03*
X1455979Y391756D03*
X1459873Y391705D03*
X1458212Y403374D03*
X1458214Y406231D03*
X1464536Y433114D03*
X1458912Y581659D03*
X1454944Y605443D03*
X1453000Y614158D03*
Y616958D03*
Y619758D03*
X1450944Y605443D03*
X1458944D03*
X1453000Y633450D03*
Y636250D03*
Y639050D03*
X1455761Y683448D03*
X1460111Y683536D03*
X1451428Y673252D03*
X1460816Y727964D03*
X1455291Y759656D03*
X1455159Y763714D03*
X1453032Y769032D03*
X1453775Y813032D03*
X1461241Y867475D03*
X1462694Y874859D03*
Y877859D03*
X1460472Y885985D03*
X1457218Y888764D03*
X1452641Y888033D03*
X1459420Y899226D03*
X1451286Y898549D03*
X1451005Y931848D03*
X1461888Y936055D03*
X1462819Y949996D03*
X1462000Y960378D03*
Y957000D03*
X1460655Y964253D03*
X1457352Y976277D03*
X1466076Y979746D03*
X1459519Y989432D03*
X1462388Y1006560D03*
X1456966Y998507D03*
X1455939Y1018368D03*
X1465846Y1023900D03*
X1465503Y1030233D03*
X1464770Y1348187D03*
X1461370D03*
X1464770D03*
X1460592Y1345691D03*
Y1350683D03*
X1465548Y1345691D03*
Y1350683D03*
X1461370Y1348187D03*
X1464770Y1360099D03*
X1461370D03*
X1460592Y1357603D03*
Y1362595D03*
X1465548Y1357603D03*
Y1362595D03*
X1464770Y1360099D03*
X1461370D03*
Y1384297D03*
X1464770D03*
X1461370Y1372385D03*
X1464770D03*
D03*
X1460592Y1381801D03*
Y1374881D03*
Y1369889D03*
X1465548Y1381801D03*
Y1374881D03*
Y1369889D03*
X1461370Y1372385D03*
X1464770Y1384297D03*
X1461370D03*
X1460592Y1386793D03*
X1465548D03*
X1452000Y1644980D03*
X1481905Y-82678D03*
Y-79278D03*
X1479409Y-83456D03*
Y-78500D03*
X1481905Y-79278D03*
Y-82678D03*
Y-69278D03*
Y-72678D03*
X1479409Y-68500D03*
Y-73456D03*
X1481905Y-69278D03*
Y-72678D03*
X1476822Y40780D03*
X1479972D03*
X1480460Y60922D03*
X1475296Y55513D03*
X1472146D03*
X1468371Y68581D03*
X1477606Y60438D03*
X1468384Y80581D03*
X1472489Y91951D03*
X1472514Y88801D03*
X1478428Y86046D03*
X1475431Y94351D03*
X1471093Y117261D03*
X1478624Y113394D03*
X1481273Y110784D03*
X1478624Y116594D03*
X1466278Y112083D03*
X1481368Y130898D03*
X1478624Y119594D03*
X1477465Y161306D03*
X1469221Y152562D03*
X1474716Y157370D03*
X1478800Y180665D03*
Y172665D03*
Y168665D03*
Y176665D03*
X1467270Y192421D03*
X1470899Y186629D03*
X1478800Y192665D03*
X1478913Y186778D03*
X1478832Y200864D03*
Y212864D03*
Y204864D03*
Y208864D03*
Y216864D03*
Y221864D03*
X1467593Y221642D03*
X1474473Y219379D03*
X1480589Y252371D03*
Y248371D03*
X1471507Y265897D03*
X1469007D03*
X1477549Y327200D03*
Y322700D03*
Y345200D03*
Y340700D03*
Y331700D03*
Y358700D03*
Y349700D03*
Y354200D03*
X1480702Y368516D03*
X1468309Y408861D03*
X1473364Y410724D03*
X1472403Y417338D03*
X1475236Y412482D03*
X1466231Y423671D03*
X1469538Y416795D03*
X1469293Y428815D03*
X1473900Y433100D03*
X1466653Y428582D03*
X1471375Y433115D03*
X1478710Y685630D03*
X1477597Y682997D03*
X1474713Y685247D03*
X1479297Y693630D03*
X1476794Y691447D03*
X1473525Y710052D03*
X1479500Y706500D03*
X1474425Y716075D03*
Y712925D03*
X1474000Y707000D03*
X1479962Y727500D03*
X1469116Y719055D03*
X1471415Y748629D03*
X1479500Y750500D03*
X1479759Y743500D03*
X1479657Y735500D03*
X1469957Y750957D03*
X1474425Y760075D03*
Y756925D03*
X1474000Y753093D03*
X1476677Y827626D03*
X1473634Y864337D03*
X1473489Y861354D03*
X1474060Y877196D03*
X1473468Y874267D03*
X1482387Y872940D03*
X1473433Y891043D03*
X1481454Y911570D03*
X1474075Y920575D03*
X1470925D03*
X1480343Y914776D03*
X1480109Y943496D03*
X1474349Y949394D03*
X1479441Y961941D03*
X1468500Y974181D03*
X1476500Y974000D03*
X1482237Y966028D03*
X1475096Y980330D03*
X1471096D03*
X1479096Y988813D03*
X1471296D03*
X1479096Y997860D03*
X1471096D03*
X1475096D03*
X1467096D03*
X1475062Y1008300D03*
Y1002453D03*
X1479624Y1035102D03*
X1468371Y1030701D03*
X1476230Y1030672D03*
X1473230D03*
X1480193Y1102091D03*
X1474384D03*
X1480193Y1114691D03*
X1474384D03*
X1471374Y1118654D03*
X1474384Y1109564D03*
X1480231D03*
X1474384Y1122164D03*
X1480231D03*
X1480193Y1127291D03*
X1474384D03*
X1480193Y1139891D03*
X1474384D03*
Y1134764D03*
X1480231D03*
X1480193Y1152491D03*
X1474384D03*
Y1147364D03*
X1480231D03*
X1480193Y1165091D03*
X1474384Y1172564D03*
X1480231D03*
X1474384Y1159964D03*
X1480231D03*
X1480193Y1177691D03*
X1474384D03*
Y1185164D03*
X1480231D03*
X1477846Y1204932D03*
X1477010Y1348187D03*
X1473610D03*
X1477010D03*
X1477788Y1350683D03*
Y1345691D03*
X1472832Y1350683D03*
Y1345691D03*
X1473610Y1348187D03*
Y1360099D03*
X1477010D03*
X1477788Y1357603D03*
Y1362595D03*
X1472832Y1357603D03*
Y1362595D03*
X1473610Y1360099D03*
X1477010D03*
X1473610Y1384297D03*
X1477010D03*
Y1372385D03*
X1473610D03*
D03*
X1477010D03*
X1477788Y1381801D03*
Y1369795D03*
Y1374881D03*
X1472832Y1381801D03*
Y1369795D03*
Y1374881D03*
X1473610Y1384297D03*
X1477010D03*
X1473610Y1396583D03*
X1477010D03*
D03*
X1477788Y1386793D03*
Y1399079D03*
Y1393993D03*
X1472832Y1386793D03*
Y1393993D03*
Y1399079D03*
X1473610Y1396583D03*
Y1408495D03*
X1477010D03*
X1477788Y1405999D03*
Y1410991D03*
X1472832Y1405999D03*
Y1410991D03*
X1473610Y1408495D03*
X1477010D03*
X1476094Y1465913D03*
Y1461182D03*
Y1456451D03*
Y1471805D03*
Y1481267D03*
Y1476536D03*
Y1491890D03*
Y1487159D03*
Y1496621D03*
Y1502514D03*
Y1511976D03*
Y1507245D03*
Y1563544D03*
Y1558813D03*
Y1568275D03*
Y1578898D03*
Y1574167D03*
Y1583629D03*
Y1594253D03*
Y1589522D03*
Y1609607D03*
Y1598984D03*
Y1604876D03*
Y1614338D03*
X1472000Y1644980D03*
X1487851Y-77080D03*
X1491092Y-79984D03*
X1491104Y-77094D03*
X1487836Y-87777D03*
X1491089D03*
X1487851Y-85262D03*
X1491104D03*
X1491092Y-82584D03*
X1484811Y-86371D03*
X1491092Y-71970D03*
X1487836Y-74565D03*
X1491089Y-74579D03*
X1487836Y-64265D03*
X1491089D03*
X1491092Y-69470D03*
X1487851Y-66780D03*
X1491104D03*
X1484811Y-65585D03*
Y-75885D03*
X1484594Y3000D03*
X1498621Y15043D03*
Y19043D03*
Y35043D03*
Y27043D03*
Y31043D03*
Y23043D03*
X1483287Y94374D03*
X1486842Y102249D03*
X1482842D03*
X1493859Y109172D03*
X1496859D03*
X1495866Y106495D03*
X1490593Y116594D03*
X1495866Y102495D03*
X1488867Y133298D03*
X1490593Y119594D03*
X1495600Y146012D03*
X1497506Y141228D03*
X1483014Y134579D03*
X1495600Y142862D03*
X1486642Y195176D03*
X1488761Y198883D03*
X1489142Y195176D03*
X1484142D03*
X1492690Y206838D03*
X1490190D03*
X1484002Y203393D03*
X1486502D03*
X1493260Y226320D03*
X1493194Y221970D03*
X1490481Y216385D03*
X1493194Y216970D03*
Y219470D03*
X1486681Y218085D03*
X1483881D03*
X1492186Y238589D03*
X1495152Y236121D03*
X1495178Y232971D03*
X1495071Y253198D03*
X1497446Y295877D03*
X1484796Y320359D03*
X1484968Y325025D03*
X1486360Y322700D03*
X1484876Y329377D03*
X1488255Y342921D03*
X1484682Y338394D03*
X1497760Y336543D03*
X1486360Y345200D03*
X1487152Y331272D03*
X1487926Y347387D03*
X1486360Y358700D03*
Y354200D03*
Y349700D03*
X1483813Y368516D03*
X1494286Y372699D03*
X1488000Y731500D03*
X1495500Y750500D03*
X1496473Y769000D03*
X1496763Y777000D03*
X1491062Y793003D03*
X1496500Y792000D03*
X1496756Y785000D03*
X1491425Y798425D03*
X1486957Y792457D03*
X1491425Y801575D03*
X1496845Y813000D03*
X1496621Y829000D03*
X1496447Y821000D03*
X1493092Y820444D03*
X1491425Y845575D03*
X1496500Y836000D03*
X1489650Y836985D03*
X1491425Y842425D03*
X1486957Y836457D03*
X1492625Y837324D03*
X1489805Y866386D03*
X1497488Y873839D03*
X1491414Y875383D03*
X1488138Y878339D03*
Y872839D03*
X1494000Y884000D03*
X1498084Y894825D03*
X1492101Y894860D03*
X1482566Y882154D03*
X1498446Y912370D03*
X1496383Y898023D03*
X1497208Y909740D03*
X1496500Y919000D03*
X1496000Y922000D03*
X1487075Y920925D03*
X1487240Y924453D03*
X1485100Y943900D03*
X1496425Y943075D03*
X1497063Y934000D03*
X1496072Y940201D03*
X1483324Y939324D03*
X1482921Y931324D03*
X1496072Y950044D03*
X1482591Y961909D03*
X1486500Y947000D03*
X1497075Y961000D03*
X1487240Y952012D03*
X1496072Y953981D03*
X1485226Y973886D03*
X1492560Y974654D03*
X1487096Y988813D03*
X1495096D03*
X1482535Y1008262D03*
Y1002453D03*
X1495339Y1009354D03*
X1491839D03*
X1486030D03*
X1491096Y997860D03*
X1483096D03*
X1495096D03*
X1487096D03*
X1482535Y1011762D03*
X1491839Y1021954D03*
X1486030D03*
Y1029427D03*
X1491877D03*
X1483693Y1102091D03*
X1496140Y1105091D03*
X1483693Y1114691D03*
X1496140Y1117691D03*
X1483693Y1127291D03*
Y1139891D03*
X1496140Y1130291D03*
X1483693Y1152491D03*
X1496140Y1155491D03*
Y1142891D03*
X1483693Y1165091D03*
X1496140Y1168091D03*
X1483693Y1177691D03*
X1496140Y1180691D03*
X1482705Y1200001D03*
X1498197Y1209607D03*
X1492471Y1215195D03*
X1484055Y1223749D03*
X1489250Y1348187D03*
X1485850D03*
X1498090D03*
X1489250D03*
X1485850D03*
X1497312Y1350683D03*
Y1345691D03*
X1485072D03*
Y1350683D03*
X1490028Y1345691D03*
Y1350683D03*
X1498090Y1348187D03*
Y1360099D03*
X1489250D03*
X1485850D03*
X1497312Y1357603D03*
Y1362595D03*
X1485072D03*
Y1357603D03*
X1490028D03*
Y1362595D03*
X1498090Y1360099D03*
X1485850D03*
X1489250D03*
Y1384297D03*
X1485850D03*
Y1372385D03*
X1489250D03*
X1498090D03*
Y1384297D03*
X1489250Y1372385D03*
X1485850D03*
X1485072Y1369889D03*
Y1374881D03*
Y1381801D03*
X1490028Y1369889D03*
Y1374881D03*
Y1381801D03*
X1497312D03*
Y1374881D03*
Y1369889D03*
X1498090Y1372385D03*
X1485850Y1384297D03*
X1498090D03*
X1489250D03*
X1498090Y1396583D03*
X1489250D03*
X1485850D03*
X1498090D03*
X1485850D03*
X1489250D03*
X1497312Y1386793D03*
Y1394087D03*
Y1399079D03*
X1485072Y1394087D03*
Y1399079D03*
Y1386793D03*
X1490028Y1399079D03*
Y1394087D03*
Y1386793D03*
X1485850Y1408495D03*
X1498090D03*
X1489250D03*
X1497312Y1405999D03*
Y1410991D03*
X1485072Y1405999D03*
Y1410991D03*
X1490028Y1405999D03*
Y1410991D03*
X1498090Y1408495D03*
X1489250D03*
X1485850D03*
X1484755Y1465513D03*
Y1460782D03*
X1493417Y1465913D03*
Y1456451D03*
Y1461182D03*
Y1471805D03*
Y1476536D03*
Y1481267D03*
X1484755Y1476136D03*
Y1470244D03*
Y1480867D03*
Y1496221D03*
X1493417Y1487159D03*
Y1491890D03*
Y1496621D03*
X1484755Y1491490D03*
Y1485598D03*
Y1506845D03*
Y1500952D03*
Y1511576D03*
X1493417Y1507245D03*
Y1502514D03*
Y1511976D03*
X1484755Y1516307D03*
Y1563144D03*
X1493417Y1558813D03*
Y1563544D03*
Y1578898D03*
X1484755Y1567875D03*
Y1578498D03*
Y1572606D03*
X1493417Y1568275D03*
Y1574167D03*
X1484755Y1583229D03*
Y1593853D03*
Y1587960D03*
X1493417Y1583629D03*
Y1589522D03*
Y1594253D03*
X1484755Y1609207D03*
Y1598584D03*
Y1603315D03*
X1493417Y1609607D03*
Y1604876D03*
Y1598984D03*
X1484755Y1613938D03*
Y1618669D03*
X1493417Y1614338D03*
X1492000Y1644980D03*
X1514765Y-44536D03*
Y-39580D03*
Y-29580D03*
Y-34536D03*
X1500578Y4469D03*
X1501939Y24773D03*
Y44773D03*
X1509260Y53597D03*
X1504460Y95111D03*
X1509310Y111255D03*
Y114655D03*
X1502010Y118342D03*
X1511610Y116496D03*
Y109410D03*
Y102323D03*
X1499610Y116497D03*
X1506910D03*
X1504410D03*
X1506910Y109410D03*
X1509310Y114655D03*
Y111255D03*
X1508829Y106561D03*
X1502010Y132515D03*
X1509310Y128828D03*
Y125428D03*
X1502010Y121742D03*
Y135915D03*
X1511610Y123583D03*
X1499610Y130670D03*
Y123584D03*
X1506910Y130670D03*
X1504410D03*
Y123584D03*
X1506910Y123583D03*
X1511610Y130670D03*
X1502010Y121742D03*
X1509310Y125428D03*
Y128828D03*
X1502010Y118342D03*
Y132515D03*
X1511610Y137756D03*
X1499610Y137757D03*
X1504410D03*
X1502010Y135915D03*
X1500394Y150847D03*
X1506689Y195176D03*
X1501689D03*
X1503207Y199248D03*
X1499189Y195176D03*
X1504189D03*
X1508142Y213539D03*
X1506207Y202048D03*
X1503207Y201748D03*
X1499270Y210509D03*
X1501043Y206806D03*
X1501770Y210509D03*
X1503543Y206806D03*
X1509823Y238714D03*
X1502362Y247292D03*
X1501588Y238689D03*
X1505823Y238714D03*
X1499947Y242078D03*
X1505304Y246874D03*
X1507524Y244297D03*
X1500480Y295727D03*
X1503884Y295549D03*
X1501807Y323766D03*
X1501500Y321000D03*
X1511950Y401513D03*
Y398113D03*
X1509550Y412287D03*
X1509454Y402291D03*
X1514446D03*
X1509454Y397335D03*
X1514446D03*
X1511950Y401513D03*
Y398113D03*
X1509550Y415687D03*
Y426460D03*
Y412287D03*
X1512046Y411509D03*
X1507054Y416465D03*
Y411509D03*
X1512046Y425682D03*
X1507054D03*
X1512046Y416465D03*
X1509550Y415687D03*
Y426460D03*
Y429860D03*
Y440633D03*
Y444033D03*
X1512046Y439855D03*
X1507054D03*
X1512046Y430638D03*
X1507054D03*
X1509550Y440633D03*
Y429860D03*
X1512046Y444811D03*
X1507054D03*
X1507864Y450750D03*
X1509550Y444033D03*
Y472787D03*
Y469387D03*
Y472787D03*
X1507054Y468609D03*
X1512046D03*
X1507054Y473565D03*
X1512046D03*
X1509550Y469387D03*
Y486960D03*
Y483560D03*
X1507054Y487738D03*
X1512046D03*
X1507054Y482782D03*
X1512046D03*
X1509550Y483560D03*
Y486960D03*
Y516921D03*
Y513521D03*
X1507054Y517699D03*
X1512046D03*
X1507054Y512743D03*
X1512046D03*
X1509550Y516921D03*
Y513521D03*
Y527694D03*
Y531094D03*
Y527694D03*
X1511963Y536382D03*
X1507054Y526916D03*
X1512046Y531872D03*
X1507054D03*
X1512046Y526916D03*
X1509550Y531094D03*
X1513284Y552466D03*
X1504495Y796844D03*
X1510527Y833500D03*
X1504938Y859711D03*
X1500353Y859855D03*
X1500638Y873839D03*
X1512712Y867418D03*
X1507034Y888133D03*
X1507358Y909740D03*
X1507305Y912262D03*
X1510280Y899732D03*
X1510527Y908951D03*
X1513927D03*
X1505337Y921240D03*
X1514354Y938811D03*
X1510500Y931500D03*
X1513955Y950396D03*
X1512161Y957541D03*
X1505888Y965964D03*
X1501400Y966000D03*
X1514000Y968739D03*
X1510740Y973740D03*
X1498973Y975443D03*
X1511000Y970500D03*
X1511096Y988813D03*
X1503096D03*
X1507096Y997860D03*
X1503096D03*
X1511096D03*
X1499096D03*
X1507786Y1012354D03*
Y1024954D03*
X1503572Y1034538D03*
X1505130Y1105091D03*
Y1117691D03*
Y1130291D03*
Y1142891D03*
Y1155491D03*
Y1168091D03*
Y1180691D03*
X1500675Y1227300D03*
X1507692Y1224472D03*
X1510330Y1348187D03*
X1513730D03*
X1501490D03*
X1513730D03*
X1509552Y1350683D03*
Y1345691D03*
X1514508Y1350683D03*
Y1345691D03*
X1502268Y1350683D03*
Y1345691D03*
X1510330Y1348187D03*
X1501490D03*
X1513730Y1360099D03*
X1501490D03*
X1510330D03*
X1509552Y1362595D03*
Y1357603D03*
X1514508D03*
Y1362595D03*
X1502268Y1357603D03*
Y1362595D03*
X1510330Y1360099D03*
X1501490D03*
X1513730D03*
Y1372385D03*
X1510330D03*
X1501490D03*
Y1384297D03*
X1513730D03*
X1510330D03*
Y1372385D03*
X1513730D03*
X1501490D03*
X1509552Y1374881D03*
Y1369889D03*
Y1381801D03*
X1514508Y1374881D03*
Y1369889D03*
Y1381801D03*
X1502268D03*
Y1374881D03*
Y1369889D03*
X1501490Y1384297D03*
X1513730D03*
X1510330D03*
X1513730Y1396583D03*
X1501490D03*
X1510330D03*
D03*
X1509552Y1394087D03*
Y1399079D03*
Y1386793D03*
X1514508Y1394087D03*
Y1399079D03*
Y1386793D03*
X1502268D03*
Y1399079D03*
Y1394087D03*
X1513730Y1396583D03*
X1501490D03*
Y1408495D03*
X1510330D03*
X1513730D03*
X1509552Y1405999D03*
Y1410991D03*
X1514508Y1405999D03*
Y1410991D03*
X1502268Y1405999D03*
Y1410991D03*
X1510330Y1408495D03*
X1513730D03*
X1501490D03*
X1502078Y1465513D03*
Y1460782D03*
X1510740Y1465913D03*
Y1456451D03*
Y1461182D03*
X1502078Y1470244D03*
Y1480867D03*
X1510740Y1471805D03*
Y1476536D03*
Y1481267D03*
X1502078Y1476136D03*
Y1491490D03*
Y1485598D03*
Y1496221D03*
X1510740Y1487159D03*
Y1491890D03*
Y1496621D03*
Y1507245D03*
Y1502514D03*
Y1511976D03*
X1502078Y1506845D03*
Y1500952D03*
Y1511576D03*
Y1516307D03*
X1510740Y1563544D03*
X1502078Y1563144D03*
X1510740Y1558813D03*
Y1578898D03*
X1502078Y1567875D03*
Y1578498D03*
Y1572606D03*
X1510740Y1568275D03*
Y1574167D03*
X1502078Y1583229D03*
Y1593853D03*
Y1587960D03*
X1510740Y1583629D03*
Y1589522D03*
Y1594253D03*
X1502078Y1609207D03*
Y1598584D03*
Y1603315D03*
X1510740Y1609607D03*
Y1604876D03*
Y1598984D03*
X1502078Y1613938D03*
Y1618669D03*
X1510740Y1614338D03*
X1512000Y1644980D03*
X1517261Y-43758D03*
X1523192Y-48857D03*
X1526445D03*
X1523207Y-46342D03*
X1526460D03*
X1520167Y-47451D03*
X1517261Y-40358D03*
Y-30358D03*
Y-33758D03*
X1526448Y-33050D03*
X1523192Y-35645D03*
X1526445Y-35659D03*
X1526448Y-30550D03*
X1523207Y-38160D03*
X1526448Y-41064D03*
X1526460Y-38174D03*
X1526448Y-43664D03*
X1520167Y-36965D03*
X1517261Y-33758D03*
Y-40358D03*
Y-30358D03*
Y-43758D03*
X1523192Y-25345D03*
X1526445D03*
X1523207Y-27860D03*
X1526460D03*
X1520167Y-26665D03*
X1529260Y53597D03*
X1520072Y82984D03*
Y75184D03*
Y77784D03*
Y80384D03*
X1522626Y92849D03*
X1520072Y85584D03*
X1529543Y95236D03*
X1519610D03*
X1529586Y103037D03*
X1519610Y102323D03*
X1519862Y109410D03*
Y116496D03*
X1529720D03*
Y109410D03*
X1520034Y124576D03*
X1529720Y130670D03*
Y123583D03*
X1521087Y130670D03*
X1526311Y137756D03*
X1521082D03*
X1528355Y210478D03*
Y215478D03*
Y212978D03*
Y207978D03*
Y228726D03*
Y223726D03*
Y226226D03*
Y231226D03*
X1515779Y351594D03*
X1519952Y391001D03*
Y394401D03*
X1517456Y390223D03*
X1522448D03*
X1519952Y391001D03*
X1519321Y382600D03*
X1519952Y405174D03*
Y408574D03*
Y394401D03*
X1517456Y395179D03*
Y404396D03*
Y409352D03*
X1522448Y395179D03*
Y404396D03*
Y409352D03*
X1519952Y408574D03*
Y405174D03*
Y419347D03*
Y422747D03*
D03*
X1517456Y418569D03*
Y423525D03*
X1522448D03*
Y418569D03*
X1519952Y419347D03*
Y436921D03*
Y433521D03*
Y436921D03*
X1522448Y437699D03*
X1517456Y432743D03*
Y437699D03*
X1522448Y432743D03*
X1519952Y433521D03*
X1519436Y458711D03*
X1521963Y453682D03*
X1520200Y455921D03*
X1519952Y476499D03*
X1518780Y463600D03*
X1519952Y479899D03*
Y490673D03*
Y479899D03*
X1517456Y489895D03*
X1522448D03*
X1517456Y480677D03*
Y475721D03*
X1522448Y480677D03*
Y475721D03*
X1519952Y476499D03*
Y490673D03*
Y494073D03*
D03*
X1517456Y494851D03*
X1522448D03*
X1519952Y524033D03*
Y520633D03*
X1517456Y519855D03*
X1522448D03*
X1519952Y520633D03*
Y524033D03*
Y538206D03*
Y534806D03*
D03*
X1522448Y538984D03*
X1517456D03*
Y524811D03*
Y534028D03*
X1522448D03*
Y524811D03*
X1519952Y538206D03*
X1528635Y555234D03*
X1528350Y562003D03*
X1519156Y596095D03*
X1516869Y594668D03*
X1518354Y592354D03*
X1518415Y589556D03*
X1519153Y599588D03*
X1516930Y597580D03*
X1519185Y603600D03*
X1519153Y607588D03*
X1519185Y619600D03*
X1523646Y634946D03*
X1519185Y623600D03*
X1524200Y646098D03*
X1519063Y876339D03*
X1518517Y878898D03*
X1518452Y873780D03*
X1517344Y896999D03*
X1515743Y888133D03*
X1517344Y903179D03*
X1517153Y908367D03*
X1516283Y912240D03*
X1519116D03*
X1523053Y912262D03*
X1522881Y901034D03*
X1522954Y897951D03*
X1523000Y923740D03*
X1526611Y921442D03*
X1525740Y928740D03*
X1521085Y921094D03*
X1515179D03*
X1527876Y939439D03*
X1528087Y936394D03*
X1527267Y932647D03*
X1522209Y937846D03*
X1524500Y949500D03*
X1525022Y957340D03*
X1530174Y956986D03*
X1529128Y952978D03*
X1521085Y957340D03*
X1525522Y971075D03*
X1525583Y968500D03*
X1530767Y972981D03*
X1519863Y977637D03*
X1525005Y974323D03*
X1523966Y980281D03*
X1530594Y979952D03*
X1519096Y988813D03*
X1515096Y997860D03*
X1531096D03*
X1519096D03*
X1523096D03*
X1516776Y1024954D03*
Y1012354D03*
X1517855Y1053457D03*
X1522570Y1348187D03*
X1525970D03*
D03*
X1526748Y1345691D03*
Y1350683D03*
X1521792Y1345691D03*
Y1350683D03*
X1522570Y1348187D03*
Y1360099D03*
X1525970D03*
X1526748Y1357603D03*
Y1362595D03*
X1521792Y1357603D03*
Y1362595D03*
X1522570Y1360099D03*
X1525970D03*
X1522570Y1384297D03*
X1525970D03*
X1522570Y1372385D03*
X1525970D03*
D03*
X1526748Y1369889D03*
Y1374881D03*
Y1381801D03*
X1521792Y1374881D03*
Y1381801D03*
Y1369889D03*
X1522570Y1372385D03*
X1525970Y1384297D03*
X1522570D03*
Y1396583D03*
X1525970D03*
X1522570D03*
X1526748Y1386793D03*
Y1399079D03*
Y1394087D03*
X1521792Y1386793D03*
Y1394087D03*
Y1399079D03*
X1525970Y1396583D03*
X1522570Y1408495D03*
X1525970D03*
X1526748Y1405999D03*
Y1410991D03*
X1521792Y1405999D03*
Y1410991D03*
X1525970Y1408495D03*
X1522570D03*
X1519401Y1465513D03*
Y1460782D03*
X1528062Y1465913D03*
Y1456451D03*
Y1461182D03*
Y1481267D03*
X1519401Y1476136D03*
Y1470244D03*
Y1480867D03*
X1528062Y1471805D03*
Y1476536D03*
X1519401Y1491490D03*
Y1485598D03*
Y1496221D03*
X1528062Y1487159D03*
Y1491890D03*
Y1496621D03*
X1519401Y1506845D03*
Y1500952D03*
Y1511576D03*
X1528062Y1507245D03*
Y1502514D03*
Y1511976D03*
X1519401Y1516307D03*
Y1563144D03*
X1528062Y1558813D03*
Y1563544D03*
Y1578898D03*
X1519401Y1567875D03*
Y1578498D03*
Y1572606D03*
X1528062Y1568275D03*
Y1574167D03*
X1519401Y1587960D03*
X1528062Y1583629D03*
Y1589522D03*
Y1594253D03*
X1519401Y1583229D03*
Y1593853D03*
Y1609207D03*
Y1598584D03*
Y1603315D03*
X1528062Y1609607D03*
Y1604876D03*
Y1598984D03*
X1519401Y1613938D03*
Y1618669D03*
X1528062Y1614338D03*
X1547367Y44773D03*
X1538407Y85539D03*
Y82939D03*
Y75139D03*
Y80339D03*
Y77739D03*
X1547003Y94017D03*
X1543003D03*
X1546732Y101701D03*
Y98551D03*
X1547131Y110445D03*
Y115401D03*
X1537720Y116496D03*
Y109410D03*
Y102323D03*
X1540478Y107649D03*
Y104249D03*
X1547131Y129574D03*
X1537720Y130670D03*
Y123583D03*
X1547131Y124618D03*
X1537720Y137756D03*
X1545044Y147540D03*
Y151540D03*
X1540100Y162368D03*
X1537500D03*
X1547200Y162793D03*
Y165393D03*
Y167993D03*
Y170493D03*
X1546197Y181426D03*
X1546405Y184221D03*
X1538811Y213213D03*
Y210713D03*
X1542883Y211695D03*
X1545383D03*
X1542883Y208695D03*
X1538811Y208213D03*
Y226461D03*
X1542518Y226141D03*
X1538811Y228961D03*
Y231461D03*
X1546780Y229286D03*
X1538811Y215713D03*
X1542761Y236611D03*
X1545261D03*
X1546780Y231786D03*
X1542463Y248891D03*
X1544963D03*
X1534184Y264180D03*
X1531684D03*
X1531609Y258880D03*
X1545878Y270026D03*
X1543378D03*
X1540578D03*
X1543378Y267526D03*
X1540578D03*
X1545878D03*
X1531901Y293796D03*
X1539915Y288190D03*
X1542415Y285690D03*
X1539915D03*
X1542415Y288190D03*
X1545215D03*
Y285690D03*
X1534401Y293796D03*
X1544736Y305156D03*
X1541534Y322850D03*
X1541283Y354553D03*
X1538133D03*
X1546183Y541863D03*
Y545263D03*
X1544375Y553407D03*
X1546875D03*
X1544375Y550907D03*
X1546875D03*
X1542704Y572162D03*
X1543946Y569928D03*
X1546293Y570962D03*
X1546036Y568475D03*
X1532067Y1041832D03*
X1531947Y1046212D03*
X1531546Y1062769D03*
X1538210Y1348187D03*
X1547050D03*
X1534810D03*
X1538210D03*
X1547050D03*
X1546272Y1350683D03*
Y1345691D03*
X1534032Y1350683D03*
Y1345691D03*
X1538988D03*
Y1350683D03*
X1534810Y1348187D03*
X1547050Y1360099D03*
X1534810D03*
X1538210D03*
X1546272Y1357603D03*
Y1362595D03*
X1534032Y1357603D03*
Y1362595D03*
X1538988D03*
Y1357603D03*
X1538210Y1360099D03*
X1534810D03*
X1547050D03*
X1538210Y1384297D03*
X1547050Y1372385D03*
Y1384297D03*
X1534810Y1372385D03*
X1538210D03*
X1534810Y1384297D03*
X1538210Y1372385D03*
X1534810D03*
X1547050D03*
X1546272Y1374881D03*
Y1369889D03*
Y1381801D03*
X1534032Y1369889D03*
Y1381801D03*
Y1374881D03*
X1538988Y1369889D03*
Y1381801D03*
Y1374881D03*
X1547050Y1384297D03*
X1534810D03*
X1538210D03*
X1547050Y1396583D03*
X1534810D03*
X1538210D03*
D03*
X1546272Y1386793D03*
Y1394087D03*
Y1399079D03*
X1534032Y1394087D03*
Y1399079D03*
Y1386793D03*
X1538988Y1394087D03*
Y1399079D03*
Y1386793D03*
X1534810Y1396583D03*
X1547050D03*
Y1408495D03*
X1534810D03*
X1538210D03*
X1546272Y1405999D03*
Y1410991D03*
X1534032Y1405999D03*
Y1410991D03*
X1538988Y1405999D03*
Y1410991D03*
X1538210Y1408495D03*
X1534810D03*
X1547050D03*
X1545385Y1461183D03*
X1536724Y1465513D03*
Y1460782D03*
X1545385Y1465914D03*
Y1456452D03*
X1536724Y1476136D03*
Y1470244D03*
Y1480867D03*
X1545385Y1476537D03*
Y1471806D03*
Y1481268D03*
X1536724Y1491490D03*
Y1485598D03*
Y1496221D03*
X1545385Y1491891D03*
Y1487160D03*
Y1496622D03*
X1536724Y1506845D03*
Y1500952D03*
Y1511576D03*
X1545385Y1507246D03*
Y1502515D03*
Y1511977D03*
X1536724Y1516307D03*
X1545385Y1563544D03*
Y1558813D03*
X1536724Y1563144D03*
Y1567875D03*
X1545385Y1568275D03*
X1536724Y1578498D03*
Y1572606D03*
X1545385Y1578898D03*
Y1574167D03*
Y1594253D03*
Y1589522D03*
X1536724Y1583229D03*
X1545385Y1583629D03*
X1536724Y1593853D03*
Y1587960D03*
Y1609207D03*
Y1598584D03*
Y1603315D03*
X1545385Y1609607D03*
Y1598984D03*
Y1604876D03*
Y1614338D03*
X1536724Y1613938D03*
Y1618669D03*
X1532000Y1644980D03*
X1560080Y84140D03*
Y76140D03*
Y80140D03*
X1562828Y72615D03*
Y76587D03*
X1555012Y94017D03*
X1551003D03*
X1549627Y114623D03*
Y111223D03*
X1560029Y118335D03*
X1562525Y117557D03*
X1557533D03*
X1552123Y115401D03*
Y110445D03*
X1554282Y103783D03*
X1549627Y111223D03*
Y114623D03*
X1557217Y106186D03*
X1550282Y103783D03*
X1560029Y121735D03*
Y132509D03*
X1549627Y128796D03*
Y125396D03*
X1560029Y135909D03*
X1549627Y128796D03*
X1560029Y132509D03*
Y121735D03*
X1562525Y122513D03*
X1552123Y129574D03*
Y124618D03*
X1557533Y131731D03*
Y122513D03*
X1562525Y131731D03*
X1560029Y118335D03*
X1549627Y125396D03*
X1560029Y135909D03*
X1560624Y146461D03*
X1557533Y136687D03*
X1562525D03*
X1548816Y141247D03*
X1559526Y152367D03*
X1561226Y180572D03*
X1552203Y181009D03*
X1549408Y181366D03*
X1557378Y168697D03*
X1548694Y191941D03*
X1555194Y184619D03*
X1561226Y185165D03*
X1558466Y191941D03*
X1549022Y184012D03*
X1557174Y206760D03*
X1560475Y206767D03*
X1562975D03*
X1554144Y213132D03*
X1550441Y211359D03*
Y213859D03*
X1550473Y222212D03*
Y224712D03*
X1560605Y221708D03*
X1560020Y224421D03*
X1563105Y221708D03*
X1561720Y231021D03*
Y228221D03*
X1554144Y215632D03*
X1547761Y236611D03*
X1562271Y236189D03*
X1550388Y256535D03*
X1558388D03*
X1547463Y248891D03*
X1562212Y248765D03*
X1554388Y256303D03*
X1559418Y279208D03*
X1562409Y268195D03*
Y270695D03*
X1549441Y290755D03*
X1553441D03*
X1547972Y304906D03*
X1556151Y318596D03*
X1556294Y327814D03*
X1554403Y316363D03*
X1556437Y332022D03*
X1556380Y336917D03*
X1556498Y340958D03*
X1553910Y331798D03*
X1553862Y344867D03*
X1556353Y345636D03*
X1554403Y352363D03*
X1556429Y389154D03*
X1563248D03*
X1548629D03*
Y403327D03*
Y410413D03*
X1556429Y396240D03*
X1557708Y404911D03*
X1561778Y396240D03*
X1548629D03*
X1556662Y412571D03*
X1557849Y426299D03*
X1548629Y417500D03*
Y424587D03*
Y438760D03*
Y431673D03*
X1558160Y445847D03*
X1548629D03*
X1556429Y467539D03*
X1548629D03*
X1556429Y474626D03*
X1548629D03*
Y488799D03*
X1556690Y480828D03*
X1548629Y481713D03*
Y495886D03*
X1558640Y498834D03*
X1548629Y511673D03*
Y518760D03*
X1562089Y516841D03*
X1556429Y518760D03*
Y511673D03*
X1548629Y540020D03*
Y525847D03*
Y532933D03*
X1556429Y525847D03*
X1548629Y547106D03*
X1556914Y552872D03*
X1557036Y550123D03*
X1556359Y562443D03*
X1558668Y572334D03*
X1558127Y560675D03*
X1548359Y569426D03*
X1548645Y566929D03*
X1556900Y574102D03*
X1547910Y602197D03*
X1562385Y598400D03*
Y602400D03*
Y594400D03*
X1548374Y595108D03*
X1562385Y614400D03*
Y606400D03*
Y610400D03*
X1561535Y653161D03*
X1561552Y665455D03*
X1547813Y906581D03*
X1548629Y927836D03*
X1548504Y915689D03*
X1548616Y931602D03*
X1551099Y959096D03*
X1551163Y952888D03*
X1552000Y969850D03*
X1550450Y1348187D03*
X1559290D03*
X1562690D03*
X1550450D03*
X1558512Y1345691D03*
Y1350683D03*
X1563468D03*
Y1345691D03*
X1551228Y1350683D03*
Y1345691D03*
X1559290Y1348187D03*
X1562690D03*
Y1360099D03*
X1550450D03*
X1559290D03*
X1563468Y1362595D03*
X1551228Y1357603D03*
Y1362595D03*
X1558512D03*
Y1357603D03*
X1563468D03*
X1559290Y1360099D03*
X1562690D03*
X1550450D03*
X1559290Y1384297D03*
X1562690D03*
X1550450Y1372385D03*
X1562690D03*
X1559290D03*
X1550450Y1384297D03*
X1562690Y1372385D03*
X1559290D03*
X1558512Y1374881D03*
Y1369889D03*
Y1381801D03*
X1563468Y1374881D03*
Y1369889D03*
Y1381801D03*
X1551228Y1369889D03*
Y1381801D03*
Y1374881D03*
X1550450Y1372385D03*
X1562690Y1384297D03*
X1559290D03*
X1550450D03*
X1562690Y1396583D03*
X1559290D03*
X1550450D03*
D03*
X1562690D03*
X1558512Y1399079D03*
Y1394087D03*
Y1386793D03*
X1563468Y1399079D03*
Y1394087D03*
Y1386793D03*
X1551228D03*
Y1394087D03*
Y1399079D03*
X1559290Y1396583D03*
X1550450Y1408495D03*
X1562690D03*
X1559290D03*
X1558512Y1405999D03*
Y1410991D03*
X1563468Y1405999D03*
Y1410991D03*
X1551228Y1405999D03*
Y1410991D03*
X1559290Y1408495D03*
X1562690D03*
X1550450D03*
X1552000Y1644980D03*
X1576256Y-48799D03*
X1573003D03*
X1576241Y-46284D03*
X1572988D03*
X1579281Y-47479D03*
X1573000Y-41094D03*
X1576256Y-38499D03*
X1573003Y-38485D03*
X1573000Y-43594D03*
X1576241Y-35984D03*
X1573000Y-33080D03*
X1572988Y-35970D03*
X1573000Y-30480D03*
X1579281Y-37179D03*
X1576256Y-25273D03*
X1573003Y-25287D03*
X1576241Y-27788D03*
X1572988Y-27802D03*
X1579281Y-26693D03*
X1571895Y58013D03*
X1570733Y68581D03*
X1570746Y80581D03*
X1574851Y91951D03*
X1574876Y88801D03*
X1577793Y94351D03*
X1573455Y117261D03*
X1565449Y103621D03*
X1568640Y112083D03*
X1579827Y161306D03*
X1571583Y152562D03*
X1577078Y157370D03*
X1565909Y180527D03*
X1566990Y171523D03*
X1569632Y192421D03*
X1565864Y185121D03*
X1573261Y186629D03*
X1565475Y206767D03*
X1565605Y221708D03*
X1569955Y221642D03*
X1576835Y219379D03*
X1564771Y236189D03*
X1567271D03*
X1564712Y248765D03*
X1567212D03*
X1567709Y270695D03*
X1573869Y265897D03*
X1571369D03*
X1567709Y268195D03*
X1564909Y270695D03*
Y268195D03*
X1565512Y288345D03*
X1568012Y293645D03*
Y290845D03*
Y288345D03*
X1565512Y293645D03*
Y290845D03*
X1563877Y325363D03*
Y316363D03*
X1574845Y338843D03*
X1571625Y333549D03*
Y344131D03*
X1574775Y333549D03*
X1563877Y329863D03*
Y343363D03*
Y334363D03*
X1578587Y341787D03*
X1563877Y352363D03*
X1574540Y389154D03*
X1576940Y401482D03*
Y398082D03*
Y412255D03*
X1579340Y396240D03*
Y403327D03*
Y410413D03*
X1574540Y396240D03*
Y403327D03*
Y410413D03*
X1576940Y398082D03*
Y401482D03*
Y426428D03*
Y415655D03*
X1566555Y414823D03*
X1565863Y422864D03*
X1579340Y417500D03*
Y424586D03*
X1574540Y417500D03*
Y424586D03*
X1576940Y415655D03*
Y412255D03*
Y426428D03*
Y429828D03*
Y440602D03*
Y444002D03*
X1565933Y429832D03*
X1565538Y436447D03*
X1574540Y438760D03*
X1579340Y431673D03*
Y438760D03*
X1574540Y431673D03*
X1576940Y440602D03*
Y429828D03*
X1567573Y447953D03*
X1579340Y445847D03*
X1574540D03*
X1576940Y444002D03*
Y476468D03*
X1566740Y467539D03*
X1574540D03*
X1565482Y472772D03*
X1574540Y474626D03*
X1579340D03*
X1576940Y479868D03*
Y490641D03*
X1579340Y488799D03*
X1574540D03*
X1566216Y487711D03*
X1566329Y479104D03*
X1574540Y481713D03*
X1579340Y481712D03*
X1576940Y476468D03*
Y490641D03*
Y479868D03*
Y494041D03*
X1579340Y495886D03*
X1574540D03*
X1566740D03*
X1576940Y494041D03*
Y520602D03*
Y524002D03*
X1579340Y518760D03*
X1574540Y511673D03*
Y518760D03*
X1565050Y511673D03*
X1576940Y520602D03*
Y524002D03*
Y534775D03*
Y538175D03*
X1574540Y540020D03*
X1579340D03*
Y532933D03*
Y525846D03*
X1574540Y525847D03*
Y532933D03*
X1576940Y534775D03*
Y538175D03*
X1574540Y547106D03*
Y554193D03*
X1575000Y565414D03*
Y567914D03*
Y570414D03*
X1575934Y561420D03*
Y558917D03*
X1575000Y572914D03*
Y575414D03*
X1565323Y577716D03*
X1571755Y577937D03*
X1574540Y602205D03*
Y595118D03*
X1579753Y599100D03*
X1578679Y613047D03*
X1578114Y607563D03*
X1574222Y629872D03*
X1576297Y627600D03*
X1574880Y645891D03*
X1569926Y668885D03*
X1575950Y662981D03*
X1572141D03*
X1578000Y678776D03*
X1569434Y677111D03*
X1570331Y691851D03*
X1568872Y686971D03*
X1575942Y705043D03*
X1575192Y707592D03*
X1574930Y1348187D03*
X1571530D03*
X1574930D03*
X1571530D03*
X1575708Y1345597D03*
X1570752Y1350683D03*
Y1345597D03*
X1575708Y1350683D03*
X1571530Y1360099D03*
X1574930D03*
X1570752Y1357603D03*
Y1362595D03*
X1575708D03*
Y1357603D03*
X1574930Y1360099D03*
X1571530D03*
X1574930Y1372385D03*
Y1384297D03*
X1571530Y1372385D03*
Y1384297D03*
X1575708Y1381801D03*
Y1374881D03*
Y1369889D03*
X1570752D03*
Y1381801D03*
Y1374881D03*
X1574930Y1372385D03*
X1571530D03*
Y1384297D03*
X1574930D03*
X1571530Y1396583D03*
X1574930D03*
X1571530D03*
X1575708Y1386793D03*
Y1399079D03*
Y1393993D03*
X1570752Y1386793D03*
Y1393993D03*
Y1399079D03*
X1574930Y1396583D03*
Y1408495D03*
X1571530D03*
X1575708Y1405999D03*
Y1410991D03*
X1570752Y1405999D03*
Y1410991D03*
X1571530Y1408495D03*
X1574930D03*
X1572000Y1644980D03*
X1592187Y-82706D03*
Y-79306D03*
X1583000Y-80014D03*
X1586256Y-77419D03*
X1583003Y-77405D03*
X1586256Y-87719D03*
X1583003D03*
X1583000Y-82514D03*
X1586241Y-85204D03*
X1582988D03*
X1589281Y-86399D03*
X1594683Y-83484D03*
Y-78528D03*
X1592187Y-79306D03*
Y-82706D03*
Y-69306D03*
Y-72706D03*
X1586241Y-74904D03*
X1583000Y-72000D03*
X1582988Y-74890D03*
X1586256Y-64207D03*
X1583003D03*
X1586241Y-66722D03*
X1582988D03*
X1583000Y-69400D03*
X1589281Y-76099D03*
Y-65613D03*
X1594683Y-68528D03*
Y-73484D03*
X1592187Y-69306D03*
Y-72706D03*
X1582187Y-43786D03*
X1584683Y-44564D03*
X1582187Y-30386D03*
Y-33786D03*
Y-40386D03*
X1584683Y-29608D03*
Y-34564D03*
Y-39608D03*
X1582187Y-33786D03*
Y-43786D03*
Y-30386D03*
Y-40386D03*
X1582822Y60922D03*
X1580327Y57448D03*
X1579968Y60438D03*
X1585649Y94374D03*
X1580790Y86046D03*
X1585204Y102249D03*
X1589204D03*
X1580986Y113394D03*
X1583635Y110784D03*
X1592955Y116594D03*
X1580986D03*
X1591229Y133298D03*
X1583229D03*
X1592955Y119594D03*
X1580986D03*
X1585376Y134579D03*
X1581162Y180665D03*
Y172665D03*
Y168665D03*
Y176665D03*
X1586504Y195176D03*
X1589004D03*
X1591123Y198883D03*
X1591504Y195176D03*
X1581162Y192665D03*
Y196665D03*
X1581275Y186778D03*
X1581194Y212864D03*
Y200864D03*
X1586364Y203393D03*
X1588864D03*
X1595052Y206838D03*
X1592552D03*
X1581194Y204864D03*
Y221864D03*
Y216864D03*
X1586243Y218085D03*
X1595622Y226320D03*
X1592843Y216385D03*
X1595556Y216970D03*
Y219470D03*
Y221970D03*
X1589043Y218085D03*
X1594548Y238589D03*
X1582951Y252371D03*
Y248371D03*
X1593290Y339876D03*
X1584240Y390995D03*
Y394395D03*
X1586640Y389153D03*
X1581840D03*
X1584240Y390995D03*
Y405168D03*
Y408568D03*
X1581840Y403326D03*
Y410413D03*
X1586640D03*
X1581840Y396240D03*
X1586640D03*
Y403326D03*
X1584240Y408568D03*
Y405168D03*
Y394395D03*
Y422741D03*
Y419341D03*
X1586640Y417499D03*
X1581840D03*
Y424586D03*
X1586640D03*
X1584240Y419341D03*
Y422741D03*
Y436915D03*
Y433515D03*
X1581840Y438760D03*
X1586640D03*
Y431673D03*
X1581840D03*
X1584240Y433515D03*
Y436915D03*
X1592635Y455911D03*
X1584240Y472781D03*
Y469381D03*
X1586640Y467539D03*
X1581840D03*
Y474626D03*
X1586640D03*
X1584240Y472781D03*
Y469381D03*
X1591443Y465332D03*
X1584240Y486954D03*
Y483554D03*
X1581840Y488799D03*
X1586640D03*
X1581840Y481712D03*
X1586640D03*
X1584240Y483554D03*
Y486954D03*
Y516915D03*
Y513515D03*
X1581840Y518760D03*
Y511673D03*
X1586640D03*
Y518760D03*
X1584240Y516915D03*
Y513515D03*
Y531088D03*
Y527688D03*
X1586640Y525846D03*
Y532933D03*
X1581840D03*
Y525846D03*
X1584240Y531088D03*
Y527688D03*
X1595185Y543925D03*
X1595760Y555000D03*
X1595460Y549800D03*
X1595260Y547075D03*
X1583720Y560500D03*
X1595364Y562800D03*
X1595300Y558800D03*
X1583770Y1348187D03*
X1587170D03*
D03*
X1587948Y1350683D03*
Y1345691D03*
X1582992D03*
Y1350683D03*
X1583770Y1348187D03*
Y1360099D03*
X1587170D03*
X1587948Y1362595D03*
Y1357603D03*
X1582992Y1362595D03*
Y1357603D03*
X1587170Y1360099D03*
X1583770D03*
X1587170Y1372385D03*
X1583770D03*
X1587170Y1384297D03*
X1583770D03*
X1587170Y1372385D03*
X1583770D03*
X1582992Y1369889D03*
Y1381801D03*
Y1374881D03*
X1587948Y1369889D03*
Y1381801D03*
Y1374881D03*
X1583770Y1384297D03*
X1587170D03*
X1583770Y1396583D03*
X1587170D03*
X1583770D03*
X1582992Y1399079D03*
Y1394087D03*
Y1386793D03*
X1587948Y1399079D03*
Y1394087D03*
Y1386793D03*
X1587170Y1396583D03*
Y1408495D03*
X1583770D03*
X1582992Y1405999D03*
Y1410991D03*
X1587948Y1405999D03*
Y1410991D03*
X1583770Y1408495D03*
X1587170D03*
X1592020Y1433061D03*
X1592643Y1460707D03*
X1593019Y1457557D03*
X1591610Y1469940D03*
X1591775Y1473090D03*
X1591586Y1505130D03*
X1591925Y1512075D03*
X1591333Y1501980D03*
X1604301Y44773D03*
X1611622Y53597D03*
X1606822Y95111D03*
X1611672Y114655D03*
Y111255D03*
X1604372Y118342D03*
X1609272Y109410D03*
X1601972Y116497D03*
X1609272D03*
X1606772D03*
X1596221Y109172D03*
X1599221D03*
X1598228Y106495D03*
X1611672Y111255D03*
Y114655D03*
X1598228Y102495D03*
X1611191Y106561D03*
X1611672Y128828D03*
Y125428D03*
X1604372Y132515D03*
Y121742D03*
Y135915D03*
X1601972Y123584D03*
Y130670D03*
X1606772Y123584D03*
X1609272Y123583D03*
Y130670D03*
X1606772D03*
X1604372Y118342D03*
X1611672Y125428D03*
X1604372Y121742D03*
X1611672Y128828D03*
X1604372Y132515D03*
X1606772Y137757D03*
X1597962Y146012D03*
X1599868Y141228D03*
X1601972Y137757D03*
X1604372Y135915D03*
X1597962Y142862D03*
X1602756Y150847D03*
X1604051Y195176D03*
X1605569Y199248D03*
X1601551Y195176D03*
X1606551D03*
X1609051D03*
X1610504Y213539D03*
X1603405Y206806D03*
X1605905D03*
X1601632Y210509D03*
X1604132D03*
X1608569Y202048D03*
X1605569Y201748D03*
X1604724Y247292D03*
X1597514Y236121D03*
X1612185Y238714D03*
X1603950Y238689D03*
X1608185Y238714D03*
X1602309Y242078D03*
X1607666Y246874D03*
X1597540Y232971D03*
X1609886Y244297D03*
X1597433Y253198D03*
X1597006Y290417D03*
X1596691Y287397D03*
X1596197Y293477D03*
X1608240Y329000D03*
X1603664Y342596D03*
X1607947Y332326D03*
X1605966Y343794D03*
X1598223Y351003D03*
X1602138Y351047D03*
X1599127Y375587D03*
X1596253Y375633D03*
X1596714Y383003D03*
X1599527Y392718D03*
X1596534Y379760D03*
X1599527Y408718D03*
Y400718D03*
Y396718D03*
X1596760Y530000D03*
X1596260Y540500D03*
X1611316Y685800D03*
X1611027Y722427D03*
X1611327Y735973D03*
X1611627Y780327D03*
X1609500Y776100D03*
X1611873Y795127D03*
X1611398Y1348187D03*
X1610620Y1345691D03*
Y1350683D03*
X1611398Y1348187D03*
Y1360099D03*
X1610620Y1357603D03*
Y1362595D03*
X1611398Y1360099D03*
Y1384297D03*
Y1372385D03*
X1610620Y1381801D03*
Y1374881D03*
Y1369889D03*
X1611398Y1384297D03*
Y1372385D03*
X1610620Y1386793D03*
X1597225Y1437014D03*
X1600333Y1440504D03*
X1596836Y1446488D03*
X1600333Y1449068D03*
X1603363Y1460570D03*
X1597457Y1452556D03*
X1601968Y1453442D03*
X1597457Y1460662D03*
X1598500Y1472500D03*
X1606745Y1474242D03*
X1605430Y1468023D03*
X1597039Y1475100D03*
X1599726Y1474990D03*
X1602580Y1483108D03*
X1598000Y1486000D03*
X1604000Y1516000D03*
X1608500Y1515000D03*
X1600700Y1534300D03*
X1622434Y82984D03*
Y80384D03*
Y75184D03*
Y77784D03*
X1624988Y92849D03*
X1622434Y85584D03*
X1621972Y95236D03*
Y102323D03*
X1622224Y109410D03*
Y116496D03*
X1613972D03*
Y102323D03*
Y109410D03*
X1622396Y124576D03*
X1623449Y130670D03*
X1613972D03*
Y123583D03*
X1623444Y137756D03*
X1613972D03*
X1626147Y351033D03*
X1628636Y422088D03*
X1625952Y431029D03*
X1626260Y427017D03*
X1625018Y435029D03*
X1625772Y438323D03*
X1625938Y449873D03*
X1621596Y456386D03*
X1625938Y445873D03*
X1627965Y474424D03*
X1625565Y472579D03*
X1627965Y474424D03*
Y477824D03*
Y488597D03*
Y491997D03*
X1625565Y479666D03*
Y486752D03*
X1627965Y488597D03*
Y477824D03*
X1625565Y493839D03*
X1627965Y491997D03*
Y521958D03*
Y518558D03*
X1625565Y523800D03*
Y516713D03*
X1627965Y521958D03*
Y518558D03*
Y536131D03*
Y532731D03*
X1625565Y537973D03*
Y530886D03*
X1627965Y536131D03*
Y532731D03*
X1616622Y546712D03*
Y542712D03*
X1627965Y571997D03*
Y568597D03*
X1625565Y566752D03*
X1627965Y571997D03*
Y568597D03*
Y582771D03*
Y586171D03*
X1625565Y588013D03*
Y573839D03*
Y580926D03*
X1627965Y582771D03*
Y586171D03*
Y596944D03*
Y600344D03*
X1625565Y602186D03*
Y595099D03*
X1627965Y596944D03*
Y600344D03*
Y614517D03*
Y611117D03*
X1625565Y609272D03*
Y616359D03*
X1627965Y614517D03*
Y611117D03*
X1614538Y618288D03*
X1620244Y638125D03*
X1627224Y643252D03*
X1613362Y656321D03*
X1621362D03*
X1617362D03*
X1613110Y678462D03*
X1616260D03*
X1619950Y678519D03*
X1615913Y692245D03*
X1624148Y708258D03*
X1628200Y711417D03*
X1612800Y705900D03*
X1620600D03*
X1620500Y723200D03*
X1628343Y747288D03*
X1616683Y744517D03*
X1620100Y738300D03*
X1627455Y759489D03*
X1624000Y760900D03*
X1612573Y761427D03*
X1619612Y783152D03*
X1620359Y774830D03*
X1619569Y796035D03*
X1620755Y787530D03*
X1613235Y808466D03*
X1620479Y815730D03*
X1620072Y801630D03*
X1628027Y801427D03*
X1616255Y824405D03*
X1613117Y828117D03*
X1619859Y839519D03*
X1627038Y1348187D03*
X1623638D03*
X1614798D03*
D03*
X1615576Y1345691D03*
Y1350683D03*
X1622860D03*
Y1345691D03*
X1627816Y1350683D03*
Y1345691D03*
X1623638Y1348187D03*
X1627038D03*
Y1360099D03*
X1623638D03*
X1614798D03*
X1615576Y1357603D03*
Y1362595D03*
X1622860Y1357603D03*
Y1362595D03*
X1627816Y1357603D03*
Y1362595D03*
X1614798Y1360099D03*
X1623638D03*
X1627038D03*
Y1372385D03*
X1614798D03*
Y1384297D03*
X1627038D03*
X1623638Y1372385D03*
Y1384297D03*
X1627038Y1372385D03*
X1622860Y1381801D03*
Y1369795D03*
Y1374881D03*
X1627816Y1381801D03*
Y1369795D03*
Y1374881D03*
X1615576Y1381801D03*
Y1374881D03*
Y1369889D03*
X1623638Y1372385D03*
X1627038Y1384297D03*
X1623638D03*
X1614798Y1372385D03*
Y1384297D03*
X1627038Y1396583D03*
X1623638D03*
X1615576Y1386793D03*
X1622860D03*
Y1393993D03*
Y1399079D03*
X1627816Y1386793D03*
Y1399079D03*
Y1393993D03*
X1627038Y1396583D03*
X1623638D03*
Y1408495D03*
X1627038D03*
X1622860Y1405999D03*
Y1410991D03*
X1627816Y1405999D03*
Y1410991D03*
X1627038Y1408495D03*
X1623638D03*
X1618800Y1528558D03*
X1614200Y1519500D03*
X1614360Y1542860D03*
X1618600Y1532000D03*
X1631622Y53597D03*
X1640769Y85539D03*
Y82939D03*
Y75139D03*
Y80339D03*
Y77739D03*
X1631905Y95236D03*
X1631948Y103037D03*
X1632082Y116496D03*
Y109410D03*
X1640082Y116496D03*
Y109410D03*
Y102323D03*
X1642840Y104249D03*
Y107649D03*
X1632082Y130670D03*
Y123583D03*
X1640082Y130670D03*
Y123583D03*
X1628673Y137756D03*
X1640082D03*
X1639862Y162368D03*
X1642462D03*
X1641173Y213213D03*
Y210713D03*
Y208213D03*
X1630717Y210478D03*
Y215478D03*
Y212978D03*
Y207978D03*
X1641173Y231461D03*
X1630717Y223726D03*
Y226226D03*
Y231226D03*
Y228726D03*
X1641173Y226461D03*
X1644880Y226141D03*
X1641173Y228961D03*
Y215713D03*
X1644825Y248891D03*
X1634046Y264180D03*
X1636546D03*
X1633971Y258880D03*
X1642940Y267526D03*
Y270026D03*
X1644777Y288190D03*
X1642277Y285690D03*
X1644777D03*
X1642277Y288190D03*
X1636763Y293796D03*
X1634263D03*
X1629553Y329067D03*
X1632230Y330400D03*
X1635987Y335616D03*
X1629302Y334402D03*
X1640030Y335550D03*
X1636561Y343072D03*
X1629514Y331727D03*
X1630703Y350655D03*
X1636468Y345595D03*
X1630691Y347432D03*
X1640197Y374690D03*
X1638340Y379536D03*
X1641615Y379600D03*
X1636271Y410394D03*
X1637205Y440098D03*
Y437598D03*
Y435098D03*
Y432598D03*
Y430098D03*
X1635170Y442856D03*
X1637665Y458406D03*
Y451319D03*
X1636271Y453881D03*
X1635265Y467337D03*
Y470737D03*
X1637489Y462264D03*
X1632865Y465492D03*
X1637665D03*
Y472579D03*
X1632865D03*
X1630365D03*
X1635265Y470737D03*
Y467337D03*
Y481510D03*
Y484910D03*
X1630365Y479666D03*
X1632865D03*
X1637665Y479665D03*
Y486752D03*
X1630365D03*
X1632865D03*
X1635265Y484910D03*
Y481510D03*
X1630365Y493839D03*
X1637665D03*
X1635265Y514871D03*
Y511471D03*
Y525644D03*
X1632865Y509626D03*
Y516713D03*
X1630365D03*
Y523800D03*
X1632865D03*
X1637665Y523799D03*
Y516713D03*
Y509626D03*
X1635265Y514871D03*
Y511471D03*
Y529044D03*
X1630365Y530886D03*
X1637665D03*
X1632865D03*
X1637665Y537973D03*
X1630365D03*
X1635265Y529044D03*
Y525644D03*
Y561510D03*
Y564910D03*
X1637665Y559665D03*
Y566752D03*
X1630365D03*
X1632865D03*
Y559665D03*
X1635265Y564910D03*
Y561510D03*
Y575684D03*
Y579084D03*
Y589857D03*
X1632865Y573839D03*
X1630365Y580926D03*
X1632865D03*
X1637665D03*
Y588012D03*
X1630365Y588013D03*
X1632865Y588012D03*
X1637665Y573839D03*
X1630365D03*
X1635265Y575684D03*
Y579084D03*
Y593257D03*
Y604030D03*
X1632865Y602185D03*
X1630365Y602186D03*
X1637665Y602185D03*
Y595099D03*
X1632865D03*
X1630365D03*
X1635265Y593257D03*
Y604030D03*
Y589857D03*
Y607430D03*
X1630365Y616359D03*
X1632865Y609272D03*
X1630365D03*
X1637665Y616358D03*
Y609272D03*
X1635265Y607430D03*
X1637526Y699930D03*
X1637472Y717830D03*
X1631031Y732430D03*
X1628813Y727045D03*
X1635283Y728117D03*
X1631187Y750630D03*
X1629969Y740826D03*
X1630327Y774627D03*
X1629927Y787327D03*
X1644304Y891353D03*
X1639278Y1348187D03*
X1635878D03*
X1639278D03*
X1640056Y1345691D03*
Y1350683D03*
X1635100Y1345691D03*
Y1350683D03*
X1635878Y1348187D03*
X1639278Y1360099D03*
X1635878D03*
X1640056Y1357603D03*
Y1362595D03*
X1635100D03*
Y1357603D03*
X1639278Y1360099D03*
X1635878D03*
Y1384297D03*
X1639278D03*
Y1372385D03*
X1635878D03*
X1640056Y1369889D03*
Y1374881D03*
Y1381801D03*
X1635100Y1369889D03*
Y1374881D03*
Y1381801D03*
X1635878Y1384297D03*
X1639278D03*
Y1372385D03*
X1635878D03*
X1639278Y1396583D03*
X1635878D03*
X1639278D03*
X1640056Y1399079D03*
Y1394087D03*
Y1386793D03*
X1635100Y1394087D03*
Y1399079D03*
Y1386793D03*
X1635878Y1396583D03*
X1639278Y1408495D03*
X1635878D03*
X1635100Y1405999D03*
Y1410991D03*
X1640056Y1405999D03*
Y1410991D03*
X1635878Y1408495D03*
X1639278D03*
X1650417Y5374D03*
X1649730Y24773D03*
Y44773D03*
X1649365Y94017D03*
X1657374D03*
X1653365D03*
X1645365D03*
X1649094Y101701D03*
Y98551D03*
X1651989Y111223D03*
Y114623D03*
X1662391Y118335D03*
X1659895Y117557D03*
X1654485Y110445D03*
Y115401D03*
X1649493Y110445D03*
Y115401D03*
X1656644Y103783D03*
X1651989Y114623D03*
Y111223D03*
X1652644Y103783D03*
X1659579Y106186D03*
X1662391Y132509D03*
Y121735D03*
X1651989Y128796D03*
Y125396D03*
X1662391Y135909D03*
X1659895Y122513D03*
Y131731D03*
X1654485Y124618D03*
Y129574D03*
X1649493Y124618D03*
Y129574D03*
X1651989Y125396D03*
Y128796D03*
X1659895Y136687D03*
X1647406Y147540D03*
X1651178Y141247D03*
X1647406Y151540D03*
X1649562Y162793D03*
Y165393D03*
Y167993D03*
Y170493D03*
X1654565Y181009D03*
X1648559Y181426D03*
X1651770Y181366D03*
X1659740Y168697D03*
X1651056Y191941D03*
X1657556Y184619D03*
X1660828Y191941D03*
X1651384Y184012D03*
X1648767Y184221D03*
X1659536Y206760D03*
X1647745Y211695D03*
X1645245Y208695D03*
X1656506Y213132D03*
X1652803Y211359D03*
Y213859D03*
X1645245Y211695D03*
X1649142Y229286D03*
X1652835Y222212D03*
Y224712D03*
X1656506Y215632D03*
X1645123Y236611D03*
X1650123D03*
X1647623D03*
X1649142Y231786D03*
X1647325Y248891D03*
X1649825D03*
X1660750Y256535D03*
X1652750D03*
X1656750Y256303D03*
X1648240Y267526D03*
X1645740D03*
Y270026D03*
X1648240D03*
X1647577Y285690D03*
Y288190D03*
X1655803Y290755D03*
X1651803D03*
X1658200Y315039D03*
X1654771Y352088D03*
X1645685Y390500D03*
X1655335Y381500D03*
X1645685D03*
X1648835Y390500D03*
X1655555Y430760D03*
X1655576Y433570D03*
X1655392Y437072D03*
X1655433Y439963D03*
X1646209Y442606D03*
X1655677Y443180D03*
X1655697Y454744D03*
X1655639Y452018D03*
X1650087Y444841D03*
X1649773Y449961D03*
X1645826Y446606D03*
X1653507Y470136D03*
X1645465Y466027D03*
X1655776Y465492D03*
X1655742Y460250D03*
X1655776Y472579D03*
X1645607Y475262D03*
X1647133Y463479D03*
X1647604Y467367D03*
X1645607Y489435D03*
X1655776Y486752D03*
Y479665D03*
X1645607Y482666D03*
X1645423Y495088D03*
X1655776Y493839D03*
X1646158Y514608D03*
X1646080Y522134D03*
X1645465Y509626D03*
X1655776D03*
Y516713D03*
X1646562Y535677D03*
X1646723Y529136D03*
X1652236Y537973D03*
X1654716Y525483D03*
X1654637Y532756D03*
X1645465Y559665D03*
X1645846Y565574D03*
X1655776Y559665D03*
Y566752D03*
X1645493Y574338D03*
X1655626Y579978D03*
X1655776Y573839D03*
X1645592Y616358D03*
X1655840Y608117D03*
X1654572Y771702D03*
X1656112Y768669D03*
X1657042Y773604D03*
X1648375Y886766D03*
X1645128Y929263D03*
X1650205Y925911D03*
X1647763Y919268D03*
X1648387Y945554D03*
X1645342Y962120D03*
X1647470Y952125D03*
X1657091Y990823D03*
X1649571Y983857D03*
X1651443Y981515D03*
X1652944Y993796D03*
X1653414Y990590D03*
X1651518Y1348187D03*
X1648118D03*
X1660358D03*
X1647340Y1350683D03*
Y1345691D03*
X1652296Y1350683D03*
Y1345691D03*
X1659580Y1350683D03*
Y1345691D03*
X1660358Y1348187D03*
X1651518D03*
X1648118D03*
X1660358Y1360099D03*
X1651518D03*
X1648118D03*
X1647340Y1357603D03*
Y1362595D03*
X1652296Y1357603D03*
Y1362595D03*
X1659580D03*
Y1357603D03*
X1660358Y1360099D03*
X1651518D03*
X1648118D03*
Y1372385D03*
X1651518D03*
X1648118Y1384297D03*
X1651518D03*
X1660358Y1372385D03*
Y1384297D03*
X1648118Y1372385D03*
X1647340Y1381801D03*
Y1374881D03*
Y1369889D03*
X1652296Y1381801D03*
Y1374881D03*
Y1369889D03*
X1659580Y1374881D03*
Y1369889D03*
Y1381801D03*
X1651518Y1372385D03*
X1648118Y1384297D03*
X1651518D03*
X1660358D03*
Y1372385D03*
Y1396583D03*
X1648118D03*
X1651518D03*
X1647340Y1386793D03*
Y1394087D03*
Y1399079D03*
X1652296Y1386793D03*
Y1399079D03*
Y1394087D03*
X1659580D03*
Y1399079D03*
Y1386793D03*
X1660358Y1396583D03*
X1651518D03*
X1648118D03*
X1660358Y1408495D03*
X1651518D03*
X1648118D03*
X1647340Y1405999D03*
Y1410991D03*
X1652296Y1405999D03*
Y1410991D03*
X1659580Y1405999D03*
Y1410991D03*
X1660358Y1408495D03*
X1648118D03*
X1651518D03*
X1657983Y1460782D03*
X1649322Y1456451D03*
Y1465913D03*
X1657983Y1465513D03*
X1649322Y1461182D03*
Y1476536D03*
X1657983Y1476136D03*
Y1470244D03*
X1649322Y1471805D03*
Y1481267D03*
X1657983Y1480867D03*
X1649322Y1487159D03*
Y1496621D03*
X1657983Y1496221D03*
X1649322Y1491890D03*
X1657983Y1491490D03*
Y1485598D03*
Y1500952D03*
X1649322Y1502514D03*
X1657983Y1511576D03*
X1649322Y1511976D03*
Y1507245D03*
X1657983Y1506845D03*
Y1516307D03*
X1649322Y1558813D03*
Y1563544D03*
X1657983Y1563144D03*
Y1572606D03*
X1649322Y1574167D03*
Y1568275D03*
X1657983Y1567875D03*
X1649322Y1578898D03*
X1657983Y1578498D03*
X1649322Y1583629D03*
X1657983Y1583229D03*
X1649322Y1594253D03*
X1657983Y1593853D03*
Y1587960D03*
X1649322Y1589522D03*
Y1609607D03*
X1657983Y1609207D03*
X1649322Y1598984D03*
X1657983Y1598584D03*
Y1603315D03*
X1649322Y1604876D03*
Y1614338D03*
X1657983Y1613938D03*
Y1618669D03*
X1652000Y1644980D03*
X1669319Y3001D03*
X1676870Y55513D03*
X1673095Y68581D03*
X1662442Y84140D03*
Y76140D03*
Y80140D03*
X1673108Y80581D03*
X1665190Y76587D03*
Y72615D03*
X1677213Y91951D03*
X1677238Y88801D03*
X1675817Y117261D03*
X1664887Y117557D03*
X1667811Y103621D03*
X1671002Y112083D03*
X1662391Y118335D03*
Y121735D03*
X1664887Y122513D03*
Y131731D03*
X1662391Y132509D03*
Y135909D03*
X1662986Y146461D03*
X1664887Y136687D03*
X1661888Y152367D03*
X1673945Y152562D03*
X1663588Y180572D03*
X1668271Y180527D03*
X1669352Y171523D03*
X1671994Y192421D03*
X1663588Y185165D03*
X1668226Y185121D03*
X1675623Y186629D03*
X1667318Y198828D03*
X1664840Y192300D03*
X1662837Y206767D03*
X1667837D03*
X1665337D03*
X1667967Y221708D03*
X1665467D03*
X1664082Y228221D03*
X1672317Y221642D03*
X1662967Y221708D03*
X1662382Y224421D03*
X1669633Y236189D03*
X1667133D03*
X1664633D03*
X1667074Y248765D03*
X1664574D03*
X1669574D03*
X1661780Y279208D03*
X1676231Y265897D03*
X1673731D03*
X1670071Y268195D03*
Y270695D03*
X1667271Y268195D03*
X1664771D03*
Y270695D03*
X1667271D03*
X1670374Y290845D03*
Y288345D03*
X1667874Y290845D03*
Y288345D03*
X1670374Y293645D03*
X1667874D03*
X1674226Y324139D03*
X1673203Y328867D03*
Y332017D03*
X1666860Y353661D03*
X1663650Y353283D03*
X1673723Y353881D03*
X1670323Y353534D03*
X1663780Y384410D03*
X1663760Y410394D03*
Y403307D03*
X1663713Y440869D03*
Y438269D03*
X1666513Y433069D03*
Y430469D03*
Y435669D03*
Y440869D03*
Y438269D03*
X1663713Y433069D03*
Y430469D03*
Y435669D03*
X1663576Y458406D03*
X1669767Y445908D03*
X1673717Y445787D03*
X1664567Y451677D03*
X1667067D03*
X1664567Y454177D03*
X1667067D03*
X1663576Y465492D03*
Y472579D03*
X1666271Y460218D03*
Y463618D03*
X1663576Y479665D03*
Y486752D03*
Y493839D03*
Y523799D03*
Y516713D03*
Y509626D03*
Y537973D03*
Y530886D03*
Y559665D03*
Y566752D03*
Y580925D03*
Y588012D03*
Y573839D03*
Y602185D03*
Y595099D03*
Y616358D03*
Y609272D03*
X1675998Y1348187D03*
X1672598D03*
X1663758D03*
D03*
X1664536Y1350683D03*
Y1345691D03*
X1671820D03*
Y1350683D03*
X1676776Y1345691D03*
Y1350683D03*
X1672598Y1348187D03*
X1675998D03*
Y1360099D03*
X1663758D03*
X1672598D03*
X1664536Y1357603D03*
Y1362595D03*
X1671820Y1357603D03*
Y1362595D03*
X1676776Y1357603D03*
Y1362595D03*
X1663758Y1360099D03*
X1675998D03*
X1672598D03*
X1663758Y1372385D03*
Y1384297D03*
X1675998Y1372385D03*
X1672598D03*
Y1384297D03*
X1675998D03*
Y1372385D03*
X1672598D03*
X1664536Y1374881D03*
Y1369889D03*
Y1381801D03*
X1671820Y1374881D03*
Y1381801D03*
Y1369889D03*
X1676776D03*
Y1374881D03*
Y1381801D03*
X1672598Y1384297D03*
X1675998D03*
X1663758D03*
Y1372385D03*
X1675998Y1396583D03*
X1663758D03*
X1672598D03*
X1663758D03*
X1664536Y1394087D03*
Y1399079D03*
Y1386793D03*
X1671820D03*
Y1394087D03*
Y1399079D03*
X1676776Y1386793D03*
Y1399079D03*
Y1394087D03*
X1675998Y1396583D03*
X1672598D03*
X1663758Y1408495D03*
X1675998D03*
X1672598D03*
X1664536Y1405999D03*
Y1410991D03*
X1671820Y1405999D03*
Y1410991D03*
X1676776Y1405999D03*
Y1410991D03*
X1663758Y1408495D03*
X1675998D03*
X1672598D03*
X1666645Y1465913D03*
Y1456451D03*
Y1461182D03*
X1675306Y1465513D03*
Y1460782D03*
X1666645Y1471805D03*
Y1476536D03*
Y1481267D03*
X1675306Y1476136D03*
Y1470244D03*
Y1480867D03*
X1666645Y1487159D03*
Y1491890D03*
Y1496621D03*
X1675306Y1491490D03*
Y1485598D03*
Y1496221D03*
Y1511576D03*
X1666645Y1511976D03*
Y1507245D03*
Y1502514D03*
X1675306Y1506845D03*
Y1500952D03*
Y1516307D03*
X1666645Y1558813D03*
Y1563544D03*
X1675306Y1563144D03*
Y1578498D03*
Y1572606D03*
X1666645Y1568275D03*
X1675306Y1567875D03*
X1666645Y1574167D03*
Y1578898D03*
Y1583629D03*
X1675306Y1583229D03*
X1666645Y1589522D03*
Y1594253D03*
X1675306Y1593853D03*
Y1587960D03*
X1666645Y1604876D03*
Y1598984D03*
X1675306Y1609207D03*
Y1598584D03*
Y1603315D03*
X1666645Y1609607D03*
Y1614338D03*
X1675306Y1613938D03*
Y1618669D03*
X1672000Y1644980D03*
X1689319Y3001D03*
X1685184Y60922D03*
X1680020Y55513D03*
X1682330Y60438D03*
X1688011Y94374D03*
X1683152Y86046D03*
X1680155Y94351D03*
X1683348Y113394D03*
X1685997Y110784D03*
X1687566Y102249D03*
X1691566D03*
X1683348Y116594D03*
X1686171Y130898D03*
X1693591Y133298D03*
X1683348Y119594D03*
X1687738Y134579D03*
X1682189Y161306D03*
X1679440Y157370D03*
X1683524Y172665D03*
Y180665D03*
Y168665D03*
Y176665D03*
X1691366Y195176D03*
X1688866D03*
X1693485Y198883D03*
X1683524Y192665D03*
X1683637Y186778D03*
X1683556Y200864D03*
Y212864D03*
X1691226Y203393D03*
X1688726D03*
X1683556Y204864D03*
Y221864D03*
Y216864D03*
X1688605Y218085D03*
X1691405D03*
X1679197Y219379D03*
X1685313Y252371D03*
Y248371D03*
X1686115Y311740D03*
X1681273Y316731D03*
X1691117Y321649D03*
X1677810Y324466D03*
X1687164Y336324D03*
X1678072Y342319D03*
X1686408Y332584D03*
X1691743Y353506D03*
X1688593Y353470D03*
X1680518Y377912D03*
Y385912D03*
Y393924D03*
Y389912D03*
Y381912D03*
Y409924D03*
Y405924D03*
Y401924D03*
Y397912D03*
X1677933Y418838D03*
X1692253Y470706D03*
Y467306D03*
X1689757Y466528D03*
Y471484D03*
X1692253Y467306D03*
Y470706D03*
Y481479D03*
Y484879D03*
X1689757Y480701D03*
Y485657D03*
X1692253Y484879D03*
Y481479D03*
Y511439D03*
Y514839D03*
Y525613D03*
Y511439D03*
X1689757Y515617D03*
Y510661D03*
X1692253Y514839D03*
Y529013D03*
D03*
Y525613D03*
X1689757Y524835D03*
Y529791D03*
X1689920Y539315D03*
X1689236Y550137D03*
X1692028D03*
X1692253Y561479D03*
Y564879D03*
Y561479D03*
X1689757Y565657D03*
Y560701D03*
X1692253Y564879D03*
Y575652D03*
Y579052D03*
Y589825D03*
Y575652D03*
X1689757Y589047D03*
Y574874D03*
Y579830D03*
X1692253Y579052D03*
Y603999D03*
Y593225D03*
D03*
Y603999D03*
X1689757Y603221D03*
Y594003D03*
X1692253Y589825D03*
Y607399D03*
D03*
X1689757Y608177D03*
X1693000Y626912D03*
X1692379Y622912D03*
X1684838Y1348187D03*
X1688238D03*
X1689016Y1345691D03*
Y1350683D03*
X1684060D03*
Y1345691D03*
X1688238Y1348187D03*
X1684838D03*
X1688238Y1360099D03*
X1684838D03*
X1689016Y1362595D03*
Y1357603D03*
X1684060D03*
Y1362595D03*
X1688238Y1360099D03*
X1684838D03*
Y1384297D03*
X1688238D03*
X1684838Y1372385D03*
X1688238D03*
X1689016Y1369889D03*
Y1381801D03*
Y1374881D03*
X1684060Y1369889D03*
Y1381801D03*
Y1374881D03*
X1684838Y1384297D03*
X1688238D03*
X1684838Y1372385D03*
X1688238D03*
Y1396583D03*
X1684838D03*
D03*
X1689016Y1394087D03*
Y1399079D03*
Y1386793D03*
X1684060Y1394087D03*
Y1399079D03*
Y1386793D03*
X1688238Y1396583D03*
X1684838Y1408495D03*
X1688238D03*
X1689016Y1405999D03*
Y1410991D03*
X1684060Y1405999D03*
Y1410991D03*
X1688238Y1408495D03*
X1684838D03*
X1683968Y1465913D03*
Y1456451D03*
Y1461182D03*
X1692629Y1465513D03*
Y1460782D03*
X1683968Y1471805D03*
Y1476536D03*
Y1481267D03*
X1692629Y1476136D03*
Y1470244D03*
Y1480867D03*
X1683968Y1487159D03*
Y1491890D03*
Y1496621D03*
X1692629Y1491490D03*
Y1485598D03*
Y1496221D03*
X1683968Y1502514D03*
Y1511976D03*
X1692629Y1506845D03*
Y1500952D03*
Y1511576D03*
X1683968Y1507245D03*
X1692629Y1516307D03*
X1683968Y1558813D03*
Y1563544D03*
X1692629Y1563144D03*
Y1572606D03*
X1683968Y1568275D03*
Y1574167D03*
Y1578898D03*
X1692629Y1567875D03*
Y1578498D03*
X1683968Y1583629D03*
Y1589522D03*
Y1594253D03*
X1692629Y1583229D03*
Y1593853D03*
Y1587960D03*
X1683968Y1598984D03*
X1692629Y1609207D03*
Y1598584D03*
Y1603315D03*
X1683968Y1609607D03*
Y1604876D03*
Y1614338D03*
X1692629Y1613938D03*
Y1618669D03*
X1692000Y1644980D03*
X1705303Y4470D03*
X1706664Y24774D03*
Y44774D03*
X1709184Y95111D03*
X1706734Y118342D03*
X1698583Y109172D03*
X1701583D03*
X1700590Y106495D03*
X1709134Y116497D03*
X1704334D03*
X1695317Y116594D03*
X1700590Y102495D03*
X1706734Y121742D03*
Y132515D03*
Y135915D03*
X1709134Y123584D03*
Y130670D03*
X1704334Y123584D03*
Y130670D03*
X1695317Y119594D03*
X1706734Y118342D03*
Y132515D03*
Y121742D03*
X1700324Y146012D03*
X1702230Y141228D03*
X1709134Y137757D03*
X1704334D03*
X1706734Y135915D03*
X1700324Y142862D03*
X1705118Y150847D03*
X1693866Y195176D03*
X1708913D03*
X1706413D03*
X1703913D03*
X1707931Y199248D03*
X1697414Y206838D03*
X1694914D03*
X1707931Y201748D03*
X1706494Y210509D03*
X1703994D03*
X1705767Y206806D03*
X1708267D03*
X1697984Y226320D03*
X1695205Y216385D03*
X1697918Y216970D03*
Y219470D03*
Y221970D03*
X1707086Y247292D03*
X1699876Y236121D03*
X1696910Y238589D03*
X1706312Y238689D03*
X1704671Y242078D03*
X1699902Y232971D03*
X1699795Y253198D03*
X1701495Y289735D03*
X1700223Y292141D03*
X1703609Y287320D03*
X1695142Y303839D03*
X1698292Y303962D03*
X1702655Y474418D03*
X1694749Y466528D03*
Y471484D03*
X1700159Y473640D03*
X1705151D03*
X1702655Y474418D03*
Y477818D03*
Y488591D03*
Y491991D03*
Y477818D03*
X1705151Y487813D03*
X1700159D03*
X1705151Y478596D03*
X1694749Y480701D03*
X1700159Y478596D03*
X1694749Y485657D03*
X1702655Y488591D03*
Y491991D03*
X1700159Y492769D03*
X1705151D03*
X1702655Y521952D03*
Y518552D03*
X1705151Y517774D03*
Y522730D03*
X1694749Y510661D03*
Y515617D03*
X1700159Y517774D03*
Y522730D03*
X1702655Y521952D03*
Y518552D03*
Y536125D03*
Y532725D03*
Y536125D03*
X1700159Y536903D03*
X1705151D03*
Y531947D03*
X1694749Y524835D03*
Y529791D03*
X1700159Y531947D03*
X1702655Y532725D03*
Y571991D03*
Y568591D03*
X1705151Y572769D03*
X1700159D03*
X1705151Y567813D03*
X1698839Y564843D03*
X1700159Y567813D03*
X1694749Y565657D03*
Y560701D03*
X1702655Y571991D03*
Y568591D03*
Y586165D03*
Y582765D03*
X1694749Y579830D03*
X1705151Y586943D03*
Y581987D03*
X1694749Y589047D03*
X1700159Y586943D03*
Y581987D03*
X1694749Y574874D03*
X1702655Y586165D03*
Y582765D03*
Y600338D03*
Y596938D03*
Y600338D03*
X1694749Y603221D03*
X1700159Y601116D03*
X1705151D03*
Y596160D03*
X1700159D03*
X1694749Y594003D03*
X1702655Y596938D03*
Y611111D03*
Y614511D03*
Y611111D03*
X1705151Y615289D03*
X1700159Y610333D03*
X1694749Y608177D03*
X1700159Y615289D03*
X1705151Y610333D03*
X1702655Y614511D03*
X1708889Y1189221D03*
X1703400Y1174400D03*
X1700478Y1348187D03*
X1709318D03*
X1697078D03*
X1696300Y1350683D03*
Y1345691D03*
X1701256Y1350683D03*
Y1345691D03*
X1708540D03*
Y1350683D03*
X1709318Y1348187D03*
X1700478D03*
X1697078D03*
X1709318Y1360099D03*
X1700478D03*
X1697078D03*
X1696300Y1357603D03*
Y1362595D03*
X1701256Y1357603D03*
Y1362595D03*
X1708540D03*
Y1357603D03*
X1709318Y1360099D03*
X1697078D03*
X1700478D03*
X1709318Y1372385D03*
Y1384297D03*
X1697078Y1372385D03*
X1700478Y1384297D03*
Y1372385D03*
X1697078Y1384297D03*
Y1372385D03*
X1696300Y1374881D03*
Y1369889D03*
Y1381801D03*
X1701256Y1369889D03*
Y1381801D03*
Y1374881D03*
X1708540D03*
Y1369889D03*
Y1381801D03*
X1700478Y1372385D03*
X1697078Y1384297D03*
X1700478D03*
X1709318D03*
Y1372385D03*
Y1396583D03*
X1700478D03*
X1697078D03*
X1696300Y1386793D03*
Y1394087D03*
Y1399079D03*
X1701256Y1386793D03*
Y1394087D03*
Y1399079D03*
X1708540D03*
Y1394087D03*
Y1386793D03*
X1709318Y1396583D03*
X1700478D03*
X1697078D03*
X1700478Y1408495D03*
X1709318D03*
X1697078D03*
X1696300Y1405999D03*
Y1410991D03*
X1701256Y1405999D03*
Y1410991D03*
X1708540Y1405999D03*
Y1410991D03*
X1709318Y1408495D03*
X1697078D03*
X1700478D03*
X1701290Y1465913D03*
Y1456451D03*
Y1461182D03*
Y1471805D03*
Y1476536D03*
Y1481267D03*
Y1487159D03*
Y1491890D03*
Y1496621D03*
Y1507245D03*
Y1502514D03*
Y1511976D03*
Y1558813D03*
Y1563544D03*
Y1568275D03*
Y1574167D03*
Y1578898D03*
Y1583629D03*
Y1589522D03*
Y1594253D03*
Y1609607D03*
Y1604876D03*
Y1598984D03*
Y1614338D03*
X1713985Y53598D03*
X1724796Y82984D03*
Y77784D03*
Y80384D03*
Y75184D03*
Y85584D03*
X1724334Y95236D03*
X1714034Y114655D03*
Y111255D03*
X1716334Y116496D03*
Y109410D03*
Y102323D03*
X1711634Y116497D03*
Y109410D03*
X1724334Y102323D03*
X1724586Y109410D03*
Y116496D03*
X1714034Y111255D03*
Y114655D03*
X1713553Y106561D03*
X1714034Y128828D03*
Y125428D03*
X1724758Y124576D03*
X1725811Y130670D03*
X1716334D03*
Y123583D03*
X1711634D03*
Y130670D03*
X1714034Y125428D03*
Y128828D03*
X1725806Y137756D03*
X1716334D03*
X1711413Y195176D03*
X1712866Y213539D03*
X1710931Y202048D03*
X1714547Y238714D03*
X1710547D03*
X1710028Y246874D03*
X1712248Y244297D03*
X1715705Y328692D03*
X1716755Y326179D03*
X1712734Y340534D03*
X1712226Y344028D03*
X1715930Y340969D03*
X1715590Y331719D03*
X1725746Y377173D03*
X1723964Y370935D03*
X1721746Y377173D03*
X1715228Y387966D03*
X1718851Y391533D03*
X1725415Y416289D03*
Y418889D03*
Y421489D03*
X1721423Y412106D03*
X1718710Y447486D03*
X1716310Y458334D03*
Y454334D03*
X1724930Y473571D03*
Y491118D03*
Y488618D03*
Y476071D03*
Y478571D03*
Y481071D03*
Y493618D03*
Y496118D03*
X1710174Y553101D03*
X1717626Y1134729D03*
X1710511Y1138130D03*
X1721008Y1134729D03*
X1725008Y1134636D03*
X1720960Y1148000D03*
X1723796Y1160168D03*
X1725660Y1193019D03*
X1721660D03*
X1711783Y1193848D03*
X1721662Y1201043D03*
X1725658D03*
X1718625Y1199814D03*
X1712542Y1196600D03*
X1720536Y1217228D03*
X1723200Y1219895D03*
X1710825Y1231688D03*
X1721558Y1348187D03*
X1724958D03*
X1712718D03*
X1713496Y1350683D03*
Y1345691D03*
X1720780Y1350683D03*
Y1345597D03*
X1725736Y1350683D03*
Y1345597D03*
X1712718Y1348187D03*
X1721558D03*
X1724958D03*
Y1360099D03*
X1712718D03*
X1721558D03*
X1713496Y1357603D03*
Y1362595D03*
X1720780Y1357603D03*
Y1362595D03*
X1725736Y1357603D03*
Y1362595D03*
X1712718Y1360099D03*
X1724958D03*
X1721558D03*
X1724958Y1372385D03*
X1721558D03*
X1724958Y1384297D03*
X1712718D03*
Y1372385D03*
X1721558Y1384297D03*
Y1372385D03*
X1713496Y1374881D03*
Y1369889D03*
Y1381801D03*
X1720780Y1369889D03*
Y1381801D03*
Y1374881D03*
X1725736Y1381801D03*
Y1374881D03*
Y1369889D03*
X1724958Y1372385D03*
Y1384297D03*
X1721558D03*
X1712718Y1372385D03*
Y1384297D03*
X1724958Y1396583D03*
X1721558D03*
X1712718D03*
D03*
X1713496Y1399079D03*
Y1394087D03*
Y1386793D03*
X1720780D03*
Y1393993D03*
Y1399079D03*
X1725736Y1386793D03*
Y1399079D03*
Y1393993D03*
X1721558Y1396583D03*
X1724958D03*
X1721558Y1408495D03*
X1712718D03*
X1724958D03*
X1713496Y1405999D03*
Y1410991D03*
X1720780Y1405999D03*
Y1410991D03*
X1725736Y1405999D03*
Y1410991D03*
X1712718Y1408495D03*
X1721558D03*
X1724958D03*
X1709952Y1465513D03*
Y1460782D03*
X1718613Y1465914D03*
Y1456452D03*
Y1461183D03*
Y1476537D03*
Y1471806D03*
Y1481268D03*
X1709952Y1476136D03*
Y1470244D03*
Y1480867D03*
Y1491490D03*
Y1485598D03*
Y1496221D03*
X1718613Y1491891D03*
Y1487160D03*
Y1496622D03*
Y1502515D03*
Y1511977D03*
X1709952Y1506845D03*
Y1500952D03*
Y1511576D03*
X1718613Y1507246D03*
X1709952Y1516307D03*
Y1563144D03*
X1718613Y1563544D03*
Y1558813D03*
X1709952Y1567875D03*
X1718613Y1568275D03*
X1709952Y1578498D03*
Y1572606D03*
X1718613Y1578898D03*
Y1574167D03*
Y1589522D03*
X1709952Y1583229D03*
X1718613Y1583629D03*
X1709952Y1593853D03*
Y1587960D03*
X1718613Y1594253D03*
Y1609607D03*
Y1598984D03*
Y1604876D03*
X1709952Y1609207D03*
Y1598584D03*
Y1603315D03*
Y1618669D03*
X1718613Y1614338D03*
X1709952Y1613938D03*
X1712000Y1644980D03*
X1736405Y-82678D03*
Y-79278D03*
X1742336Y-87777D03*
X1739311Y-86371D03*
X1733909Y-83456D03*
Y-78500D03*
X1736405Y-79278D03*
Y-82678D03*
Y-69278D03*
Y-72678D03*
X1742336Y-74565D03*
Y-64265D03*
X1739311Y-65585D03*
Y-75885D03*
X1733909Y-68500D03*
Y-73456D03*
X1736405Y-69278D03*
Y-72678D03*
X1733985Y53598D03*
X1727350Y92849D03*
X1734267Y95236D03*
X1734310Y103037D03*
X1734444Y116496D03*
Y109410D03*
Y130670D03*
Y123583D03*
X1730647Y137756D03*
X1742224Y162368D03*
X1733079Y207978D03*
Y210478D03*
Y215478D03*
Y212978D03*
Y223726D03*
Y226226D03*
Y231226D03*
Y228726D03*
X1736408Y264180D03*
X1738908D03*
X1736333Y258880D03*
X1739125Y293796D03*
X1736625D03*
X1734826Y376499D03*
X1741746Y377173D03*
X1737786D03*
X1729751D03*
X1733027Y392228D03*
X1728433Y392183D03*
X1733746Y385123D03*
X1735811Y409032D03*
X1732494Y402867D03*
X1728478Y396866D03*
X1733071D03*
X1739847Y401066D03*
X1729508Y403300D03*
X1728915Y405889D03*
Y408489D03*
Y413689D03*
Y411089D03*
Y416289D03*
Y421489D03*
Y418889D03*
Y424089D03*
X1729302Y439718D03*
Y442518D03*
Y432718D03*
Y435518D03*
X1739179Y439318D03*
X1728915Y426689D03*
X1739179Y442118D03*
Y449118D03*
Y446318D03*
X1738824Y452740D03*
X1736214Y450091D03*
X1733014D03*
X1730014D03*
X1727404Y447209D03*
X1730404D03*
X1737703Y472189D03*
X1740542Y468088D03*
Y465288D03*
X1733014Y462060D03*
X1730014D03*
X1736592Y487570D03*
Y490070D03*
X1734952Y479217D03*
X1737646Y477213D03*
Y479713D03*
X1729002Y477053D03*
X1731502D03*
X1734952Y476717D03*
X1728038Y491870D03*
X1730538D03*
X1733147Y493758D03*
Y496258D03*
X1741800Y917900D03*
X1742029Y1116251D03*
X1730675Y1132361D03*
X1726963Y1132319D03*
X1739508Y1137129D03*
X1729008Y1134729D03*
X1732881D03*
X1739917Y1150087D03*
X1729207Y1159455D03*
X1737393Y1162817D03*
Y1170767D03*
X1728333Y1178240D03*
X1733660Y1193019D03*
X1729660D03*
X1737660D03*
X1733662Y1201039D03*
X1729628Y1201043D03*
X1737662Y1200969D03*
X1733695Y1212164D03*
X1735989Y1214458D03*
X1740785Y1219254D03*
X1737781Y1208993D03*
X1726475Y1223170D03*
X1731533Y1228226D03*
X1729322Y1226016D03*
X1737198Y1348187D03*
X1733798D03*
D03*
X1737198D03*
X1737976Y1350683D03*
Y1345691D03*
X1733020D03*
Y1350683D03*
X1737198Y1360099D03*
X1733798D03*
X1737976Y1362595D03*
Y1357603D03*
X1733020Y1362595D03*
Y1357603D03*
X1733798Y1360099D03*
X1737198D03*
X1733798Y1384297D03*
X1737198D03*
X1733798Y1372385D03*
X1737198D03*
X1737976Y1369889D03*
Y1374881D03*
X1733020Y1369889D03*
Y1381801D03*
Y1374881D03*
X1737976Y1381801D03*
X1737198Y1384297D03*
X1733798D03*
Y1372385D03*
X1737198D03*
Y1396583D03*
X1733798D03*
X1737198D03*
X1737976Y1399079D03*
Y1394087D03*
Y1386793D03*
X1733020Y1399079D03*
Y1394087D03*
Y1386793D03*
X1733798Y1396583D03*
Y1408495D03*
X1737198D03*
X1737976Y1405999D03*
Y1410991D03*
X1733020Y1405999D03*
Y1410991D03*
X1737198Y1408495D03*
X1733798D03*
X1732000Y1644980D03*
X1742351Y-77080D03*
X1745592Y-79984D03*
X1745604Y-77094D03*
X1745589Y-87777D03*
X1742351Y-85262D03*
X1745604D03*
X1745592Y-82584D03*
Y-71970D03*
X1745589Y-74579D03*
Y-64265D03*
X1745592Y-69470D03*
X1742351Y-66780D03*
X1745604D03*
X1752778Y5374D03*
X1752091Y24773D03*
Y44773D03*
X1743131Y85539D03*
Y82939D03*
Y75139D03*
Y80339D03*
Y77739D03*
X1755727Y94017D03*
X1751456Y101701D03*
X1747727Y94017D03*
X1751727D03*
X1751456Y98551D03*
X1754351Y114623D03*
Y111223D03*
D03*
X1742444Y102323D03*
Y116496D03*
Y109410D03*
X1751855Y110445D03*
Y115401D03*
X1756847D03*
Y110445D03*
X1754351Y114623D03*
X1755006Y103783D03*
X1745202Y104249D03*
Y107649D03*
X1754351Y125396D03*
Y128796D03*
D03*
Y125396D03*
X1742444Y130670D03*
Y123583D03*
X1751855Y129574D03*
Y124618D03*
X1756847D03*
Y129574D03*
X1742444Y137756D03*
X1744824Y162368D03*
X1751924Y162793D03*
Y165393D03*
Y167993D03*
Y170493D03*
X1756927Y181009D03*
X1750921Y181426D03*
X1754132Y181366D03*
X1753418Y191941D03*
X1751129Y184221D03*
X1753746Y184012D03*
X1747607Y211695D03*
X1755165Y211359D03*
Y213859D03*
X1750107Y211695D03*
X1747607Y208695D03*
X1743535Y208213D03*
Y213213D03*
Y210713D03*
Y226461D03*
X1747242Y226141D03*
X1755197Y224712D03*
X1743535Y228961D03*
Y231461D03*
X1751504Y229286D03*
X1755197Y222212D03*
X1743535Y215713D03*
X1752485Y236611D03*
X1749985D03*
X1751504Y231786D03*
X1747485Y236611D03*
X1747187Y248891D03*
X1749687D03*
X1752187D03*
X1755112Y256535D03*
X1750602Y267526D03*
X1745302D03*
X1748102D03*
X1745302Y270026D03*
X1748102D03*
X1750602D03*
X1749939Y288190D03*
X1747139D03*
X1744639D03*
X1749939Y285690D03*
X1744639D03*
X1747139D03*
X1758165Y290755D03*
X1754165D03*
X1744524Y370010D03*
X1756497Y370976D03*
X1748497Y371060D03*
X1747561Y385161D03*
X1744180Y383966D03*
X1748252Y395248D03*
X1750187Y409539D03*
X1753187D03*
Y407039D03*
X1752851Y401981D03*
X1755351D03*
X1757124Y398278D03*
X1754624D03*
X1749470Y424067D03*
X1751970D03*
X1756970D03*
X1754470D03*
X1749705Y413611D03*
X1752205D03*
X1757205D03*
X1754705D03*
X1756844Y438293D03*
X1747179Y439318D03*
X1756844Y441093D03*
X1747179Y442118D03*
X1756844Y450041D03*
Y452841D03*
Y455641D03*
X1747179Y449118D03*
Y446318D03*
X1747359Y454309D03*
Y458309D03*
X1756844Y443893D03*
X1747359Y462309D03*
X1747306Y470001D03*
X1744806D03*
X1745231Y489036D03*
X1743092Y485580D03*
X1745592D03*
X1748092D03*
X1758401Y484882D03*
X1747467Y492836D03*
Y495636D03*
X1753474Y542699D03*
X1756089Y542952D03*
X1750879Y541940D03*
X1757402Y825111D03*
Y820155D03*
X1754906Y824333D03*
Y820737D03*
X1746897Y879199D03*
X1746884Y884649D03*
X1744937Y912517D03*
X1747937D03*
X1750751Y910785D03*
X1747900Y900160D03*
X1744900D03*
X1750915Y902055D03*
X1749267Y918413D03*
X1751200Y931100D03*
X1746600Y935100D03*
X1748081Y984379D03*
X1751854Y991297D03*
X1749314Y987904D03*
X1748677Y993986D03*
X1756192Y996132D03*
X1753860Y997271D03*
X1743224Y1119055D03*
X1744529Y1116251D03*
X1758390Y1577905D03*
X1758583Y1581027D03*
X1750685Y1621654D03*
X1756422Y1640303D03*
X1752000Y1644980D03*
X1765559Y3001D03*
X1764804Y84140D03*
Y76140D03*
Y80140D03*
X1767552Y76587D03*
Y72615D03*
X1759736Y94017D03*
X1764753Y118335D03*
X1767249Y117557D03*
X1770173Y103621D03*
X1759006Y103783D03*
X1762257Y117557D03*
X1761941Y106186D03*
X1773364Y112083D03*
X1764753Y132509D03*
Y121735D03*
Y135909D03*
Y121735D03*
X1762257Y122513D03*
Y131731D03*
X1767249Y122513D03*
Y131731D03*
X1764753Y118335D03*
Y132509D03*
Y135909D03*
X1762257Y136687D03*
X1767249D03*
X1765950Y180572D03*
X1770633Y180527D03*
X1771714Y171523D03*
X1762102Y168697D03*
X1774356Y192421D03*
X1759918Y184619D03*
X1770588Y185121D03*
X1765950Y185165D03*
X1763190Y191941D03*
X1767202Y192300D03*
X1761898Y206760D03*
X1765199Y206767D03*
X1770199D03*
X1767699D03*
X1758868Y213132D03*
X1765329Y221708D03*
X1770329D03*
X1767829D03*
X1764744Y224421D03*
X1766444Y231021D03*
Y228221D03*
X1774679Y221642D03*
X1758868Y215632D03*
X1771995Y236189D03*
X1769495D03*
X1766995D03*
X1763112Y256535D03*
X1771936Y248765D03*
X1769436D03*
X1766936D03*
X1759112Y256303D03*
X1764142Y279208D03*
X1767133Y270695D03*
X1769633D03*
X1772433Y268195D03*
Y270695D03*
X1769633Y268195D03*
X1767133D03*
X1772736Y293645D03*
X1770236D03*
Y290845D03*
Y288345D03*
X1772736Y290845D03*
Y288345D03*
X1760497Y371070D03*
X1765497Y370899D03*
X1762997Y377581D03*
X1772513Y387702D03*
X1769713D03*
X1765913Y389402D03*
X1763200Y388817D03*
Y383817D03*
Y386317D03*
X1766204Y398949D03*
X1770778Y402642D03*
X1773278D03*
X1767633Y409904D03*
X1763704Y401949D03*
X1767953Y413611D03*
X1770453D03*
X1772953D03*
X1772893Y423944D03*
X1770393D03*
X1767893D03*
X1766837Y438293D03*
Y441093D03*
Y450041D03*
Y452841D03*
Y455641D03*
Y443893D03*
X1765097Y466409D03*
X1768586Y467560D03*
X1764903Y470382D03*
X1765083Y487382D03*
X1764912Y482382D03*
X1768575Y479560D03*
X1765006Y478382D03*
X1768575Y475560D03*
X1770135Y490711D03*
X1758957Y543036D03*
X1761953Y706827D03*
X1772768Y818696D03*
X1761953Y865160D03*
X1773600Y888100D03*
X1773614Y895275D03*
X1773600Y902800D03*
X1770680Y926322D03*
X1763818Y926241D03*
X1773789Y927663D03*
X1765664Y923724D03*
X1769064D03*
X1773789Y930663D03*
X1772599Y993053D03*
X1762898Y992883D03*
X1774476Y995049D03*
X1773810Y990821D03*
X1762486Y990260D03*
X1760201Y992475D03*
X1758881Y995633D03*
X1769004Y1019395D03*
X1768844Y1027248D03*
X1771773Y1028829D03*
X1764744Y1101930D03*
Y1097879D03*
X1766899Y1121122D03*
X1769499D03*
X1772099D03*
X1774799D03*
X1766999Y1130822D03*
X1772199D03*
X1769599D03*
X1774339Y1437975D03*
X1774216Y1470165D03*
X1765294Y1575434D03*
X1759092Y1588137D03*
X1767142Y1588219D03*
X1760422Y1640303D03*
X1768422D03*
X1772422D03*
X1772000Y1644980D03*
X1788884Y59871D03*
X1782382Y55513D03*
X1779232D03*
X1775457Y68581D03*
X1785246Y60660D03*
X1775470Y80581D03*
X1790664Y71908D03*
X1779575Y91951D03*
X1779600Y88801D03*
X1790373Y94663D03*
X1786466Y85923D03*
X1782517Y94351D03*
X1778179Y117261D03*
X1777653Y103621D03*
X1785886Y172665D03*
Y180665D03*
Y168665D03*
Y176665D03*
X1777985Y186629D03*
X1785779Y192665D03*
X1785886Y196665D03*
X1785999Y186778D03*
X1785918Y200864D03*
Y212864D03*
Y204864D03*
Y216864D03*
Y221864D03*
X1778593Y265897D03*
X1776093D03*
X1790533Y303750D03*
X1787674Y303130D03*
X1777681Y387151D03*
Y382151D03*
Y384651D03*
X1790136Y399161D03*
Y401661D03*
Y396661D03*
X1778103Y399161D03*
Y401661D03*
Y396661D03*
X1783028Y408240D03*
X1785528D03*
X1780528D03*
X1783107Y424240D03*
X1780646Y420393D03*
X1785646D03*
X1783146D03*
X1783107Y426740D03*
X1786184Y435321D03*
Y438121D03*
X1783384Y435321D03*
Y438121D03*
X1786184Y440921D03*
X1783384D03*
X1786713Y455039D03*
X1786184Y443721D03*
X1783384D03*
X1790014Y468607D03*
X1783014Y474513D03*
X1786693Y459170D03*
X1784602Y564092D03*
X1791041Y818795D03*
X1778801Y836469D03*
X1782600Y874500D03*
X1780016Y874400D03*
X1788400Y888100D03*
X1781000Y888087D03*
X1788396Y895066D03*
X1788300Y902800D03*
X1780665Y902796D03*
X1786256Y927626D03*
X1784306Y924601D03*
X1775904Y924546D03*
X1778047Y916120D03*
X1786256Y930626D03*
X1789537Y930498D03*
X1780158Y953295D03*
X1785758Y956095D03*
Y953295D03*
X1782958D03*
Y956095D03*
X1780158D03*
X1784763Y964660D03*
X1789363Y969160D03*
X1782563Y979660D03*
X1785663D03*
X1779363D03*
X1779143Y995203D03*
X1786740Y1019237D03*
X1780802Y1019474D03*
X1774863Y1019237D03*
X1774844Y1023694D03*
X1783844D03*
X1786844Y1027248D03*
X1780844D03*
X1774844D03*
X1789844Y1023694D03*
X1775998Y1074707D03*
Y1072207D03*
X1781198Y1074707D03*
X1778598D03*
X1783798D03*
Y1072207D03*
X1778598D03*
X1781198D03*
X1790736Y1072090D03*
Y1074590D03*
X1780326Y1089851D03*
X1777726D03*
X1782926D03*
Y1092351D03*
X1777726D03*
X1780326D03*
X1775126Y1089851D03*
Y1092351D03*
X1790639Y1082585D03*
X1790572Y1085152D03*
X1780662Y1108413D03*
X1783262D03*
X1778062D03*
X1775462D03*
X1785321Y1121122D03*
X1787921D03*
X1790521D03*
X1780566Y1111038D03*
X1783166D03*
X1777966D03*
X1775366D03*
X1774899Y1130822D03*
Y1139822D03*
X1777399D03*
X1790521Y1130822D03*
X1781874Y1139822D03*
X1787921Y1130822D03*
X1785321D03*
X1784374Y1139822D03*
X1777399Y1147822D03*
X1774899D03*
X1781802D03*
X1784302D03*
X1779581Y1222200D03*
Y1219400D03*
Y1216600D03*
Y1213800D03*
X1782581Y1222200D03*
Y1219400D03*
Y1216600D03*
Y1213800D03*
X1780397Y1237469D03*
Y1230569D03*
Y1228069D03*
X1779581Y1225000D03*
X1782581D03*
X1785961Y1224892D03*
X1780397Y1234969D03*
Y1241869D03*
Y1244369D03*
Y1248769D03*
Y1251269D03*
X1779868Y1446668D03*
X1778227Y1438099D03*
X1786091Y1443715D03*
X1783178Y1437550D03*
X1786564Y1478858D03*
X1778104Y1470289D03*
X1776422Y1640303D03*
X1801761Y-43888D03*
X1804667Y-47581D03*
X1799265Y-44666D03*
X1801761Y-40488D03*
Y-30488D03*
Y-33888D03*
X1804667Y-37095D03*
X1799265Y-39710D03*
Y-29710D03*
Y-34666D03*
X1801761Y-33888D03*
Y-43888D03*
Y-30488D03*
Y-40488D03*
X1804667Y-26795D03*
X1791570Y74535D03*
X1791088Y77296D03*
X1804758Y294429D03*
X1804993Y297591D03*
X1793524Y303343D03*
X1805196Y300952D03*
X1799897Y408104D03*
X1802697D03*
X1805497D03*
X1793475Y424939D03*
X1799614Y420375D03*
X1802414D03*
X1805214D03*
X1804984Y433975D03*
X1803570Y436164D03*
X1793475Y427439D03*
X1804933Y461607D03*
X1796933D03*
X1796136Y471334D03*
X1800933Y461607D03*
X1793149Y662810D03*
X1798705Y718793D03*
X1791302Y829031D03*
X1802000Y892447D03*
X1797365Y930761D03*
X1793474Y930374D03*
X1794163Y968760D03*
X1797963D03*
X1792263Y962960D03*
X1805463Y969260D03*
X1801963Y969160D03*
X1798163Y982360D03*
X1793563D03*
X1805863Y980760D03*
X1803351Y1027471D03*
X1805188Y1019078D03*
X1799646Y1018999D03*
X1793470Y1018762D03*
X1801844Y1023694D03*
X1795844D03*
X1798844Y1027248D03*
X1792844D03*
X1795936Y1072090D03*
X1793336D03*
X1798536D03*
Y1074590D03*
X1793336D03*
X1795936D03*
X1805013Y1091877D03*
X1792847Y1099210D03*
X1799012Y1095893D03*
X1805013Y1096470D03*
X1792863Y1103246D03*
X1800813D03*
X1806206Y1114589D03*
X1803506D03*
X1800906D03*
X1798306D03*
X1798702Y1124328D03*
X1801302D03*
X1803902D03*
X1806602D03*
X1793221Y1121122D03*
Y1130822D03*
X1804532Y1133356D03*
X1807232D03*
X1807035Y1136912D03*
Y1144912D03*
X1801285Y1213373D03*
X1801147Y1208555D03*
X1802844Y1227695D03*
X1799845Y1261044D03*
X1794845D03*
X1797345D03*
X1799845Y1263544D03*
X1797345D03*
X1794845D03*
X1793976Y1440762D03*
X1803885Y1435046D03*
X1806428Y1444543D03*
X1807270Y1468535D03*
X1793879Y1472952D03*
X1803762Y1467236D03*
X1792000Y1644980D03*
X1807692Y-49001D03*
X1810945Y-48987D03*
X1807707Y-46486D03*
X1810960Y-46472D03*
X1810948Y-33180D03*
X1807692Y-35775D03*
X1810945Y-35789D03*
X1810948Y-30680D03*
X1807707Y-38290D03*
X1810948Y-41194D03*
X1810960Y-38304D03*
X1810948Y-43794D03*
X1807692Y-25475D03*
X1810945D03*
X1807707Y-27990D03*
X1810960D03*
X1822983Y346053D03*
Y366053D03*
Y386053D03*
Y406053D03*
Y426053D03*
Y446053D03*
Y466053D03*
Y486053D03*
Y506053D03*
Y526053D03*
Y546053D03*
Y566053D03*
Y586053D03*
Y606053D03*
Y626053D03*
Y646053D03*
Y666053D03*
Y686053D03*
Y706053D03*
Y726053D03*
Y746053D03*
Y766053D03*
Y786053D03*
Y806053D03*
Y826053D03*
Y846053D03*
Y866053D03*
Y886053D03*
Y906053D03*
X1819900Y906900D03*
X1822983Y926053D03*
Y946053D03*
X1816322Y977215D03*
X1807663Y966660D03*
Y963860D03*
X1823074Y992833D03*
X1808014Y984832D03*
X1812538Y1026859D03*
X1811468Y1021084D03*
X1807844Y1023694D03*
Y1027248D03*
X1810349Y1031264D03*
X1812296Y1075688D03*
X1809696Y1091832D03*
X1809651Y1096426D03*
X1816756Y1097145D03*
X1823028Y1124289D03*
X1817728D03*
X1815128D03*
X1820328D03*
X1822928Y1114589D03*
X1820228D03*
X1815028D03*
X1817628D03*
X1816385Y1136912D03*
X1813885D03*
X1815865Y1133356D03*
X1809535Y1136912D03*
X1813885Y1144912D03*
X1816385D03*
X1809535D03*
X1822594Y1211054D03*
Y1215324D03*
X1809897Y1237285D03*
Y1230385D03*
Y1232885D03*
X1811482Y1226423D03*
X1809897Y1239785D03*
Y1244185D03*
Y1246685D03*
X1810018Y1295944D03*
X1812818D03*
X1815618Y1298744D03*
Y1295944D03*
X1812818Y1298744D03*
X1810018D03*
X1807393Y1436345D03*
X1809342Y1476733D03*
X1812000Y1644980D03*
X1825559Y3001D03*
X1836543Y4470D03*
X1837904Y24774D03*
Y44774D03*
Y64774D03*
Y84774D03*
Y104774D03*
Y124774D03*
Y144774D03*
Y164774D03*
Y184774D03*
Y204774D03*
Y224774D03*
Y244774D03*
Y264774D03*
Y284774D03*
Y304774D03*
X1837728Y324733D03*
X1830094Y333210D03*
X1830472Y960970D03*
X1837937Y973244D03*
X1831511Y978888D03*
X1837937Y993244D03*
X1831914Y992877D03*
X1837937Y1013244D03*
Y1033244D03*
Y1053244D03*
Y1073244D03*
X1824706Y1081145D03*
Y1089145D03*
Y1085145D03*
X1824949Y1077145D03*
X1824733Y1102830D03*
X1837937Y1093244D03*
X1825832Y1097589D03*
X1824706Y1100185D03*
Y1106145D03*
X1828272Y1095968D03*
X1824706Y1093150D03*
X1837937Y1113244D03*
X1830915Y1109146D03*
X1837937Y1133244D03*
Y1153244D03*
Y1173244D03*
Y1193244D03*
Y1213244D03*
X1834665Y1213239D03*
X1837937Y1253244D03*
Y1273244D03*
Y1293244D03*
Y1313244D03*
Y1333244D03*
Y1353244D03*
Y1373244D03*
Y1393244D03*
Y1433244D03*
Y1453244D03*
Y1473244D03*
Y1493244D03*
Y1513244D03*
Y1533244D03*
Y1553244D03*
Y1573244D03*
X1837933Y1636171D03*
X1832000Y1644980D03*
X2575564Y2383401D03*
X2589291Y2743713D03*
X2609880Y1999066D03*
X2644196Y1285303D03*
Y1635321D03*
X2785168Y832513D03*
X3463464Y2007236D03*
X3458385Y2377916D03*
X3481496Y2774598D03*
X3493931Y1646712D03*
G54D11*
X13780Y1226024D03*
X79331Y1186654D03*
X390354Y1141024D03*
X536418Y1086654D03*
X854291Y1225118D03*
X993504Y1170748D03*
X1304528Y1141024D03*
X1450591Y1086654D03*
X1761614Y1215000D03*
X1827165Y1235630D03*
X2785168Y501013D03*
G54D20*
X46348Y1727941D03*
Y1737941D03*
X46248Y1760941D03*
Y1750941D03*
X46348Y1773941D03*
Y1783941D03*
X46248Y1806941D03*
Y1796941D03*
X56348Y1727941D03*
Y1737941D03*
X56248Y1750941D03*
X56348Y1773941D03*
X56248Y1760941D03*
X56348Y1783941D03*
X56248Y1806941D03*
Y1796941D03*
X308448Y1737941D03*
Y1727941D03*
Y1750941D03*
Y1760941D03*
Y1773941D03*
Y1783941D03*
X308348Y1796941D03*
Y1806941D03*
X318448Y1727941D03*
Y1737941D03*
Y1750941D03*
Y1760941D03*
Y1773941D03*
Y1783941D03*
X318348Y1796941D03*
Y1806941D03*
X333286Y1728583D03*
X343286Y1738583D03*
Y1728583D03*
X333286Y1738583D03*
X343112Y1751624D03*
X333112D03*
X343212Y1774624D03*
X333212D03*
X333112Y1761624D03*
X343112D03*
X343212Y1784624D03*
X333212D03*
X343212Y1797624D03*
X333212D03*
Y1807624D03*
X343212D03*
X605386Y1728583D03*
X595386D03*
Y1738583D03*
X605386D03*
X605312Y1751624D03*
X595312D03*
Y1774624D03*
X605312D03*
X595312Y1761624D03*
X605312D03*
X595312Y1784624D03*
X605312D03*
X595312Y1807624D03*
X605312D03*
Y1797624D03*
X595312D03*
X620083Y1728286D03*
Y1738286D03*
X619861Y1751765D03*
X619711Y1775438D03*
X619861Y1761765D03*
X619711Y1785438D03*
X619475Y1798845D03*
Y1808845D03*
X630083Y1738286D03*
Y1728286D03*
X629861Y1751765D03*
X629711Y1775438D03*
X629861Y1761765D03*
X629711Y1785438D03*
X629475Y1798845D03*
Y1808845D03*
X882183Y1728286D03*
Y1738286D03*
X881911Y1751765D03*
X881761Y1775438D03*
X881911Y1761765D03*
X881761Y1785438D03*
X881525Y1798845D03*
Y1808845D03*
X892183Y1728286D03*
Y1738286D03*
X891911Y1751765D03*
X891761Y1775438D03*
X891911Y1761765D03*
X891761Y1785438D03*
X891525Y1808845D03*
Y1798845D03*
X907279Y1738990D03*
Y1728990D03*
X907163Y1752566D03*
Y1762566D03*
X907073Y1776014D03*
Y1786014D03*
X907166Y1800435D03*
Y1810435D03*
X917279Y1738990D03*
Y1728990D03*
X917163Y1752566D03*
Y1762566D03*
X917073Y1786014D03*
Y1776014D03*
X917166Y1800435D03*
Y1810435D03*
X1169329Y1728990D03*
Y1738990D03*
X1169263Y1752566D03*
Y1762566D03*
X1169123Y1776014D03*
Y1786014D03*
X1169216Y1800435D03*
Y1810435D03*
X1179329Y1728990D03*
Y1738990D03*
X1179263Y1752566D03*
Y1762566D03*
X1179123Y1776014D03*
Y1786014D03*
X1179216Y1800435D03*
Y1810435D03*
X2785168Y898813D03*
G54D12*
X19685Y-83298D03*
Y1801195D03*
X1821260Y-83298D03*
Y1801195D03*
G54D21*
X116731Y1052235D03*
X106619Y1056423D03*
X102431Y1066535D03*
X106619Y1076647D03*
X116731Y1080835D03*
Y1249086D03*
X106619Y1253274D03*
X102431Y1263386D03*
X106619Y1273498D03*
X116731Y1277686D03*
X126843Y1056423D03*
Y1076647D03*
X131031Y1066535D03*
X126843Y1253274D03*
X131031Y1263386D03*
X126843Y1273498D03*
X342840Y1056423D03*
X338652Y1066535D03*
X342840Y1076647D03*
Y1253274D03*
X338652Y1263386D03*
X342840Y1273498D03*
X352952Y1052235D03*
Y1080835D03*
Y1249086D03*
Y1277686D03*
X363064Y1056423D03*
Y1076647D03*
X367252Y1066535D03*
X363064Y1253274D03*
X367252Y1263386D03*
X363064Y1273498D03*
X563706Y1056423D03*
X559518Y1066535D03*
X563706Y1076647D03*
Y1253274D03*
X559518Y1263386D03*
X563706Y1273498D03*
X583930Y1056423D03*
X573818Y1052235D03*
X583930Y1076647D03*
X588118Y1066535D03*
X573818Y1080835D03*
X583930Y1253274D03*
X573818Y1249086D03*
X588118Y1263386D03*
X573818Y1277686D03*
X583930Y1273498D03*
X760433Y1480906D03*
X756274Y1490945D03*
X760433Y1500984D03*
X780511Y1480906D03*
X770472Y1476747D03*
Y1505143D03*
X780511Y1500984D03*
X799926Y1056423D03*
X795738Y1066535D03*
X799926Y1076647D03*
Y1253274D03*
X795738Y1263386D03*
X799926Y1273498D03*
X784670Y1490945D03*
X810040Y378544D03*
X805881Y388583D03*
X810040Y398622D03*
X810038Y1052235D03*
Y1080835D03*
Y1249086D03*
Y1277686D03*
X820079Y374385D03*
X830118Y378544D03*
X820079Y402781D03*
X830118Y398622D03*
X820150Y1056423D03*
Y1076647D03*
X824338Y1066535D03*
X820150Y1253274D03*
X824338Y1263386D03*
X820150Y1273498D03*
X834277Y388583D03*
X1010827Y378544D03*
X1006668Y388583D03*
X1010827Y398622D03*
X1020866Y374385D03*
Y402781D03*
X1020793Y1056423D03*
X1016605Y1066535D03*
X1020793Y1076647D03*
Y1253274D03*
X1016605Y1263386D03*
X1020793Y1273498D03*
X1030905Y378544D03*
X1035064Y388583D03*
X1030905Y398622D03*
X1041017Y1056423D03*
X1030905Y1052235D03*
X1041017Y1076647D03*
X1030905Y1080835D03*
X1041017Y1253274D03*
X1030905Y1249086D03*
Y1277686D03*
X1041017Y1273498D03*
X1045205Y1066535D03*
Y1263386D03*
X1060433Y1480906D03*
X1056274Y1490945D03*
X1060433Y1500984D03*
X1070472Y1476747D03*
Y1505143D03*
X1080511Y1480906D03*
X1084670Y1490945D03*
X1080511Y1500984D03*
X1252825Y1066535D03*
Y1263386D03*
X1267125Y1052235D03*
X1257013Y1056423D03*
Y1076647D03*
X1267125Y1080835D03*
Y1249086D03*
X1257013Y1253274D03*
Y1273498D03*
X1267125Y1277686D03*
X1277237Y1056423D03*
Y1076647D03*
X1281425Y1066535D03*
X1277237Y1253274D03*
X1281425Y1263386D03*
X1277237Y1273498D03*
X1477879Y1056423D03*
X1473691Y1066535D03*
X1477879Y1076647D03*
Y1253274D03*
X1473691Y1263386D03*
X1477879Y1273498D03*
X1498103Y1056423D03*
X1487991Y1052235D03*
X1498103Y1076647D03*
X1487991Y1080835D03*
X1498103Y1253274D03*
X1487991Y1249086D03*
Y1277686D03*
X1498103Y1273498D03*
X1502291Y1066535D03*
Y1263386D03*
X1709912Y1066535D03*
Y1263386D03*
X1724212Y1052235D03*
X1714100Y1056423D03*
Y1076647D03*
X1724212Y1080835D03*
Y1249086D03*
X1714100Y1253274D03*
Y1273498D03*
X1724212Y1277686D03*
X1734324Y1056423D03*
Y1076647D03*
X1738512Y1066535D03*
X1734324Y1253274D03*
X1738512Y1263386D03*
X1734324Y1273498D03*
X2785168Y733063D03*
G54D30*
X970071Y1365652D03*
Y1409152D03*
X2785168Y401563D03*
G54D31*
X1030635Y754546D03*
Y764546D03*
Y774546D03*
Y784546D03*
Y794546D03*
Y804546D03*
Y814546D03*
Y824546D03*
X2785168Y633613D03*
G54D13*
X11011Y79720D03*
X10292Y94236D03*
X12786Y87903D03*
X10131Y115473D03*
X19855Y133000D03*
X15948Y141267D03*
X16909Y153263D03*
X12247Y166341D03*
X17313Y166937D03*
X21909Y153263D03*
X22335Y166721D03*
X18320Y195176D03*
X15139Y201683D03*
X22599Y228646D03*
X18206Y244571D03*
X15586Y249108D03*
X18206Y264571D03*
X8335Y280663D03*
X14807Y282181D03*
X15586Y269108D03*
X15499Y288542D03*
X14197Y1014205D03*
X12599Y1438143D03*
X16304Y1468196D03*
X15889Y1494254D03*
X10089D03*
X19859Y1520657D03*
X18879Y1534334D03*
X26588Y97667D03*
X35442D03*
X35048Y103411D03*
X26565Y177448D03*
X32507Y180517D03*
X32585Y199248D03*
X27340Y230556D03*
X36185Y230117D03*
X31595Y227824D03*
X25549Y256394D03*
X29116Y281129D03*
X37117Y279991D03*
X25549Y276394D03*
X34359Y541135D03*
X34732Y534909D03*
X34425Y546553D03*
X34448Y552726D03*
X36494Y616905D03*
X36306Y622285D03*
X27686Y625311D03*
X36692Y633724D03*
X36575Y627713D03*
X28818Y682139D03*
X30479Y1006509D03*
X31631Y1198651D03*
X29880Y1441702D03*
X25674Y1486291D03*
X45988Y90512D03*
X48596Y451419D03*
X49643Y464419D03*
X41643Y464919D03*
X43948Y492108D03*
X44563Y482165D03*
X43804Y500202D03*
X45256Y495993D03*
X40362Y610548D03*
X54192Y633473D03*
X42172Y633716D03*
X49192Y628078D03*
X47179Y633736D03*
X42192Y641817D03*
X47949Y822718D03*
X53549Y843118D03*
X52077Y905295D03*
X42470Y1006738D03*
X47314Y1072228D03*
X41172Y1079064D03*
X55188Y1205179D03*
X51023Y1201416D03*
X48842Y1211109D03*
X53479Y1216256D03*
X39452Y1250932D03*
X64829Y92874D03*
X55871Y99961D03*
X65189Y223661D03*
X65737Y445603D03*
X57857Y446071D03*
X67670Y464818D03*
X58224Y465004D03*
X63154Y462371D03*
X61330Y544895D03*
X63859Y590801D03*
X63684Y597130D03*
X67684Y605637D03*
X66510Y628242D03*
X58181Y627908D03*
X69049Y847718D03*
X68598Y859415D03*
X63969Y869475D03*
X63930Y874694D03*
X71528Y913190D03*
X59962Y910251D03*
X55699Y1072761D03*
X61588Y1074481D03*
X62109Y1084656D03*
Y1079656D03*
Y1091656D03*
X60269Y1198820D03*
X63094Y1207604D03*
X55596Y1210466D03*
X65478Y1541980D03*
X64747Y1555890D03*
X69816Y1592527D03*
X60554Y1612002D03*
X66291Y1633801D03*
X82661Y143740D03*
X80041Y148277D03*
X80502Y177616D03*
X81083Y172190D03*
X74939Y188727D03*
X72061Y208695D03*
X71696Y226141D03*
X75438Y265701D03*
X85541Y266114D03*
X80525Y265896D03*
X83014Y281982D03*
X77073Y281716D03*
X83819Y290755D03*
X78133Y566597D03*
X78733Y578405D03*
X84159Y578986D03*
X83684Y596729D03*
X72515Y596089D03*
X77734Y596782D03*
X78129Y656900D03*
X82648Y670679D03*
X73914Y660107D03*
X84845Y659857D03*
X82562Y680037D03*
X78735Y683426D03*
X74700Y842890D03*
X80593Y946082D03*
X87632Y1007522D03*
X87000Y1597855D03*
X74909Y1593009D03*
X71910Y1625009D03*
X78291Y1625743D03*
X83689Y1624736D03*
X91224Y141247D03*
X95711Y143518D03*
X94811Y152373D03*
X103456Y157370D03*
X98826Y172665D03*
X98763Y178560D03*
X98653Y183834D03*
X98943Y200864D03*
X92898Y192490D03*
X98173Y190185D03*
X98966Y207037D03*
X99032Y212455D03*
X88098Y231021D03*
X103841Y228631D03*
X89900Y281307D03*
X95943Y377953D03*
X88875Y840940D03*
X90000Y871389D03*
X103770Y868206D03*
X103692Y900295D03*
X91387Y905295D03*
X103836Y988813D03*
X95836D03*
X94398Y1006648D03*
X91765Y1018307D03*
X88007Y1013678D03*
X88479Y1023731D03*
X100594Y1035088D03*
X103124Y1165091D03*
X119582Y102249D03*
X118307Y110784D03*
X113307D03*
X117886Y124663D03*
X112864Y124879D03*
X107798Y124283D03*
X119230Y138838D03*
X107540Y192665D03*
X117501Y201683D03*
X107572Y208864D03*
X117948Y249108D03*
X120250Y758841D03*
X109591Y796905D03*
X110887Y884000D03*
X111836Y988813D03*
X119836D03*
X110409Y1024094D03*
X108971Y1109564D03*
Y1147364D03*
X109415Y1202103D03*
X118533Y1207737D03*
X112048Y1214372D03*
X107803Y1218169D03*
X128950Y97667D03*
X122867Y125107D03*
X131481Y143762D03*
X125381Y148717D03*
X120682Y195176D03*
X134947Y199248D03*
X129702Y230556D03*
X133957Y227824D03*
X120568Y244571D03*
X127911Y256394D03*
X126131Y359511D03*
X125753Y365856D03*
X122437Y860775D03*
X123387Y892000D03*
X135836Y988813D03*
X127836D03*
X124079Y1021954D03*
X120617Y1029427D03*
X124925Y1102091D03*
X130380Y1105091D03*
X124925Y1114691D03*
Y1127291D03*
X130380Y1117691D03*
X124925Y1139891D03*
X130380Y1130291D03*
X130434Y1144964D03*
X130380Y1155491D03*
X124925Y1152491D03*
X130434Y1170164D03*
X124925Y1165091D03*
Y1177691D03*
X131000Y1180266D03*
X135757Y1221407D03*
X135448Y1229402D03*
Y1234921D03*
X126433Y1230407D03*
X137410Y103411D03*
X137804Y97667D03*
X148600Y90650D03*
X138547Y230117D03*
X148061Y378600D03*
X147925Y615600D03*
X149469Y634190D03*
X152658Y645389D03*
X136862Y857244D03*
X151836Y988813D03*
X143836D03*
X142026Y1012354D03*
X136571Y1009354D03*
Y1021954D03*
X142026Y1024954D03*
X144640Y1039439D03*
X150952Y1040115D03*
X167191Y92874D03*
X153912Y90615D03*
X167551Y223661D03*
X164496Y309405D03*
X159836Y988813D03*
X155836Y997860D03*
X153693Y1051037D03*
X165649Y1159350D03*
Y1151870D03*
X185023Y143740D03*
X182403Y148277D03*
X182864Y177616D03*
X183445Y172190D03*
X177301Y188727D03*
X174423Y208695D03*
X174058Y226141D03*
X177800Y265701D03*
X182887Y265896D03*
X179435Y281716D03*
X169389Y1155610D03*
X193007Y100625D03*
X186026Y97475D03*
X193586Y141247D03*
X198073Y143518D03*
X197173Y152373D03*
X201015Y183834D03*
X201125Y178560D03*
X201188Y172665D03*
X195260Y192490D03*
X200535Y190185D03*
X201305Y200864D03*
X201394Y212455D03*
X201328Y207037D03*
X187903Y266114D03*
X192262Y281307D03*
X185376Y281982D03*
X186181Y290755D03*
X185328Y545528D03*
X205848Y60513D03*
X214389Y86012D03*
X210482Y94279D03*
X215669Y110784D03*
X210160Y124283D03*
X215226Y124879D03*
X209902Y196665D03*
X209934Y208864D03*
X214983Y218085D03*
X206203Y228631D03*
X204675Y382109D03*
X204674Y551683D03*
X208500Y595500D03*
X203500Y606929D03*
X208000Y604567D03*
X203460Y618400D03*
X203741Y612592D03*
X209158Y610072D03*
X209094Y616317D03*
X221944Y102249D03*
X231312Y97667D03*
X220669Y110784D03*
X225229Y125107D03*
X220248Y124663D03*
X227743Y148717D03*
X221592Y138838D03*
X223044Y195176D03*
X219863Y201683D03*
X232064Y230556D03*
X227323Y228646D03*
X220310Y249108D03*
X222930Y244571D03*
X233417Y253198D03*
X233258Y359186D03*
X228267Y404718D03*
Y412718D03*
X223500Y568000D03*
X221693Y594982D03*
X220333Y617930D03*
X224780Y1478149D03*
X217985Y1483055D03*
X225765Y1471985D03*
X233313Y1476699D03*
X221899Y1488800D03*
X218021Y1494724D03*
X222843Y1498442D03*
X233180Y1486442D03*
X233166Y1491454D03*
X226135Y1502442D03*
X230758Y1505046D03*
X226971Y1514578D03*
X227552Y1530675D03*
X232622Y1531104D03*
X226971Y1522578D03*
X219981Y1530797D03*
X223322Y1518578D03*
X222119Y1539941D03*
X227882Y1540816D03*
X233753Y1539752D03*
X239772Y103411D03*
X240166Y97667D03*
X237309Y199248D03*
X240909Y230117D03*
X236319Y227824D03*
X234986Y336161D03*
X236264Y342494D03*
X245362Y546712D03*
X250102Y656321D03*
X235790Y754332D03*
X248556Y824003D03*
X246311Y819000D03*
X238400Y836900D03*
X234976Y1481676D03*
X243535Y1511473D03*
X245500Y1517033D03*
X237633Y1511909D03*
X244600Y1531700D03*
X240808Y1519942D03*
X235687Y1522578D03*
X237580Y1528604D03*
X245937Y1524237D03*
X239949Y1541327D03*
X244912Y1539389D03*
X250962Y90650D03*
X256274Y90615D03*
X260595Y99961D03*
X265011Y403307D03*
X252695Y442956D03*
X261965Y458455D03*
X262526Y451108D03*
X252688Y636364D03*
X256303Y812254D03*
X255289Y824340D03*
X252305Y831018D03*
X250876Y1532782D03*
X255909Y1542043D03*
X250790Y1539759D03*
X269553Y92874D03*
X279663Y188727D03*
X276785Y208695D03*
X276420Y226141D03*
X269913Y223661D03*
X280162Y265701D03*
X281797Y281716D03*
X277575Y395084D03*
X278784Y435158D03*
X278529Y440489D03*
X282230Y458572D03*
X275123Y847874D03*
X281594Y1211712D03*
X270374Y1215452D03*
X290113Y23188D03*
X289631Y28281D03*
X295369Y100625D03*
X288388Y97475D03*
X287385Y143740D03*
X284765Y148277D03*
X285807Y172190D03*
X285226Y177616D03*
X297622Y192490D03*
X290265Y266114D03*
X285249Y265896D03*
X294624Y281307D03*
X287738Y281982D03*
X288543Y290755D03*
X297719Y339559D03*
X291396Y350223D03*
X292358Y393858D03*
X298000Y391496D03*
X295699Y382047D03*
X296000Y403500D03*
X298000Y409000D03*
X294000Y398583D03*
X307916Y60529D03*
X312844Y94279D03*
X312522Y124283D03*
X300435Y143518D03*
X299535Y152373D03*
X303377Y183834D03*
X303550Y172665D03*
X303487Y178560D03*
X302897Y190185D03*
X303667Y200864D03*
X312296Y208864D03*
X303756Y212455D03*
X303690Y207037D03*
X308565Y228631D03*
X315079Y314890D03*
X312263Y324518D03*
X299000Y377912D03*
Y386500D03*
X299088Y397912D03*
X322847Y19806D03*
X321840Y14408D03*
X322113Y26187D03*
X316751Y86012D03*
X324306Y102249D03*
X318031Y110784D03*
X323031D03*
X327591Y125107D03*
X322610Y124663D03*
X317588Y124879D03*
X330105Y148717D03*
X323954Y138838D03*
X325406Y195176D03*
X322225Y201683D03*
X329685Y228646D03*
X322672Y249108D03*
X325292Y244571D03*
X318508Y324322D03*
X315944Y332584D03*
X316067Y347937D03*
X321416Y348015D03*
X318500Y356519D03*
X327456Y550065D03*
X333674Y97667D03*
X342134Y103411D03*
X342528Y97667D03*
X336205Y143762D03*
X339671Y199248D03*
X343271Y230117D03*
X338681Y227824D03*
X334426Y230556D03*
X340988Y244297D03*
X332635Y256394D03*
X347058Y399918D03*
X333985Y1017945D03*
X341077Y1018056D03*
X336755Y1143489D03*
X340500Y1147500D03*
X335190Y1173065D03*
X341266Y1171956D03*
X342009Y1176100D03*
X339776Y1187962D03*
X358636Y90615D03*
X353324Y90650D03*
X362957Y99961D03*
X359486Y385123D03*
X349311Y385644D03*
X354486Y385123D03*
X353894Y406060D03*
X353320Y454214D03*
X353663Y449045D03*
X353367Y459330D03*
X358754Y462060D03*
X358207Y836462D03*
X352545Y1142666D03*
X360877Y1157404D03*
X354420Y1157544D03*
X352931Y1167768D03*
X357950D03*
X357083Y1185205D03*
X361792Y1187310D03*
X348432Y1187215D03*
X348125Y1180175D03*
X360659Y1209789D03*
X362332Y1230265D03*
X371915Y92874D03*
X379147Y208695D03*
X372275Y223661D03*
X378782Y226141D03*
X373264Y379429D03*
X378875Y379088D03*
X366486Y385123D03*
X370160Y391569D03*
X368587Y409016D03*
X378927Y406739D03*
X367564Y456034D03*
Y461034D03*
X373703Y782555D03*
X365691Y815127D03*
X371507Y815303D03*
X370214Y943812D03*
X379928Y949774D03*
X379245Y956643D03*
X378875Y961862D03*
X378928Y967812D03*
X366429Y1185238D03*
X366222Y1180235D03*
X387948Y27288D03*
X390750Y97475D03*
X387588Y177616D03*
X388169Y172190D03*
X382025Y188727D03*
X387611Y265896D03*
X382524Y265701D03*
X392627Y266114D03*
X384159Y281716D03*
X390100Y281982D03*
X390905Y290755D03*
X384173Y379028D03*
X381237Y371076D03*
X394237Y379591D03*
X396373Y407104D03*
X393893Y413611D03*
X393833Y423944D03*
X393646Y474382D03*
X385634Y472020D03*
X385694Y477318D03*
X385293Y466409D03*
X385131Y487382D03*
X381875Y740341D03*
X380331Y782627D03*
X392584Y875845D03*
X384856Y947987D03*
X383710Y1007283D03*
X382465Y1012430D03*
X392234Y1369579D03*
Y1364501D03*
X391740Y1545629D03*
Y1540529D03*
X395296Y1561024D03*
X391740Y1550729D03*
Y1555829D03*
X410789Y22627D03*
X397731Y100625D03*
X405912Y172665D03*
X405739Y183834D03*
X405849Y178560D03*
X399984Y192490D03*
X405259Y190185D03*
X406029Y200864D03*
X406118Y212455D03*
X406052Y207037D03*
X410927Y228631D03*
X396986Y281307D03*
X410086Y336795D03*
X409655Y331589D03*
X410688Y344736D03*
X411007Y356743D03*
X405801Y475560D03*
X405301Y467560D03*
X404468Y864407D03*
X406770Y869767D03*
X405466Y881299D03*
X397431Y870654D03*
X401108Y878487D03*
X405179Y959051D03*
X397252Y962861D03*
X396671Y968287D03*
X401063Y1233428D03*
X405063Y1225428D03*
X409063Y1233428D03*
X404324Y1271889D03*
X399373Y1555855D03*
X405496Y1561024D03*
X400396D03*
X410596D03*
X422450Y30483D03*
X414145Y27486D03*
X413904Y32569D03*
X414739Y186778D03*
X414658Y208864D03*
X422988Y323627D03*
X426830Y359026D03*
X416574Y357528D03*
X421413Y359053D03*
X426647Y452987D03*
X421267Y452799D03*
X414910Y448931D03*
X418801Y474513D03*
X424731Y508152D03*
X427693Y498943D03*
X424993Y728291D03*
X422430Y834800D03*
X425062Y883981D03*
X415015Y1088205D03*
X419987Y1098518D03*
X423340Y1104335D03*
X418495Y1106867D03*
X417063Y1225428D03*
X425063Y1237428D03*
X423200Y1397500D03*
X421454Y1544625D03*
X422539Y1534361D03*
X426701Y1541947D03*
X437386Y143740D03*
X434766Y148277D03*
X436666Y322583D03*
X443424Y332988D03*
X440538Y355372D03*
X438098Y442114D03*
X437835Y435101D03*
X432270Y431112D03*
X432440Y440101D03*
X432075Y452718D03*
X438086Y452601D03*
X438078Y447121D03*
X438396Y511493D03*
X443144Y628667D03*
X441162Y638313D03*
X443091Y1026266D03*
X430878Y1081816D03*
X429063Y1225428D03*
X450436Y143518D03*
X449536Y152373D03*
X446566Y337917D03*
X450852Y372054D03*
X459414Y468689D03*
X459757Y463520D03*
X459461Y473805D03*
X459929Y491669D03*
X460537Y501905D03*
X459952Y496842D03*
X459645Y509486D03*
X447279Y637031D03*
X447921Y630789D03*
X453552Y631779D03*
X460498Y870334D03*
X459360Y1012325D03*
X459885Y1018860D03*
X451140Y1021793D03*
X450875Y1028416D03*
X452091Y1039880D03*
X459700Y1032266D03*
X452115Y1098518D03*
X455468Y1104335D03*
X450623Y1106867D03*
X474307Y102249D03*
X474058Y116594D03*
X473032Y110784D03*
X468032D03*
X477592Y125107D03*
X462523Y124283D03*
X467589Y124879D03*
X472611Y124663D03*
X473955Y138838D03*
X475407Y195176D03*
X472226Y201683D03*
X475293Y244571D03*
X472673Y249108D03*
X467335Y359944D03*
X469530Y366754D03*
X473658Y470509D03*
Y475509D03*
X468558Y491669D03*
X468850Y545586D03*
X474540Y927341D03*
X475018Y992568D03*
X467345Y996480D03*
X464385Y1038534D03*
X471755Y1038665D03*
X470610Y1033783D03*
X475588Y1043055D03*
X470978Y1046591D03*
X463290Y1297035D03*
X492135Y103411D03*
X492529Y97667D03*
X483675D03*
X486206Y143762D03*
X480106Y148717D03*
X489672Y199248D03*
X493272Y230117D03*
X484427Y230556D03*
X488682Y227824D03*
X479686Y228646D03*
X490989Y244297D03*
X482636Y256394D03*
X492817Y357111D03*
X491843Y351089D03*
X490885Y373589D03*
X491053Y365423D03*
X491289Y391589D03*
X490885Y382570D03*
X488438Y418417D03*
X481485Y439900D03*
Y431917D03*
X489485Y431417D03*
X492736Y478982D03*
Y491982D03*
X491818Y534909D03*
X491445Y541135D03*
X482905Y544726D03*
X491534Y552726D03*
X491511Y546553D03*
X493392Y622285D03*
X493580Y616905D03*
X493661Y627713D03*
X493778Y633724D03*
X483059Y662649D03*
X481742Y657477D03*
X490706Y859339D03*
X491616Y938771D03*
X479613Y952189D03*
X480711Y999941D03*
X477857Y1004375D03*
X485633Y1036155D03*
X477765Y1093432D03*
X485574Y1098518D03*
X488927Y1104335D03*
X484082Y1106867D03*
X503325Y90650D03*
X508637Y90615D03*
X496023Y362913D03*
X497048Y369450D03*
X495750Y377531D03*
X506500Y379687D03*
X495203Y386890D03*
X503682Y448419D03*
X504729Y469905D03*
X496729Y461919D03*
X504729Y461419D03*
X501224Y492050D03*
X501649Y482165D03*
X500890Y500202D03*
X502493Y495917D03*
X506925Y546830D03*
X497448Y610548D03*
X504265Y633736D03*
X499258Y633716D03*
X506278Y628078D03*
X499278Y641817D03*
X499528Y657843D03*
X504508Y783817D03*
X504641Y789139D03*
X507095Y814784D03*
X509665Y824512D03*
X503383Y863025D03*
X498507Y865392D03*
X508248Y873319D03*
X509791Y881932D03*
X509017Y905295D03*
X498435Y1008766D03*
X498524Y997590D03*
X498585Y1016266D03*
X506562Y1238194D03*
X498562Y1226194D03*
Y1242194D03*
X521916Y92874D03*
X512958Y99961D03*
X522276Y223661D03*
X519638Y314346D03*
X512943Y443071D03*
X520823Y442603D03*
X518240Y459371D03*
X512210Y475825D03*
X513310Y462004D03*
X522756Y461818D03*
X513626Y528578D03*
X518416Y544895D03*
X520945Y590801D03*
X520770Y597130D03*
X524770Y605637D03*
X523596Y628242D03*
X515267Y627908D03*
X511278Y633473D03*
X513504Y755804D03*
X513278Y783286D03*
X519891Y795848D03*
X520741Y805149D03*
X524741Y845149D03*
X520870Y874694D03*
X511025Y911443D03*
X525159Y913818D03*
X516902Y910251D03*
X524475Y952290D03*
X522544Y992854D03*
X512232Y985172D03*
X521055Y1104335D03*
X516210Y1106867D03*
X514562Y1230194D03*
X540751Y97475D03*
X539748Y143740D03*
X537128Y148277D03*
X538170Y172190D03*
X537589Y177616D03*
X532026Y188727D03*
X529148Y208695D03*
X528783Y226141D03*
X532525Y265701D03*
X537612Y265896D03*
X534160Y281716D03*
X540101Y281982D03*
X540906Y290755D03*
X532659Y359557D03*
X526388Y351301D03*
X531612Y354272D03*
X531636Y349057D03*
X528812Y369164D03*
X533211Y364746D03*
X533115Y371856D03*
X530144Y376062D03*
X531953Y380749D03*
X542034Y392209D03*
X541706Y386223D03*
X533189Y390723D03*
X531953Y385749D03*
X535119Y483886D03*
X535219Y566797D03*
X535819Y578405D03*
X541245Y578986D03*
X534820Y596782D03*
X540770Y596729D03*
X529601Y596089D03*
X536087Y702364D03*
X542275Y760782D03*
X539449Y782389D03*
X537578Y772428D03*
X530741Y845149D03*
X531076Y913190D03*
X547732Y100625D03*
X552798Y143518D03*
X551898Y152373D03*
X555850Y178560D03*
X555913Y172665D03*
X555740Y183834D03*
X555260Y190185D03*
X549985Y192490D03*
X556030Y200864D03*
X556119Y212455D03*
X556053Y207037D03*
X542628Y266114D03*
X546987Y281307D03*
X551620Y390723D03*
X553563Y384987D03*
X557751Y750851D03*
X544515Y793875D03*
X544741Y809649D03*
X544878Y816309D03*
X556741Y820149D03*
X544741Y823149D03*
X557836Y851669D03*
X546940Y871389D03*
X548327Y905295D03*
X552923Y988813D03*
X544719Y1007522D03*
X551485Y1006648D03*
X548852Y1018307D03*
X545094Y1013678D03*
X545566Y1023731D03*
X554696Y1018469D03*
X557681Y1035088D03*
X557584Y1543411D03*
X560573Y60513D03*
X569114Y86012D03*
X565207Y94279D03*
X570394Y110784D03*
X574973Y124663D03*
X564885Y124283D03*
X569951Y124879D03*
X574588Y201683D03*
X564659Y208864D03*
X560928Y228631D03*
X575035Y249108D03*
X573479Y374705D03*
X563200Y739600D03*
X571493Y763090D03*
X564362Y757979D03*
X560263Y782207D03*
X567126Y779066D03*
X571984Y784507D03*
X561134Y869291D03*
X559214Y897425D03*
X567827Y884000D03*
X565003Y936807D03*
X570603Y957207D03*
X560923Y988813D03*
X568923D03*
X567484Y1024003D03*
X566058Y1109564D03*
X560211Y1134764D03*
Y1165091D03*
X566502Y1202103D03*
X575620Y1207737D03*
X569135Y1214372D03*
X564890Y1218169D03*
X570796Y1530309D03*
X563968Y1541445D03*
X568279Y1538438D03*
X572507Y1541375D03*
X576669Y102249D03*
X586037Y97667D03*
X575394Y110784D03*
X579954Y125107D03*
X582468Y148717D03*
X576317Y138838D03*
X577769Y195176D03*
X586789Y230556D03*
X591044Y227824D03*
X582048Y228646D03*
X577655Y244571D03*
X584998Y256394D03*
X578193Y336391D03*
X584679Y336285D03*
X577638Y769772D03*
X578271Y763556D03*
X583102Y767137D03*
X587183Y785008D03*
X578204Y775137D03*
X585912Y778470D03*
X588659Y790336D03*
X582737Y819831D03*
X580327Y892000D03*
X586136Y908935D03*
X586103Y961807D03*
X584923Y988813D03*
X576923D03*
X581166Y1021954D03*
X577704Y1029427D03*
X587880Y1034834D03*
X587467Y1105091D03*
X582012Y1102091D03*
X587467Y1117691D03*
X582012Y1127291D03*
Y1114691D03*
X587467Y1130291D03*
Y1142891D03*
X582012Y1139891D03*
X587467Y1155491D03*
X582012Y1152491D03*
X587467Y1168091D03*
X582012Y1165091D03*
X587467Y1180691D03*
X582012Y1177691D03*
X583520Y1230407D03*
X581803Y1493687D03*
X578859Y1497758D03*
X588859Y1490895D03*
X590826Y1495688D03*
X588507Y1514141D03*
X582027Y1502800D03*
X581803Y1509687D03*
X577931Y1505687D03*
X575809Y1532912D03*
X587809Y1528389D03*
X583809Y1533025D03*
X579809Y1528163D03*
X587809Y1545854D03*
X583809Y1541607D03*
X577571Y1544013D03*
X594497Y103411D03*
X594891Y97667D03*
X605687Y90650D03*
X592034Y199248D03*
X595634Y230117D03*
X593351Y244297D03*
X605147Y378600D03*
X602462Y458711D03*
X605011Y615600D03*
X604715Y914640D03*
X591754Y956979D03*
X606142Y965665D03*
X597556Y965829D03*
X600923Y988813D03*
X592923D03*
X599113Y1012354D03*
X593658Y1009354D03*
X599113Y1024954D03*
X593658Y1021954D03*
X606434Y1041904D03*
X594183Y1220068D03*
X592885Y1229402D03*
X592634Y1234921D03*
X591487Y1501687D03*
X591481Y1509313D03*
X595809Y1532133D03*
Y1546214D03*
X591809Y1542407D03*
X610999Y90615D03*
X615320Y99961D03*
X616923Y988813D03*
X608923D03*
X612923Y997860D03*
X607993Y1036920D03*
X610780Y1051037D03*
X622736Y1151870D03*
Y1159350D03*
X613738Y1546507D03*
X624278Y92874D03*
X639490Y148277D03*
X639951Y177616D03*
X634388Y188727D03*
X631510Y208695D03*
X624638Y223661D03*
X631145Y226141D03*
X639974Y265896D03*
X634887Y265701D03*
X636522Y281716D03*
X626476Y1155610D03*
X650094Y100625D03*
X643113Y97475D03*
X655160Y143518D03*
X642110Y143740D03*
X654260Y152373D03*
X640532Y172190D03*
X652347Y192490D03*
X647547Y231021D03*
X644990Y266114D03*
X649349Y281307D03*
X642463Y281982D03*
X643268Y290755D03*
X642414Y545528D03*
X650958Y668153D03*
X662935Y60513D03*
X671476Y86012D03*
X667569Y94279D03*
X658756Y103621D03*
X667247Y124283D03*
X672313Y124879D03*
X658275Y172665D03*
X658212Y178560D03*
X658102Y183834D03*
X657622Y190185D03*
X658392Y200864D03*
X667021Y208864D03*
X658481Y212455D03*
X658415Y207037D03*
X663290Y228631D03*
X661761Y382109D03*
X661760Y551683D03*
X660586Y606929D03*
X665086Y604567D03*
X665586Y595500D03*
X660827Y612592D03*
X666244Y610072D03*
X660546Y618400D03*
X666180Y616317D03*
X665643Y646055D03*
X658064Y650119D03*
X679031Y102249D03*
X688399Y97667D03*
X677756Y110784D03*
X672756D03*
X682316Y125107D03*
X677335Y124663D03*
X684830Y148717D03*
X678679Y138838D03*
X680131Y195176D03*
X676950Y201683D03*
X684410Y228646D03*
X677397Y249108D03*
X680017Y244571D03*
X682857Y339477D03*
X687055Y376456D03*
X685353Y404718D03*
Y412718D03*
X680586Y568000D03*
X696859Y103411D03*
X697253Y97667D03*
X690930Y143762D03*
X694396Y199248D03*
X697996Y230117D03*
X689151Y230556D03*
X693406Y227824D03*
X695713Y244297D03*
X690504Y253198D03*
X689486Y339583D03*
X692356Y764614D03*
X691991Y759581D03*
X692155Y778974D03*
X692221Y773449D03*
X708049Y90650D03*
X713361Y90615D03*
X717682Y99961D03*
X712692Y356779D03*
X717105Y410964D03*
X717420Y404334D03*
X709781Y442956D03*
X720996Y442856D03*
X719051Y458455D03*
X719612Y451108D03*
X706211Y465874D03*
X711463Y546712D03*
X713425Y786029D03*
X726640Y92874D03*
X736750Y188727D03*
X733872Y208695D03*
X733507Y226141D03*
X727000Y223661D03*
X737249Y265701D03*
X723404Y379657D03*
X721900Y384500D03*
X723440Y391496D03*
X734661Y393633D03*
X723440Y398583D03*
X728503Y891692D03*
X736452Y890548D03*
X728692Y886653D03*
X725194Y942073D03*
X733798Y950186D03*
X736067Y1611892D03*
X729600Y1625165D03*
X732268Y1618260D03*
X752456Y100625D03*
X745475Y97475D03*
X744472Y143740D03*
X741852Y148277D03*
X742894Y172190D03*
X742313Y177616D03*
X747352Y266114D03*
X742336Y265896D03*
X751711Y281307D03*
X744825Y281982D03*
X738884Y281716D03*
X745630Y290755D03*
X749444Y393858D03*
X752785Y382047D03*
X753086Y403500D03*
X751086Y398583D03*
X739316Y458572D03*
X744069Y746617D03*
X742000Y768137D03*
X738707Y987952D03*
X745673Y1007009D03*
X740530Y1524113D03*
X749786Y1590517D03*
X738775Y1597866D03*
X749704Y1608631D03*
X765297Y60513D03*
X769931Y94279D03*
X769609Y124283D03*
X757522Y143518D03*
X756622Y152373D03*
X760637Y172665D03*
X760464Y183834D03*
X760574Y178560D03*
X754709Y192490D03*
X759984Y190185D03*
X760754Y200864D03*
X769383Y208864D03*
X760843Y212455D03*
X760777Y207037D03*
X769349Y324518D03*
X754805Y339559D03*
X759624Y353961D03*
X756086Y377912D03*
X755086Y391496D03*
X756086Y386500D03*
X756174Y397912D03*
X755086Y409000D03*
X760398Y1440276D03*
X763542Y1590186D03*
X767310Y1599164D03*
X768361Y1610083D03*
X756358Y1616917D03*
X773838Y86012D03*
X781393Y102249D03*
X775118Y110784D03*
X780118D03*
X784678Y125107D03*
X779697Y124663D03*
X774675Y124879D03*
X781041Y138838D03*
X782493Y195176D03*
X779312Y201683D03*
X774432Y218085D03*
X782379Y244571D03*
X779759Y249108D03*
X772165Y314890D03*
X784118Y303962D03*
X772162Y332584D03*
X778502Y348015D03*
X772859Y347937D03*
X784902Y428653D03*
X783620Y1460108D03*
X781110Y1595254D03*
X777059Y1608982D03*
X784046Y1600438D03*
X799221Y103411D03*
X799615Y97667D03*
X790761D03*
X793292Y143762D03*
X787192Y148717D03*
X796758Y199248D03*
X800358Y230117D03*
X795768Y227824D03*
X791513Y230556D03*
X786772Y228646D03*
X798075Y244297D03*
X789722Y256394D03*
X786461Y293028D03*
X790280Y287421D03*
X795445Y356950D03*
X789581Y405011D03*
X793893Y409502D03*
X802136Y448334D03*
X796338Y1138130D03*
X793842Y1143384D03*
X797160Y1146609D03*
X792277Y1173065D03*
X799020Y1175975D03*
X798353Y1172011D03*
X792382Y1191664D03*
X793548Y1397690D03*
X789647Y1427518D03*
X798601Y1431673D03*
X793288Y1450918D03*
X787694Y1442749D03*
X800607Y1440760D03*
X790361Y1447895D03*
X790754Y1441399D03*
X793994Y1441499D03*
X797083Y1467883D03*
X794005Y1464178D03*
X790296Y1463459D03*
X787038Y1460533D03*
X786591Y1452803D03*
X790989Y1455695D03*
X810411Y90650D03*
X815723Y90615D03*
X817456Y305368D03*
Y313368D03*
X809490Y305368D03*
X809466Y310604D03*
X817100Y319600D03*
X809457Y330459D03*
X809490Y325368D03*
Y317368D03*
X810749Y443045D03*
X810453Y453330D03*
X810406Y448214D03*
X813678Y740979D03*
X817584Y764219D03*
X813635Y762000D03*
X818000Y797000D03*
X817845Y817879D03*
X818500Y810135D03*
X815863Y830097D03*
X814299Y840877D03*
X813887Y835146D03*
X816037Y845578D03*
X814080Y864464D03*
X817884Y915425D03*
X809632Y1142666D03*
X817964Y1157404D03*
X811507Y1157544D03*
X810018Y1167768D03*
X815037D03*
X814170Y1185205D03*
X805212Y1180175D03*
X805519Y1187215D03*
X804458Y1193112D03*
X817446Y1210089D03*
X806148Y1383715D03*
Y1375208D03*
X810204Y1401661D03*
X804654Y1404769D03*
X805569Y1441519D03*
X802684Y1465549D03*
X807576Y1469584D03*
X829002Y92874D03*
X820044Y99961D03*
X829362Y223661D03*
X822160Y258880D03*
X822477Y309368D03*
X829485Y345101D03*
X822626Y348066D03*
X818840Y444091D03*
X824650Y455034D03*
Y450034D03*
X834282Y536085D03*
X832284Y731216D03*
X821582Y727140D03*
X830484Y738750D03*
X830075Y769000D03*
X824500Y756000D03*
Y774000D03*
Y782500D03*
X830075Y787000D03*
X824342Y792315D03*
X824500Y800500D03*
X830075Y805000D03*
Y823000D03*
X829757Y842672D03*
X822916Y852576D03*
X823540Y857956D03*
X831654Y864494D03*
X822938Y863298D03*
X833194Y873561D03*
X827992Y874107D03*
X830063Y898500D03*
X819918Y889365D03*
X824804Y898395D03*
X834465Y884538D03*
X829848Y914211D03*
X825336Y916774D03*
X834751Y922368D03*
X824414Y939655D03*
X832432Y977982D03*
X825744Y1146937D03*
X818879Y1187310D03*
X823309Y1180235D03*
X823516Y1185238D03*
X819419Y1230265D03*
X826204Y1444689D03*
Y1440689D03*
X826341Y1451236D03*
X826365Y1458974D03*
X826219Y1455244D03*
X847837Y97475D03*
X844675Y177616D03*
X845256Y172190D03*
X839112Y188727D03*
X836234Y208695D03*
X835869Y226141D03*
X844698Y265896D03*
X839611Y265701D03*
X849714Y266114D03*
X841246Y281716D03*
X847187Y281982D03*
X847992Y290755D03*
X845435Y356172D03*
X849591Y411388D03*
X842515Y461382D03*
X850732Y469382D03*
X842779Y473076D03*
X842916Y467009D03*
X848444Y657756D03*
X837272Y663910D03*
X842352Y659243D03*
X845850Y710969D03*
X836078Y709619D03*
X848284Y731181D03*
X846484Y738750D03*
X836713Y738751D03*
X835215Y847719D03*
X835346Y891346D03*
X847098Y891213D03*
X842856Y949146D03*
X843734Y1008778D03*
X835474Y1457397D03*
X854818Y100625D03*
X862826Y183834D03*
X862999Y172665D03*
X862936Y178560D03*
X857071Y192490D03*
X862346Y190185D03*
X863116Y200864D03*
X863205Y212455D03*
X863139Y207037D03*
X852271Y231021D03*
X866015Y224536D03*
X854073Y281307D03*
X863430Y309368D03*
Y316970D03*
X863114Y324505D03*
X863040Y330140D03*
X860586Y383000D03*
X861235Y394000D03*
X854086Y392999D03*
X855017Y411969D03*
X867093Y570703D03*
Y582828D03*
X861663Y646653D03*
X855300Y646819D03*
X853982Y657506D03*
X859441Y678015D03*
X864029Y688970D03*
X858186Y713170D03*
X867455Y710611D03*
X858002Y707244D03*
X867227Y722060D03*
X859199Y744517D03*
X854484Y738633D03*
X859000Y756000D03*
Y774000D03*
Y792000D03*
Y810000D03*
X858988Y898307D03*
X867096Y935963D03*
X858601Y934505D03*
X853030Y934690D03*
X851925Y951350D03*
X860887Y1023208D03*
X867659Y60513D03*
X876200Y86012D03*
X867787Y85731D03*
X872293Y94279D03*
X883118Y262687D03*
X873262Y300030D03*
X869924Y305368D03*
Y313368D03*
Y321368D03*
Y328722D03*
X874005Y344917D03*
X870413Y342791D03*
X869924Y333722D03*
X877909Y391731D03*
X882925Y391099D03*
X872736Y391754D03*
X867586Y393000D03*
X868586Y398500D03*
X874253Y420080D03*
X869454Y479303D03*
X869954Y487303D03*
X882954Y486256D03*
X882195Y539204D03*
X878382Y554942D03*
X876949Y571419D03*
X881476Y588202D03*
X881131Y577349D03*
X875290Y578703D03*
X878881Y667156D03*
X880501Y710611D03*
X873021Y715729D03*
X879875Y753612D03*
X873728Y752692D03*
X870017Y757313D03*
X870000Y780000D03*
X879887Y784719D03*
X880040Y792851D03*
X876402Y797415D03*
X871600Y898584D03*
X876481Y941126D03*
X872126Y934766D03*
X870209Y949384D03*
X869741Y1025895D03*
X875321Y1207654D03*
X883142Y1259935D03*
X878244Y1451605D03*
X894472Y143740D03*
X891852Y148277D03*
X895064Y250186D03*
X885884Y255118D03*
X897004Y257480D03*
X892484Y260860D03*
X886496Y268968D03*
X886059Y284644D03*
X885953Y321368D03*
Y333368D03*
X888812Y357372D03*
X890553Y392038D03*
X889219Y426952D03*
X891699Y420445D03*
X885556Y543664D03*
X895933Y609696D03*
X886836Y729778D03*
X892040Y784511D03*
X898737Y792289D03*
X889516Y792851D03*
X890326Y828548D03*
X895050D03*
X891367Y941126D03*
X885099Y1021685D03*
X887862Y1088067D03*
X894004Y1081231D03*
X888650Y1199622D03*
X894713Y1210419D03*
X898878Y1214182D03*
X899286Y1219469D03*
X892532Y1220112D03*
X897169Y1225259D03*
X889244Y1444859D03*
X889336Y1452554D03*
X889244Y1468859D03*
X907522Y143518D03*
X906622Y152373D03*
X915653Y307438D03*
X905483Y355262D03*
X905000Y362158D03*
X906161Y367191D03*
X910646Y376084D03*
X906344Y372524D03*
X910236Y465272D03*
X914296Y558143D03*
X913728Y550495D03*
X908846Y560124D03*
X910789Y598726D03*
X912462Y683770D03*
Y695770D03*
X902236Y689332D03*
Y694332D03*
X913247Y714204D03*
X900983Y940895D03*
X906909Y951494D03*
X909811Y962400D03*
X902389Y1081764D03*
X908799Y1093659D03*
Y1088659D03*
X908278Y1083484D03*
X908799Y1100659D03*
X902353Y1104333D03*
X903959Y1207823D03*
X906784Y1216607D03*
X931393Y102249D03*
X930118Y110784D03*
X925118D03*
X924675Y124879D03*
X929697Y124663D03*
X919609Y124283D03*
X931041Y138838D03*
X929978Y186854D03*
X923732Y304585D03*
X923311Y349959D03*
X921343Y376888D03*
X916330Y377748D03*
X929947Y376821D03*
X927766Y456442D03*
X927596Y447453D03*
X921973Y469328D03*
X927401Y469059D03*
X916593Y469140D03*
X917811Y544325D03*
X923642Y561578D03*
X919038Y579378D03*
X923599Y581578D03*
X929790Y828603D03*
X929181Y895029D03*
X916628Y918042D03*
X928628D03*
X929741Y967006D03*
X924956Y994321D03*
X924864Y1023208D03*
X916749Y1092664D03*
X930754Y1310564D03*
X931159Y1379427D03*
X920360Y1387039D03*
X931199Y1371951D03*
X931159Y1390827D03*
Y1406027D03*
X917744Y1453573D03*
X940761Y97667D03*
X934678Y125107D03*
X943292Y143762D03*
X937192Y148717D03*
X933159Y180347D03*
X947424Y184419D03*
X946234Y213390D03*
X942179Y215727D03*
X937438Y213817D03*
X936962Y249807D03*
X944248Y239844D03*
X934128Y355168D03*
X944238Y360828D03*
X936175Y364823D03*
X933424Y458455D03*
X933161Y451442D03*
X933404Y463462D03*
X933412Y468942D03*
X948532Y541135D03*
X939992Y544726D03*
X948598Y546553D03*
X948621Y552726D03*
X935281Y677795D03*
X939314Y707847D03*
X933201Y798297D03*
X946970Y786366D03*
X938357Y808856D03*
X940100Y830700D03*
X938729Y874396D03*
X942194Y891216D03*
X944628Y928101D03*
X933810Y972433D03*
X945671Y982191D03*
X943093Y1021769D03*
X939298Y1207654D03*
X947119Y1259935D03*
X944207Y1320739D03*
X947308Y1325035D03*
X939559Y1398427D03*
X944235Y1406262D03*
X937671Y1492139D03*
X949221Y103411D03*
X949615Y97667D03*
X960411Y90650D03*
X950177Y215730D03*
X948741Y229468D03*
X948785Y242464D03*
X950953Y317947D03*
X962769Y451419D03*
X955816Y464919D03*
X963816Y464419D03*
X958124Y492354D03*
X958736Y482165D03*
X959600Y496486D03*
X957977Y500202D03*
X948905Y534909D03*
X950479Y622285D03*
X954535Y610548D03*
X950667Y616905D03*
X963365Y628078D03*
X961352Y633736D03*
X950865Y633724D03*
X950748Y627713D03*
X956345Y633716D03*
X956365Y641817D03*
X956023Y706907D03*
X963869Y725057D03*
X955950Y734178D03*
X957763Y725336D03*
X957579Y744168D03*
X953837Y763025D03*
X950699Y779711D03*
X949609Y796051D03*
X957487Y798553D03*
X955712Y833988D03*
X955343Y866850D03*
X964280Y927777D03*
X958567Y927654D03*
X959545Y918306D03*
X951863Y936168D03*
X957235Y936398D03*
X962329Y936229D03*
X957671Y977921D03*
X949671D03*
X957671Y991564D03*
X953671Y982191D03*
X954937Y1021998D03*
X957981Y1081231D03*
X951839Y1088067D03*
X952627Y1199622D03*
X958690Y1210419D03*
X963263Y1219469D03*
X962855Y1214182D03*
X956509Y1220112D03*
X961146Y1225259D03*
X952395Y1395276D03*
X979002Y92874D03*
X965723Y90615D03*
X970044Y99961D03*
X979362Y223661D03*
X975631Y343112D03*
X972030Y446071D03*
X979910Y445603D03*
X972397Y465004D03*
X977327Y462371D03*
X975868Y527449D03*
X978303Y544895D03*
X978032Y590801D03*
X977857Y597130D03*
X980683Y628242D03*
X972354Y627908D03*
X968365Y633473D03*
X973450Y747280D03*
X978978Y817618D03*
X974437Y849140D03*
X973510Y834991D03*
X967842Y864801D03*
X970299Y853773D03*
X978880Y869552D03*
X966813Y904556D03*
X973988Y910038D03*
X965671Y982191D03*
X966366Y1081764D03*
X972776Y1093659D03*
X972255Y1083484D03*
X972776Y1088659D03*
X966330Y1104333D03*
X972776Y1100659D03*
X967936Y1207823D03*
X970761Y1216607D03*
X974985Y1290950D03*
X979996Y1386100D03*
X996834Y143740D03*
X994214Y148277D03*
X995256Y172190D03*
X994675Y177616D03*
X989112Y188727D03*
X986234Y208695D03*
X985869Y226141D03*
X989611Y265701D03*
X994698Y265896D03*
X991246Y281716D03*
X997187Y281982D03*
X987517Y314092D03*
X993552Y318175D03*
X989630Y343862D03*
X983717Y341665D03*
X983956Y346652D03*
X993026Y353813D03*
X981719Y352217D03*
X988631Y349496D03*
X986373Y370467D03*
X981843Y464818D03*
X992206Y483886D03*
X985699Y480705D03*
X985334Y498151D03*
X982375Y529929D03*
X986268Y532949D03*
X992306Y566797D03*
X992906Y578405D03*
X991907Y596782D03*
X986688Y596089D03*
X986600Y717641D03*
X987461Y745796D03*
X984357Y777555D03*
X997051Y778833D03*
X990699Y778630D03*
X987990Y774005D03*
X987394Y787490D03*
X985921Y805135D03*
X994051Y810871D03*
X996385Y816141D03*
X994094Y829000D03*
X987702Y829159D03*
X987703Y837159D03*
X992441Y870398D03*
X985448Y1398271D03*
X982241Y1489637D03*
X1004818Y100625D03*
X997837Y97475D03*
X1013480Y103621D03*
X1005397Y141247D03*
X1009884Y143518D03*
X1008984Y152373D03*
X1012936Y178560D03*
X1012826Y183834D03*
X1012999Y172665D03*
X1012346Y190185D03*
X1007071Y192490D03*
X1013116Y200864D03*
X1013139Y207037D03*
X1013205Y212455D03*
X999714Y266114D03*
X1004061Y280808D03*
X997992Y290755D03*
X1002580Y309619D03*
X1003181Y323057D03*
X1001105Y318006D03*
X998332Y578986D03*
X997857Y596729D03*
X1007990Y765899D03*
X999990Y764566D03*
X1013151Y756726D03*
X1012695Y776728D03*
X999990Y774671D03*
X1013319Y785929D03*
X1006053Y787745D03*
X1006054Y810969D03*
X1010699Y803454D03*
X1012703Y837659D03*
X1001187Y850084D03*
X1005413Y905295D03*
X1006619Y933822D03*
X1012219Y954222D03*
X1009564Y988874D03*
X1001805Y1007522D03*
X1008571Y1006648D03*
X1002180Y1013678D03*
X1002652Y1023731D03*
X1005938Y1018307D03*
X998600Y1369200D03*
X999283Y1377400D03*
X998643Y1398271D03*
X1017659Y60513D03*
X1026200Y86012D03*
X1017787Y85731D03*
X1022293Y94279D03*
X1027480Y110784D03*
X1021971Y124283D03*
X1027037Y124879D03*
X1021826Y186778D03*
X1018014Y228631D03*
X1020406Y350772D03*
X1021885Y698974D03*
X1018015Y751565D03*
X1017664Y779101D03*
X1018071Y798490D03*
X1017955Y812097D03*
X1021221Y848712D03*
X1017800Y867065D03*
X1021408Y895008D03*
X1024913Y884000D03*
X1022346Y917669D03*
X1029570Y917718D03*
X1027719Y958822D03*
X1018009Y988813D03*
X1026009D03*
X1024570Y1024003D03*
X1014767Y1035088D03*
X1025143Y1030672D03*
X1023144Y1109564D03*
X1023139Y1184856D03*
X1022420Y1203204D03*
X1026221Y1214372D03*
X1021976Y1218169D03*
X1019391Y1377061D03*
X1016769Y1489832D03*
X1033755Y102249D03*
X1043123Y97667D03*
X1032480Y110784D03*
X1037040Y125107D03*
X1032059Y124663D03*
X1045654Y143762D03*
X1039554Y148717D03*
X1033403Y138838D03*
X1034855Y195176D03*
X1031674Y201683D03*
X1043875Y230556D03*
X1039134Y228646D03*
X1034741Y244571D03*
X1032121Y249108D03*
X1042084Y256394D03*
X1045650Y300093D03*
X1041783Y321114D03*
X1031259Y350427D03*
X1043016Y782161D03*
X1043425Y830800D03*
X1043626Y836563D03*
X1037527Y836486D03*
X1031813Y850273D03*
X1046045Y841217D03*
X1040822Y841339D03*
X1044390Y861210D03*
X1038363Y875288D03*
X1038010Y902565D03*
X1042009Y988813D03*
X1034009D03*
X1038252Y1021954D03*
X1044553Y1105091D03*
X1039098Y1102091D03*
X1044553Y1117691D03*
X1039098Y1114691D03*
Y1127291D03*
X1044553Y1130291D03*
Y1142891D03*
X1039098Y1139891D03*
X1044553Y1155491D03*
X1039098Y1152491D03*
X1044553Y1168091D03*
X1039098Y1165091D03*
X1044553Y1180691D03*
X1039098Y1177691D03*
X1032831Y1207950D03*
X1040606Y1230407D03*
X1051583Y103411D03*
X1051977Y97667D03*
X1049120Y199248D03*
X1052720Y230117D03*
X1048130Y227824D03*
X1061387Y343509D03*
X1060679Y356151D03*
X1059549Y458711D03*
X1062098Y615600D03*
X1048314Y833102D03*
X1053392Y832788D03*
X1051550Y823146D03*
X1050358Y837793D03*
X1052500Y841200D03*
X1049087Y856033D03*
X1053909Y855472D03*
X1050009Y988813D03*
X1058009D03*
X1056199Y1012354D03*
X1050744Y1009354D03*
X1056199Y1024954D03*
X1050744Y1021954D03*
X1057212Y1040356D03*
X1049930Y1221407D03*
X1049770Y1229402D03*
X1049720Y1234921D03*
X1062773Y90650D03*
X1068085Y90615D03*
X1072406Y99961D03*
X1076571Y310574D03*
X1063642Y634190D03*
X1066931Y645389D03*
X1065823Y988773D03*
X1074009Y988813D03*
X1070009Y997860D03*
X1065079Y1036920D03*
X1076577Y1041332D03*
X1067866Y1051037D03*
X1069642Y1445541D03*
X1068861Y1451311D03*
X1081364Y92874D03*
X1091474Y188727D03*
X1088596Y208695D03*
X1088231Y226141D03*
X1081724Y223661D03*
X1091973Y265701D03*
X1093608Y281716D03*
X1092554Y340318D03*
X1079822Y1151870D03*
X1083562Y1155610D03*
X1079822Y1159350D03*
X1084000Y1529600D03*
X1091529Y1528718D03*
X1091525Y1546300D03*
X1091569Y1561300D03*
X1092527Y1579422D03*
X1090469Y1588435D03*
X1083900Y1593206D03*
X1088021Y1606949D03*
X1093778Y1599574D03*
X1086904Y1599004D03*
X1090093Y1628297D03*
X1089474Y1638213D03*
X1100199Y97475D03*
X1107180Y100625D03*
X1107759Y141247D03*
X1099196Y143740D03*
X1096576Y148277D03*
X1097618Y172190D03*
X1109903Y171523D03*
X1097037Y177616D03*
X1109433Y192490D03*
X1102076Y266114D03*
X1097060Y265896D03*
X1106435Y281307D03*
X1099549Y281982D03*
X1100354Y290755D03*
X1105012Y353504D03*
X1099501Y545528D03*
X1104448Y653161D03*
X1108045Y668153D03*
X1096780Y1526700D03*
X1101402Y1531702D03*
X1098617Y1546183D03*
X1096780Y1535400D03*
X1099371Y1561153D03*
X1100476Y1579318D03*
X1102904Y1566668D03*
X1100233Y1588000D03*
X1098904Y1602138D03*
X1101946Y1614709D03*
X1096941Y1627905D03*
X1105474Y1629450D03*
Y1638426D03*
X1097474Y1637753D03*
X1120021Y60513D03*
X1120149Y85731D03*
X1124655Y94279D03*
X1115842Y103621D03*
X1124333Y124283D03*
X1112246Y143518D03*
X1111346Y152373D03*
X1115188Y183834D03*
X1115298Y178560D03*
X1115361Y172665D03*
X1124075Y192665D03*
X1115478Y200864D03*
X1115501Y207037D03*
X1115567Y212455D03*
X1124107Y208864D03*
X1120376Y228631D03*
X1118848Y382109D03*
X1118847Y551683D03*
X1117673Y606929D03*
X1122673Y595500D03*
X1122173Y604567D03*
X1123331Y610072D03*
X1123267Y616317D03*
X1117633Y618400D03*
X1117914Y612592D03*
X1115151Y650119D03*
X1128562Y86012D03*
X1136117Y102249D03*
X1129842Y110784D03*
X1134842D03*
X1139402Y125107D03*
X1129399Y124879D03*
X1134421Y124663D03*
X1141916Y148717D03*
X1135765Y138838D03*
X1137217Y195176D03*
X1134036Y201683D03*
X1141496Y228646D03*
X1137103Y244571D03*
X1134483Y249108D03*
X1137830Y336230D03*
X1142440Y404718D03*
Y412718D03*
X1135548Y455804D03*
X1137673Y568000D03*
X1153945Y103411D03*
X1145485Y97667D03*
X1154339D03*
X1148016Y143762D03*
X1151482Y199248D03*
X1146237Y230556D03*
X1155082Y230117D03*
X1150492Y227824D03*
X1147590Y253198D03*
X1145587Y339148D03*
X1157251Y636842D03*
X1152485Y764552D03*
X1147468Y766093D03*
X1153485Y813142D03*
X1154985Y802897D03*
X1153229Y848581D03*
X1170447Y90615D03*
X1165135Y90650D03*
X1174768Y99961D03*
X1166868Y442956D03*
X1163298Y465874D03*
X1160756Y665140D03*
X1164732Y802269D03*
X1173122Y802759D03*
X1163579Y850774D03*
X1161535Y844167D03*
X1174461Y914515D03*
X1183726Y92874D03*
X1190958Y208695D03*
X1190593Y226141D03*
X1184086Y223661D03*
X1191748Y392676D03*
X1179184Y403307D03*
X1176699Y451108D03*
X1176138Y458455D03*
X1177566Y778539D03*
X1185516Y844248D03*
X1190968Y848703D03*
X1184340Y851072D03*
X1183012Y856553D03*
X1190213Y856816D03*
X1184547Y1215452D03*
X1202561Y97475D03*
X1201558Y143740D03*
X1198938Y148277D03*
X1199980Y172190D03*
X1199399Y177616D03*
X1193836Y188727D03*
X1199422Y265896D03*
X1204438Y266114D03*
X1194335Y265701D03*
X1201911Y281982D03*
X1195970Y281716D03*
X1202716Y290755D03*
X1195800Y324000D03*
X1206531Y393858D03*
X1208173Y398583D03*
X1192702Y440489D03*
X1192957Y435158D03*
X1196403Y458572D03*
X1222383Y60513D03*
X1222511Y85731D03*
X1218204Y103621D03*
X1209542Y100625D03*
X1210121Y141247D03*
X1214608Y143518D03*
X1213708Y152373D03*
X1217550Y183834D03*
X1212265Y171523D03*
X1217723Y172665D03*
X1217660Y178560D03*
X1211795Y192490D03*
X1217840Y200864D03*
X1217863Y207037D03*
X1217929Y212455D03*
X1222738Y228631D03*
X1208797Y281307D03*
X1211892Y339559D03*
X1213173Y377912D03*
Y386500D03*
X1209872Y382047D03*
X1212173Y391496D03*
X1213261Y397912D03*
X1210173Y403500D03*
X1212173Y409000D03*
X1230924Y86012D03*
X1238479Y102249D03*
X1227017Y94279D03*
X1232204Y110784D03*
X1237204D03*
X1236783Y124663D03*
X1226695Y124283D03*
X1231761Y124879D03*
X1238127Y138838D03*
X1239579Y195176D03*
X1236398Y201683D03*
X1226469Y208864D03*
X1239465Y244571D03*
X1236845Y249108D03*
X1229252Y314890D03*
X1226436Y324518D03*
X1235589Y348015D03*
X1229942Y347937D03*
X1256307Y103411D03*
X1247847Y97667D03*
X1256701D03*
X1241764Y125107D03*
X1250378Y143762D03*
X1244278Y148717D03*
X1253844Y199248D03*
X1248599Y230556D03*
X1252854Y227824D03*
X1243858Y228646D03*
X1246808Y256394D03*
X1241205Y303962D03*
X1250928Y1142828D03*
X1254200Y1146600D03*
X1256218Y1175987D03*
X1249363Y1166065D03*
X1255439Y1172008D03*
X1255628Y1188345D03*
X1254275Y1531334D03*
X1249894Y1527805D03*
X1253904Y1519645D03*
X1254275Y1539334D03*
X1250434Y1535334D03*
X1267497Y90650D03*
X1257444Y230117D03*
X1266616Y322456D03*
X1263500Y336000D03*
X1263484Y385644D03*
X1268659Y385123D03*
X1268067Y406060D03*
X1261231Y399918D03*
X1267540Y459330D03*
X1267493Y454214D03*
X1267836Y449045D03*
X1270586Y905324D03*
X1272661Y929858D03*
X1266718Y1142666D03*
X1268593Y1157544D03*
X1267104Y1167768D03*
X1272123D03*
X1271256Y1185205D03*
X1262605Y1187215D03*
X1262298Y1180175D03*
X1260800Y1191096D03*
X1267333Y1531334D03*
X1262891Y1527334D03*
X1267183Y1539334D03*
X1262891Y1535334D03*
X1286088Y92874D03*
X1277130Y99961D03*
X1286448Y223661D03*
X1289345Y330655D03*
X1287437Y370010D03*
Y379429D03*
X1273659Y385123D03*
X1280659D03*
X1284333Y391569D03*
X1282760Y409016D03*
X1281737Y461034D03*
Y456034D03*
X1284900Y678800D03*
X1278255Y722241D03*
X1282539Y746076D03*
Y756076D03*
X1279539Y776576D03*
X1281777Y823500D03*
X1285500Y843500D03*
X1281269Y835492D03*
X1285500Y851500D03*
X1279460Y854487D03*
Y859487D03*
Y864487D03*
X1274396Y866896D03*
X1279460Y874487D03*
Y879487D03*
X1274264Y898591D03*
X1279460Y884487D03*
X1279299Y898813D03*
X1279460Y889487D03*
X1274400Y914123D03*
X1283493Y929858D03*
X1279693Y919800D03*
X1274670Y919808D03*
X1289547Y941000D03*
X1275050Y1157404D03*
X1275965Y1187232D03*
X1280602Y1185238D03*
X1280395Y1180235D03*
X1275032Y1209589D03*
X1302139Y26325D03*
X1304923Y97475D03*
X1301761Y177616D03*
X1302342Y172190D03*
X1296198Y188727D03*
X1293320Y208695D03*
X1292955Y226141D03*
X1296697Y265701D03*
X1301784Y265896D03*
X1304273Y281982D03*
X1298332Y281716D03*
X1305078Y290755D03*
X1292500Y335000D03*
X1299959Y356954D03*
X1299410Y370976D03*
X1293048Y379088D03*
X1298346Y379028D03*
X1293100Y406739D03*
X1299867Y477318D03*
X1299466Y466409D03*
X1299807Y472020D03*
X1299304Y487382D03*
X1301194Y565518D03*
X1305836Y660009D03*
X1298963Y659609D03*
X1289811Y677612D03*
X1303520Y748403D03*
X1291604Y781576D03*
Y776576D03*
Y771435D03*
X1298720Y798975D03*
X1302140Y812625D03*
X1302501Y824747D03*
X1297667Y832150D03*
X1293500Y827500D03*
X1296770Y828775D03*
X1293500Y843500D03*
Y835500D03*
X1296687Y839500D03*
X1293500Y851500D03*
X1294000Y863500D03*
X1305250Y889250D03*
X1291129Y892267D03*
X1304949Y928546D03*
X1295453Y928047D03*
X1291059Y917000D03*
X1302000D03*
X1300882Y937144D03*
X1297558Y970216D03*
X1314887Y45448D03*
X1311904Y100625D03*
X1320566Y103621D03*
X1319912Y183834D03*
X1314627Y171523D03*
X1320085Y172665D03*
X1320022Y178560D03*
X1314157Y192490D03*
X1320202Y200864D03*
X1320225Y207037D03*
X1320291Y212455D03*
X1309357Y231021D03*
X1306800Y266114D03*
X1311159Y281307D03*
X1313103Y339606D03*
X1312240Y334681D03*
X1308012Y348109D03*
X1308410Y379591D03*
X1310546Y407104D03*
X1308066Y413611D03*
X1308006Y423944D03*
X1307819Y474382D03*
X1319474Y467560D03*
X1319974Y475560D03*
X1319323Y598454D03*
X1319000Y641000D03*
X1313979Y677726D03*
X1319000Y685500D03*
X1321000Y796000D03*
X1313000D03*
X1317000Y799000D03*
X1315000Y811620D03*
X1321000Y804000D03*
X1314500Y911500D03*
Y905000D03*
X1309103Y917000D03*
X1313152Y936605D03*
X1312575Y943974D03*
X1321256Y943815D03*
X1307000Y960500D03*
X1315441Y960000D03*
X1311000Y970124D03*
X1307707Y979870D03*
X1307561Y986951D03*
X1315756Y1039344D03*
X1306385Y1036646D03*
X1319237Y1225428D03*
X1318287Y1291381D03*
X1324120Y22742D03*
X1328003Y32403D03*
X1328318Y27333D03*
X1336623Y30483D03*
X1328831Y208864D03*
X1325100Y228631D03*
X1332359Y322685D03*
X1331922Y359836D03*
X1335440Y452799D03*
X1329083Y448931D03*
X1332974Y474513D03*
X1326993Y556788D03*
X1327043Y573346D03*
X1327000Y562500D03*
X1326946Y567906D03*
X1338000Y562500D03*
X1335000Y590500D03*
X1327000Y578500D03*
Y583826D03*
Y605000D03*
Y594500D03*
X1333224Y615484D03*
X1327000Y613000D03*
X1335532Y622260D03*
X1338000Y609000D03*
X1335000Y633000D03*
X1327000Y629000D03*
X1327003Y623940D03*
X1338000Y653500D03*
X1327000Y641000D03*
Y657500D03*
Y685500D03*
Y695500D03*
Y700500D03*
X1338000D03*
X1327000Y711500D03*
Y716500D03*
Y732500D03*
X1330295Y746328D03*
X1336661Y753675D03*
Y745675D03*
Y737675D03*
X1330295Y751328D03*
X1330086Y763758D03*
X1324217Y780595D03*
X1336746Y781675D03*
X1329000Y796000D03*
X1325000Y799000D03*
X1337000Y796000D03*
X1333000Y799000D03*
X1323205Y867665D03*
X1336096Y905042D03*
X1326500Y925500D03*
X1333132Y933781D03*
X1336000Y943500D03*
X1323000Y934075D03*
X1326500Y943500D03*
X1325550Y960445D03*
X1329189Y1088205D03*
X1334161Y1098518D03*
X1337514Y1104335D03*
X1332669Y1106867D03*
X1331237Y1229428D03*
X1335237Y1237428D03*
X1323237D03*
X1351559Y143740D03*
X1348939Y148277D03*
X1344007Y279054D03*
X1347990Y322539D03*
X1341169Y325926D03*
X1349636Y340862D03*
X1349763Y371908D03*
X1346443Y431112D03*
X1352008Y435101D03*
X1352271Y442114D03*
X1346613Y440101D03*
X1352251Y447121D03*
X1346248Y452718D03*
X1340820Y452987D03*
X1352259Y452601D03*
X1346738Y564492D03*
X1339289Y568461D03*
X1342053Y579339D03*
X1346533Y576780D03*
X1340522Y586133D03*
X1343000Y590458D03*
X1346533Y581898D03*
X1344129Y606914D03*
X1344433Y601201D03*
X1339289Y614961D03*
X1344680Y619085D03*
X1346738Y611192D03*
X1346533Y628398D03*
X1342053Y625839D03*
X1340522Y632633D03*
X1343000Y636958D03*
X1346738Y655492D03*
X1339289Y659461D03*
X1346533Y667780D03*
X1342053Y670339D03*
X1346533Y672898D03*
X1340522Y677133D03*
X1343000Y681458D03*
X1350929Y687043D03*
X1340299Y686243D03*
X1346738Y702492D03*
X1346533Y719898D03*
X1339289Y706461D03*
X1342053Y717339D03*
X1346533Y714780D03*
X1340522Y724133D03*
X1343000Y728458D03*
X1344768Y769675D03*
X1345226Y777675D03*
X1341000Y799000D03*
X1345000Y796000D03*
X1348917D03*
X1352817D03*
X1353948Y943603D03*
X1345948D03*
X1349848Y936755D03*
X1343237Y1241428D03*
X1351876Y1260160D03*
X1360122Y141247D03*
X1364609Y143518D03*
X1363709Y152373D03*
X1355255Y561032D03*
Y652032D03*
X1367000Y811620D03*
X1365000Y804000D03*
X1355000Y811620D03*
X1365948Y939475D03*
X1357948Y938842D03*
X1361948Y943603D03*
X1369948D03*
X1365049Y1028416D03*
X1365314Y1021793D03*
X1366265Y1039880D03*
X1366289Y1098518D03*
X1369642Y1104335D03*
X1364797Y1106867D03*
X1360876Y1260160D03*
X1382205Y110784D03*
X1387205D03*
X1386784Y124663D03*
X1376696Y124283D03*
X1381762Y124879D03*
X1386399Y201683D03*
X1381519Y218085D03*
X1386846Y249108D03*
X1383634Y342766D03*
X1384265Y334371D03*
Y352371D03*
X1383963Y366675D03*
X1375108Y420838D03*
X1383343Y508228D03*
X1383907Y516591D03*
X1383556Y554388D03*
X1378415Y558795D03*
Y563984D03*
Y569776D03*
X1378957Y584457D03*
X1382997Y581317D03*
X1383425Y593575D03*
X1378415Y605295D03*
Y610484D03*
Y616276D03*
X1384657Y631620D03*
X1378957Y627988D03*
X1378415Y649795D03*
Y654984D03*
Y660776D03*
X1386289Y672488D03*
X1378957Y675457D03*
X1378415Y696795D03*
Y701984D03*
X1378957Y719488D03*
X1378415Y707776D03*
X1385290Y722400D03*
X1381000Y804000D03*
X1385360Y811757D03*
X1375193Y811724D03*
X1378500Y925500D03*
X1382775Y930281D03*
X1373948Y940103D03*
X1381519Y996280D03*
X1373534Y1012325D03*
X1378938Y1000586D03*
X1374059Y1018860D03*
X1378559Y1038534D03*
X1384784Y1033783D03*
X1385929Y1038665D03*
X1373874Y1032266D03*
X1385152Y1046591D03*
X1388480Y102249D03*
X1397848Y97667D03*
X1391765Y125107D03*
X1400379Y143762D03*
X1394279Y148717D03*
X1388128Y138838D03*
X1389580Y195176D03*
X1402855Y227824D03*
X1398600Y230556D03*
X1393859Y228646D03*
X1389466Y244571D03*
X1396809Y256394D03*
X1395726Y320529D03*
X1395568Y325529D03*
X1395726Y330529D03*
X1395736Y335529D03*
X1395726Y340529D03*
Y345529D03*
Y360529D03*
Y350529D03*
Y355529D03*
X1391896Y365529D03*
X1399884Y367165D03*
X1389557Y424678D03*
X1390271Y417578D03*
X1403085Y460565D03*
X1397079Y531726D03*
Y544726D03*
X1390741Y561000D03*
Y569000D03*
X1397000Y652000D03*
Y660000D03*
Y699000D03*
Y707000D03*
X1391040Y812027D03*
X1398530Y811717D03*
X1402417Y811692D03*
X1400069Y827515D03*
X1401300Y820485D03*
X1402000Y840000D03*
Y848000D03*
Y864000D03*
Y876000D03*
Y884000D03*
Y892000D03*
Y900000D03*
X1387520Y905307D03*
X1387753Y912629D03*
X1394891Y914783D03*
X1402187Y908270D03*
X1396869Y958707D03*
X1402064Y965913D03*
X1389192Y992568D03*
X1394885Y999941D03*
X1392031Y1004375D03*
X1389762Y1043055D03*
X1399807Y1036155D03*
X1392086Y1092743D03*
X1399748Y1098518D03*
X1403101Y1104335D03*
X1398256Y1106867D03*
X1389052Y1303139D03*
X1406308Y103411D03*
X1406702Y97667D03*
X1417498Y90650D03*
X1403845Y199248D03*
X1407445Y230117D03*
X1408854Y381207D03*
X1408254Y398041D03*
X1407844Y411033D03*
X1415674Y421278D03*
X1417856Y448419D03*
X1410903Y470419D03*
Y461919D03*
X1418903Y461419D03*
X1415623Y492268D03*
X1415823Y482165D03*
X1415064Y500202D03*
X1416413Y495649D03*
X1405992Y534909D03*
X1405619Y541135D03*
X1405685Y546553D03*
X1405708Y552726D03*
X1411622Y610548D03*
X1407566Y622285D03*
X1407754Y616905D03*
X1418439Y633736D03*
X1407952Y633724D03*
X1413432Y633716D03*
X1407835Y627713D03*
X1413452Y641817D03*
X1418000Y696000D03*
Y701000D03*
Y717000D03*
X1410000D03*
X1418000Y724000D03*
Y729000D03*
X1404249Y735858D03*
X1418000Y740000D03*
Y745000D03*
X1407482Y750853D03*
X1418000Y761000D03*
X1406867Y783273D03*
X1409115Y773520D03*
X1414597Y792375D03*
X1406483Y811717D03*
X1413449Y823934D03*
X1405402Y819917D03*
X1405500Y844000D03*
Y836000D03*
Y860000D03*
Y880000D03*
Y868000D03*
X1413500Y876000D03*
X1417797Y879501D03*
X1405500Y888000D03*
Y896000D03*
X1417081D03*
X1413500Y892000D03*
Y884000D03*
X1405500Y904000D03*
X1404760Y915186D03*
X1419337Y942285D03*
X1419446Y977192D03*
X1412698Y997590D03*
X1412609Y1008766D03*
X1412759Y1016266D03*
X1416736Y1242194D03*
X1417711Y1301729D03*
X1422810Y90615D03*
X1427131Y99961D03*
X1434166Y325361D03*
X1434164Y339232D03*
X1434038Y334114D03*
X1435818Y352361D03*
X1434997Y442603D03*
X1427117Y443071D03*
X1432414Y459371D03*
X1427484Y462004D03*
X1427800Y528578D03*
X1421099Y546830D03*
X1435390Y544895D03*
X1435119Y590801D03*
X1434944Y597130D03*
X1420452Y628078D03*
X1430175Y627852D03*
X1425452Y633473D03*
X1433529Y660564D03*
X1426615Y674112D03*
X1429000Y685000D03*
X1425909Y691120D03*
X1433464Y692658D03*
X1433053Y701839D03*
X1431522Y708633D03*
X1434000Y712958D03*
X1430289Y734961D03*
X1429000Y729000D03*
X1434000Y751958D03*
X1433153Y745839D03*
X1435000Y765500D03*
X1434000Y756958D03*
X1435000Y770500D03*
Y802500D03*
Y814500D03*
Y809500D03*
X1434975Y830500D03*
X1435000Y825500D03*
Y846500D03*
X1427000D03*
X1435043Y874694D03*
X1435082Y869475D03*
X1423190Y905295D03*
X1429907Y936998D03*
X1424897Y936777D03*
X1435516Y936000D03*
X1430839Y965546D03*
X1435229Y1104335D03*
X1430384Y1106867D03*
X1420736Y1226194D03*
X1424736Y1238194D03*
X1432736Y1230194D03*
X1421964Y1502813D03*
X1436089Y92874D03*
X1451301Y148277D03*
X1451762Y177616D03*
X1446199Y188727D03*
X1443321Y208695D03*
X1442956Y226141D03*
X1436449Y223661D03*
X1451785Y265896D03*
X1446698Y265701D03*
X1448333Y281716D03*
X1449060Y329861D03*
Y320861D03*
X1438829Y329861D03*
X1437064Y320861D03*
X1448500Y340575D03*
X1439712Y336673D03*
X1440420Y346833D03*
X1441180Y354909D03*
X1448572Y349441D03*
X1443041Y363648D03*
X1442633Y371502D03*
X1440523Y382747D03*
X1436930Y461818D03*
X1439462Y529929D03*
X1449393Y566797D03*
X1449993Y578405D03*
X1443775Y596089D03*
X1448994Y596782D03*
X1437770Y628242D03*
X1437738Y686992D03*
X1451976Y693844D03*
X1437533Y704398D03*
Y699280D03*
X1438930Y716363D03*
X1446860Y730735D03*
X1437738Y730992D03*
X1437533Y743280D03*
Y748398D03*
X1447289Y776461D03*
X1446000Y770500D03*
X1451000Y793458D03*
Y798458D03*
X1450253Y787339D03*
X1447000Y810500D03*
Y818500D03*
X1448000Y834500D03*
X1449000Y844500D03*
X1439031Y957683D03*
X1441088Y976409D03*
X1440700Y981763D03*
X1440869Y1010256D03*
X1443769Y1562173D03*
X1457347Y31518D03*
X1457829Y26425D03*
X1461905Y100625D03*
X1454924Y97475D03*
X1462484Y141247D03*
X1466971Y143518D03*
X1453921Y143740D03*
X1466071Y152373D03*
X1452343Y172190D03*
X1464158Y192490D03*
X1456801Y266114D03*
X1461160Y281307D03*
X1454274Y281982D03*
X1455079Y290755D03*
X1463145Y391579D03*
X1455419Y578986D03*
X1454944Y596729D03*
X1461474Y655807D03*
X1468372Y673812D03*
X1454504Y777575D03*
X1454533Y784780D03*
X1454738Y772492D03*
X1454533Y789898D03*
X1453102Y821102D03*
X1454541Y831339D03*
X1453102Y826500D03*
X1452619Y836457D03*
X1461113Y871389D03*
X1462500Y905295D03*
X1458202Y960288D03*
X1457937Y966712D03*
X1467096Y988813D03*
X1458892Y1007522D03*
X1465658Y1006648D03*
X1463025Y1018307D03*
X1459267Y1013678D03*
X1456280Y1023405D03*
X1459683Y1028377D03*
X1474746Y60513D03*
X1474874Y85731D03*
X1483287Y86012D03*
X1479380Y94279D03*
X1470567Y103621D03*
X1484567Y110784D03*
X1479058Y124283D03*
X1484124Y124879D03*
X1469913Y183834D03*
X1470023Y178560D03*
X1470086Y172665D03*
X1469433Y190185D03*
X1478800Y196665D03*
X1470203Y200864D03*
X1470292Y212455D03*
X1470226Y207037D03*
X1475101Y228631D03*
X1475264Y680933D03*
X1476716Y704398D03*
X1479500Y689630D03*
Y697630D03*
X1479759Y720885D03*
X1469957Y706957D03*
X1479794Y709388D03*
X1472000Y727500D03*
X1480000Y731500D03*
X1476716Y748398D03*
X1480000Y739500D03*
X1471006Y744818D03*
X1470801Y739280D03*
X1479665Y754555D03*
X1474883Y868206D03*
X1473387Y897425D03*
X1482195Y885807D03*
X1480144Y946880D03*
X1480414Y952214D03*
X1479196Y970000D03*
X1480414Y975064D03*
X1475096Y988813D03*
X1483096D03*
X1482535Y1024254D03*
X1468869Y1018469D03*
X1471854Y1035088D03*
X1474384Y1165091D03*
X1480675Y1202103D03*
X1483308Y1214372D03*
X1479063Y1218169D03*
X1489556Y17645D03*
X1489829Y29424D03*
X1490563Y23043D03*
X1490842Y102249D03*
X1500210Y97667D03*
X1489567Y110784D03*
X1494127Y125107D03*
X1489146Y124663D03*
X1496641Y148717D03*
X1490490Y138838D03*
X1491942Y195176D03*
X1488761Y201683D03*
X1496221Y228646D03*
X1491828Y244571D03*
X1489208Y249108D03*
X1499171Y256394D03*
X1486860Y327200D03*
X1500659Y330024D03*
X1495605Y322700D03*
X1487318Y318200D03*
X1500386Y344642D03*
X1486913Y340327D03*
X1495689Y332534D03*
X1495521Y340700D03*
Y349681D03*
X1495925Y358700D03*
X1499839Y354001D03*
X1486890Y368576D03*
X1488731Y739500D03*
X1496629Y765000D03*
X1493301Y776911D03*
X1496814Y773000D03*
X1497000Y781000D03*
X1499633Y787794D03*
X1493716Y789898D03*
X1495170Y796670D03*
X1487050Y809413D03*
X1496845Y809000D03*
X1496806Y817000D03*
X1486386Y825296D03*
X1493038Y833898D03*
X1495240Y825000D03*
X1494954Y895264D03*
X1484824Y927324D03*
X1485500Y932500D03*
X1495500Y972500D03*
X1489500D03*
X1491096Y988813D03*
X1499096D03*
X1490235Y1004816D03*
X1487266Y1002046D03*
X1495339Y1021954D03*
X1486030Y1016827D03*
X1491877D03*
X1496185Y1102091D03*
Y1114691D03*
Y1127291D03*
Y1139891D03*
Y1152491D03*
Y1165091D03*
Y1177691D03*
X1489793Y1207737D03*
X1497693Y1230407D03*
X1508670Y103411D03*
X1509064Y97667D03*
X1502741Y143762D03*
X1506207Y199248D03*
X1509807Y230117D03*
X1500962Y230556D03*
X1505217Y227824D03*
X1501000Y317500D03*
X1501684Y336561D03*
X1516838Y347422D03*
X1515909Y354601D03*
X1516636Y458711D03*
X1502158Y899479D03*
X1504208Y909740D03*
X1509274Y921226D03*
X1509500Y937000D03*
Y944138D03*
X1516500Y947500D03*
X1501812Y938397D03*
X1509500Y950500D03*
X1507096Y988813D03*
X1515096D03*
X1513286Y1012354D03*
X1507831Y1009354D03*
X1513286Y1024954D03*
X1507831Y1021954D03*
X1501640Y1105091D03*
Y1117691D03*
Y1130291D03*
Y1142891D03*
Y1155491D03*
Y1168091D03*
Y1180691D03*
X1508356Y1220068D03*
X1506807Y1234921D03*
X1507058Y1229402D03*
X1525172Y90615D03*
X1519860Y90650D03*
X1529493Y99961D03*
X1519321Y378600D03*
X1519185Y615600D03*
X1520729Y634190D03*
X1525022Y909558D03*
X1521500Y947500D03*
X1528500Y947612D03*
X1531096Y988813D03*
X1523096D03*
X1527096Y997860D03*
X1526810Y1025090D03*
X1522904Y1021256D03*
X1521939Y1040818D03*
X1522099Y1035521D03*
X1531993Y1056453D03*
X1531961Y1050849D03*
X1524953Y1051037D03*
X1538451Y92874D03*
X1548561Y188727D03*
X1545683Y208695D03*
X1538811Y223661D03*
X1545318Y226141D03*
X1549060Y265701D03*
X1545583Y316363D03*
X1539140Y320863D03*
X1545636Y325363D03*
X1542797Y329863D03*
X1545846Y334363D03*
X1544951Y343363D03*
X1545434Y352363D03*
X1548080Y910757D03*
X1547644Y903060D03*
X1536909Y1151870D03*
Y1159350D03*
X1540649Y1155610D03*
X1564267Y100625D03*
X1557286Y97475D03*
X1564846Y141247D03*
X1556283Y143740D03*
X1553663Y148277D03*
X1554705Y172190D03*
X1554124Y177616D03*
X1559163Y266114D03*
X1554147Y265896D03*
X1563522Y281307D03*
X1556636Y281982D03*
X1550695Y281716D03*
X1557441Y290755D03*
X1550931Y305158D03*
X1553534Y327337D03*
X1553597Y336601D03*
X1551175Y347283D03*
X1556588Y545528D03*
X1564670Y650122D03*
X1565132Y668153D03*
Y677843D03*
X1577108Y60513D03*
X1577236Y85731D03*
X1581742Y94279D03*
X1572929Y103621D03*
X1581420Y124283D03*
X1569333Y143518D03*
X1568433Y152373D03*
X1572275Y183834D03*
X1572385Y178560D03*
X1572448Y172665D03*
X1571795Y190185D03*
X1566520Y192490D03*
X1572565Y200864D03*
X1572654Y212455D03*
X1572588Y207037D03*
X1581194Y208864D03*
X1577463Y228631D03*
X1578420Y338309D03*
X1574775Y344127D03*
X1575935Y382109D03*
X1577862Y554121D03*
X1579760Y595500D03*
X1574760Y606929D03*
X1579260Y604567D03*
X1574720Y618400D03*
X1575001Y612592D03*
X1580418Y610072D03*
X1580354Y616317D03*
X1577077Y631712D03*
X1571888Y649380D03*
X1585649Y86012D03*
X1593204Y102249D03*
X1586929Y110784D03*
X1591929D03*
X1596489Y125107D03*
X1586486Y124879D03*
X1591508Y124663D03*
X1592852Y138838D03*
X1594304Y195176D03*
X1591123Y201683D03*
X1594190Y244571D03*
X1591570Y249108D03*
X1595069Y337361D03*
X1595109Y342663D03*
X1594466Y350984D03*
X1594760Y568000D03*
X1596790Y1442557D03*
X1596038Y1492000D03*
X1590748Y1523377D03*
X1602572Y97667D03*
X1611032Y103411D03*
X1611426Y97667D03*
X1605103Y143762D03*
X1599003Y148717D03*
X1608569Y199248D03*
X1603324Y230556D03*
X1607579Y227824D03*
X1612169Y230117D03*
X1598583Y228646D03*
X1604677Y253198D03*
X1599527Y404718D03*
Y412718D03*
X1614338Y636842D03*
X1606190Y803774D03*
X1606709Y819165D03*
X1600008Y1488492D03*
X1601500Y1514500D03*
X1608500Y1506000D03*
X1613790Y1531334D03*
X1609348Y1527334D03*
X1613790Y1523334D03*
X1604000Y1519000D03*
X1600732Y1539334D03*
X1609348Y1535334D03*
X1598574Y1543373D03*
X1622222Y90650D03*
X1627534Y90615D03*
X1623955Y442956D03*
X1620385Y465874D03*
X1618538Y618288D03*
X1617843Y665140D03*
X1640813Y92874D03*
X1631855Y99961D03*
X1641173Y223661D03*
X1636271Y403307D03*
X1632439Y452265D03*
X1633225Y458455D03*
X1635185Y446595D03*
X1644552Y871353D03*
X1635176Y886761D03*
X1644718Y909263D03*
X1635000Y919263D03*
X1644325Y942120D03*
X1637771Y952120D03*
X1641634Y1215452D03*
X1640581Y1551907D03*
X1659648Y97475D03*
X1658645Y143740D03*
X1656025Y148277D03*
X1656486Y177616D03*
X1657067Y172190D03*
X1650923Y188727D03*
X1648045Y208695D03*
X1647680Y226141D03*
X1656509Y265896D03*
X1661525Y266114D03*
X1651422Y265701D03*
X1653057Y281716D03*
X1658998Y281982D03*
X1659803Y290755D03*
X1650044Y435158D03*
X1649789Y440489D03*
X1653490Y458572D03*
X1647402Y881460D03*
X1647565Y981432D03*
X1679470Y60513D03*
X1679598Y85731D03*
X1675291Y103621D03*
X1666629Y100625D03*
X1667208Y141247D03*
X1671695Y143518D03*
X1670795Y152373D03*
X1674637Y183834D03*
X1674810Y172665D03*
X1674747Y178560D03*
X1674157Y190185D03*
X1668882Y192490D03*
X1674927Y200864D03*
X1674950Y207037D03*
X1675016Y212455D03*
X1664082Y231021D03*
X1665884Y281307D03*
X1668979Y339559D03*
X1670260Y377912D03*
X1669260Y391496D03*
X1663618Y393858D03*
X1666959Y382047D03*
X1670260Y386500D03*
X1669260Y409000D03*
X1665260Y398583D03*
X1670348Y397912D03*
X1667260Y403500D03*
X1688011Y86012D03*
X1695566Y102249D03*
X1684104Y94279D03*
X1694291Y110784D03*
X1689291D03*
X1683782Y124283D03*
X1693870Y124663D03*
X1688848Y124879D03*
X1695214Y138838D03*
X1693485Y201683D03*
X1683556Y208864D03*
X1679825Y228631D03*
X1693932Y249108D03*
X1686339Y314890D03*
X1683523Y324518D03*
X1687424Y347937D03*
X1692676Y348015D03*
X1691182Y357016D03*
X1704934Y97667D03*
X1698851Y125107D03*
X1707465Y143762D03*
X1701365Y148717D03*
X1696666Y195176D03*
X1710931Y199248D03*
X1705686Y230556D03*
X1709941Y228747D03*
X1700945Y228646D03*
X1696552Y244571D03*
X1703895Y256394D03*
X1698716Y550065D03*
X1708015Y1142700D03*
X1711333Y1146609D03*
X1706450Y1173065D03*
X1713394Y103411D03*
X1713788Y97667D03*
X1724584Y90650D03*
X1714531Y230117D03*
X1720571Y385644D03*
X1725746Y385123D03*
X1718318Y399918D03*
X1725154Y406060D03*
X1724627Y459330D03*
X1724580Y454214D03*
X1724923Y449045D03*
X1723805Y1142666D03*
X1725680Y1157544D03*
X1724191Y1167768D03*
X1713239Y1176038D03*
X1712526Y1171950D03*
X1728343Y1185205D03*
X1719692Y1187215D03*
X1719385Y1180175D03*
X1712715Y1188500D03*
X1712966Y1229841D03*
X1743175Y92874D03*
X1729896Y90615D03*
X1734217Y99961D03*
X1743535Y223661D03*
X1744524Y379429D03*
X1730746Y385123D03*
X1737746D03*
X1741420Y391569D03*
X1739847Y409016D03*
X1738824Y456034D03*
Y461034D03*
X1739917Y1146937D03*
X1732137Y1157404D03*
X1729210Y1167768D03*
X1733052Y1187310D03*
X1737689Y1185238D03*
X1737482Y1180235D03*
X1731619Y1210089D03*
X1758848Y177616D03*
X1759429Y172190D03*
X1753285Y188727D03*
X1750407Y208695D03*
X1750042Y226141D03*
X1753784Y265701D03*
X1758871Y265896D03*
X1755419Y281716D03*
X1752497Y371076D03*
X1750135Y379088D03*
X1755433Y379028D03*
X1750187Y406739D03*
X1756894Y472020D03*
X1756553Y466409D03*
X1756954Y477318D03*
X1756391Y487382D03*
X1745824Y987058D03*
X1759569Y1021944D03*
X1759947Y1599029D03*
X1750685Y1618504D03*
X1762010Y97475D03*
X1768991Y100625D03*
X1776999Y183834D03*
X1771244Y192490D03*
X1776519Y190185D03*
X1763887Y266114D03*
X1768246Y281307D03*
X1761360Y281982D03*
X1762165Y290755D03*
X1765497Y379591D03*
X1767633Y407104D03*
X1765093Y423944D03*
X1765153Y413611D03*
X1764906Y474382D03*
X1776561Y467560D03*
X1777061Y475560D03*
X1768844Y1023694D03*
X1772188Y1428369D03*
X1766313Y1580198D03*
X1761072Y1590719D03*
X1765040Y1599511D03*
X1764422Y1640303D03*
X1762041Y1631511D03*
X1768422Y1632245D03*
X1773820Y1631238D03*
X1781832Y60513D03*
X1781960Y85731D03*
X1790712Y81713D03*
X1786466Y94279D03*
X1777172Y172665D03*
X1777109Y178560D03*
X1777289Y200864D03*
X1777378Y212455D03*
X1777312Y207037D03*
X1785918Y208864D03*
X1781559Y219379D03*
X1782187Y228631D03*
X1786170Y448931D03*
X1792527Y452799D03*
X1790061Y474513D03*
X1779404Y826570D03*
X1781263Y964660D03*
X1786863Y985060D03*
X1779033Y1023432D03*
X1783278Y1208140D03*
X1791099Y1260421D03*
X1787745Y1437765D03*
X1777131Y1604357D03*
X1809095Y435101D03*
X1803700Y440101D03*
X1803530Y431112D03*
X1809358Y442114D03*
X1803335Y452718D03*
X1809346Y452601D03*
X1797907Y452987D03*
X1809338Y447121D03*
X1802363Y989660D03*
X1801961Y1081717D03*
X1795819Y1088553D03*
X1796607Y1200108D03*
X1806835Y1214668D03*
X1800489Y1220598D03*
X1807243Y1219955D03*
X1802670Y1210905D03*
X1805126Y1225745D03*
X1795374Y1444543D03*
X1802813Y1464015D03*
X1809078Y2165771D03*
X1806706Y2180760D03*
X1817439Y447101D03*
X1816756Y1089145D03*
Y1094145D03*
X1816235Y1083970D03*
X1810346Y1082250D03*
X1816756Y1101145D03*
X1810310Y1104819D03*
X1812130Y1205349D03*
X1814741Y1217093D03*
X1812202Y1432624D03*
X1812366Y2063809D03*
X1822066Y2054109D03*
X1812366D03*
X1813087Y2087512D03*
X1825427Y2104853D03*
X1817378Y2165771D03*
X1815006Y2180760D03*
X1841295Y2065122D03*
X1832995D03*
X1833649Y2057507D03*
X1830872Y2083503D03*
X1840875Y2083215D03*
X1837649Y2072324D03*
X1829349D03*
X1833727Y2104853D03*
X1835862Y2121040D03*
X1833506Y2185252D03*
X1852032Y2052576D03*
X1854559Y2077931D03*
X1851762Y2121040D03*
X1854796Y2170548D03*
X1846496D03*
X1855978Y2185118D03*
X1847678D03*
X1859032Y2052576D03*
X1870505Y2064156D03*
X1860338Y2071384D03*
X1874505Y2078973D03*
X1860234Y2157701D03*
X1867072Y2174962D03*
X1864547Y2185020D03*
X1890039Y2066092D03*
X1878805Y2064156D03*
X1886128Y2075919D03*
X1882805Y2078973D03*
X1876497Y2070684D03*
X1884535Y2155415D03*
X1882972Y2174962D03*
X1882111Y2179074D03*
X1874932Y2180585D03*
X1881852Y2196600D03*
X1886699Y2183170D03*
X1876697D03*
X1905939Y2066092D03*
X1893118Y2054585D03*
X1905944Y2055424D03*
X1898342Y2062143D03*
X1901295Y2072745D03*
X1892835Y2155415D03*
X1902872Y2178531D03*
X1894572D03*
X1893087Y2168011D03*
X1896403Y2185019D03*
X1917195Y2072745D03*
X1917550Y2158451D03*
X1909250D03*
X1922010Y2151829D03*
X1913710D03*
X1921855Y2172152D03*
X1936295Y2074343D03*
X1935195Y2155918D03*
X1936377Y2163810D03*
X1924735Y2178131D03*
X1936212Y2173508D03*
X1930155Y2172152D03*
X1931738Y2182647D03*
X1923438D03*
X1941040Y2070124D03*
X1951095Y2155918D03*
X1946077Y2163810D03*
X1969128Y2161283D03*
X1959428D03*
X1969128Y2151583D03*
X1959428D03*
X2785168Y865663D03*
Y965113D03*
G54D22*
X116731Y1066535D03*
Y1263386D03*
X352952Y1066535D03*
Y1263386D03*
X573818Y1066535D03*
Y1263386D03*
X810038Y1066535D03*
Y1263386D03*
X1030905Y1066535D03*
Y1263386D03*
X1267125Y1066535D03*
Y1263386D03*
X1487991Y1066535D03*
Y1263386D03*
X1724212Y1066535D03*
Y1263386D03*
X2785168Y103213D03*
G54D32*
X1236871Y1715189D03*
Y1744208D03*
X1236864Y1773377D03*
X1235371Y1802909D03*
X1250055Y1710189D03*
Y1720189D03*
Y1739208D03*
Y1749208D03*
X1250048Y1768377D03*
Y1778377D03*
X1248555Y1797909D03*
Y1807909D03*
X1734069Y1710189D03*
Y1720189D03*
Y1739208D03*
Y1749208D03*
X1734062Y1768377D03*
Y1778377D03*
X1734069Y1797909D03*
Y1807909D03*
X1747253Y1715189D03*
Y1744208D03*
X1747246Y1773377D03*
X1747253Y1802909D03*
X2785168Y567313D03*
G54D14*
X26789Y1373669D03*
X184851Y334492D03*
X235433Y1580079D03*
Y1606142D03*
Y1626339D03*
X581890Y1606142D03*
Y1580079D03*
Y1626339D03*
X1259055Y1580079D03*
Y1606142D03*
Y1626339D03*
X1605512Y1606142D03*
Y1580079D03*
Y1626339D03*
X1796847Y1517889D03*
X1809883Y120792D03*
X2785168Y169513D03*
Y202663D03*
G54D23*
X118543Y1462953D03*
X109882Y1463741D03*
Y1458622D03*
X118543Y1468071D03*
X109882Y1453504D03*
Y1458622D03*
Y1463741D03*
Y1479095D03*
Y1473977D03*
X118543Y1478308D03*
Y1483426D03*
X109882Y1468859D03*
Y1473977D03*
Y1479095D03*
X118543Y1498780D03*
Y1493662D03*
X109882Y1494449D03*
Y1489331D03*
Y1484213D03*
Y1489331D03*
Y1494449D03*
Y1509804D03*
Y1504685D03*
X118543Y1514134D03*
Y1509016D03*
X109882Y1499567D03*
Y1504685D03*
Y1509804D03*
Y1514922D03*
Y1560985D03*
X118543Y1565315D03*
X109882Y1555867D03*
Y1560985D03*
Y1576339D03*
Y1566103D03*
X118543Y1570434D03*
Y1580670D03*
X109882Y1581457D03*
Y1566103D03*
Y1571221D03*
Y1576339D03*
X118543Y1596024D03*
Y1585788D03*
X109882Y1591693D03*
Y1596811D03*
Y1581457D03*
Y1586575D03*
Y1591693D03*
Y1612166D03*
Y1607048D03*
X118543Y1611378D03*
Y1601142D03*
X109882Y1596811D03*
Y1601930D03*
Y1607048D03*
Y1612166D03*
X118543Y1616496D03*
X109882Y1617284D03*
Y1622402D03*
X135866Y1462953D03*
X127205Y1463741D03*
Y1458622D03*
X135866Y1468071D03*
X127205Y1453504D03*
Y1458622D03*
Y1463741D03*
X118543Y1452717D03*
Y1457835D03*
Y1462953D03*
X127205Y1479095D03*
Y1473977D03*
X135866Y1478308D03*
Y1483426D03*
X127205Y1468859D03*
Y1473977D03*
Y1479095D03*
X118543Y1468071D03*
Y1473189D03*
Y1478308D03*
X135866Y1498780D03*
Y1493662D03*
X127205Y1494449D03*
Y1489331D03*
Y1484213D03*
Y1489331D03*
Y1494449D03*
X118543Y1483426D03*
Y1488544D03*
Y1493662D03*
Y1498780D03*
X127205Y1509804D03*
Y1504685D03*
X135866Y1514134D03*
Y1509016D03*
X127205Y1499567D03*
Y1504685D03*
Y1509804D03*
Y1514922D03*
X118543Y1503898D03*
Y1509016D03*
Y1514134D03*
Y1519252D03*
X127205Y1560985D03*
X135866Y1565315D03*
X127205Y1555867D03*
Y1560985D03*
X118543Y1560197D03*
X127205Y1576339D03*
Y1566103D03*
X135866Y1570434D03*
Y1580670D03*
X127205Y1581457D03*
Y1566103D03*
Y1571221D03*
Y1576339D03*
X118543Y1565315D03*
Y1570434D03*
Y1575552D03*
X135866Y1596024D03*
Y1585788D03*
X127205Y1591693D03*
Y1596811D03*
Y1581457D03*
Y1586575D03*
Y1591693D03*
X118543Y1580670D03*
Y1585788D03*
Y1590906D03*
Y1596024D03*
X127205Y1612166D03*
Y1607048D03*
X135866Y1611378D03*
Y1601142D03*
X127205Y1596811D03*
Y1601930D03*
Y1607048D03*
Y1612166D03*
X118543Y1601142D03*
Y1606260D03*
Y1611378D03*
X135866Y1616496D03*
X127205Y1617284D03*
Y1622402D03*
X118543Y1616496D03*
Y1621615D03*
X144528Y1463741D03*
Y1458622D03*
Y1453504D03*
Y1458622D03*
Y1463741D03*
X135866Y1452717D03*
Y1457835D03*
Y1462953D03*
X144528Y1479095D03*
Y1473977D03*
Y1468859D03*
Y1473977D03*
Y1479095D03*
X135866Y1468071D03*
Y1473189D03*
Y1478308D03*
X144528Y1494449D03*
Y1489331D03*
Y1484213D03*
Y1489331D03*
Y1494449D03*
X135866Y1483426D03*
Y1488544D03*
Y1493662D03*
Y1498780D03*
X144528Y1509804D03*
Y1504685D03*
Y1499567D03*
Y1504685D03*
Y1509804D03*
Y1514922D03*
X135866Y1503898D03*
Y1509016D03*
Y1514134D03*
Y1519252D03*
X144528Y1560985D03*
Y1555867D03*
Y1560985D03*
X135866Y1560197D03*
X144528Y1576339D03*
Y1566103D03*
Y1581457D03*
Y1566103D03*
Y1571221D03*
Y1576339D03*
X135866Y1565315D03*
Y1570434D03*
Y1575552D03*
X144528Y1591693D03*
Y1596811D03*
Y1581457D03*
Y1586575D03*
Y1591693D03*
X135866Y1580670D03*
Y1585788D03*
Y1590906D03*
Y1596024D03*
X144528Y1612166D03*
Y1607048D03*
Y1596811D03*
Y1601930D03*
Y1607048D03*
Y1612166D03*
X135866Y1601142D03*
Y1606260D03*
Y1611378D03*
X144528Y1617284D03*
Y1622402D03*
X135866Y1616496D03*
Y1621615D03*
X153189Y1462953D03*
X161850Y1463741D03*
Y1458622D03*
X153189Y1468071D03*
X161850Y1453504D03*
Y1458622D03*
Y1463741D03*
X153189Y1452717D03*
Y1457835D03*
Y1462953D03*
Y1478308D03*
X161850Y1479095D03*
Y1473977D03*
X153189Y1483426D03*
X161850Y1468859D03*
Y1473977D03*
Y1479095D03*
X153189Y1468071D03*
Y1473189D03*
Y1478308D03*
Y1498780D03*
Y1493662D03*
X161850Y1494449D03*
Y1489331D03*
Y1484213D03*
Y1489331D03*
Y1494449D03*
X153189Y1483426D03*
Y1488544D03*
Y1493662D03*
Y1498780D03*
Y1514134D03*
Y1509016D03*
X161850Y1509804D03*
Y1504685D03*
Y1499567D03*
Y1504685D03*
Y1509804D03*
Y1514922D03*
X153189Y1503898D03*
Y1509016D03*
Y1514134D03*
Y1519252D03*
X161850Y1560985D03*
X153189Y1565315D03*
X161850Y1555867D03*
Y1560985D03*
X153189Y1560197D03*
Y1570434D03*
X161850Y1576339D03*
Y1566103D03*
X153189Y1580670D03*
X161850Y1581457D03*
Y1566103D03*
Y1571221D03*
Y1576339D03*
X153189Y1565315D03*
Y1570434D03*
Y1575552D03*
Y1596024D03*
Y1585788D03*
X161850Y1591693D03*
Y1596811D03*
Y1581457D03*
Y1586575D03*
Y1591693D03*
X153189Y1580670D03*
Y1585788D03*
Y1590906D03*
Y1596024D03*
Y1611378D03*
Y1601142D03*
X161850Y1612166D03*
Y1607048D03*
Y1596811D03*
Y1601930D03*
Y1607048D03*
Y1612166D03*
X153189Y1601142D03*
Y1606260D03*
Y1611378D03*
Y1616496D03*
X161850Y1617284D03*
Y1622402D03*
X153189Y1616496D03*
Y1621615D03*
X170512Y1462953D03*
X179173Y1463741D03*
Y1458622D03*
X170512Y1468071D03*
X179173Y1453504D03*
Y1458622D03*
Y1463741D03*
X170512Y1452717D03*
Y1457835D03*
Y1462953D03*
Y1478308D03*
X179173Y1479095D03*
Y1473977D03*
X170512Y1483426D03*
X179173Y1468859D03*
Y1473977D03*
Y1479095D03*
X170512Y1468071D03*
Y1473189D03*
Y1478308D03*
Y1498780D03*
Y1493662D03*
X179173Y1484213D03*
Y1489331D03*
Y1494449D03*
X170512Y1483426D03*
Y1488544D03*
Y1493662D03*
Y1498780D03*
Y1514134D03*
Y1509016D03*
X179173Y1499567D03*
Y1504685D03*
Y1509804D03*
Y1514922D03*
X170512Y1503898D03*
Y1509016D03*
Y1514134D03*
Y1519252D03*
Y1565315D03*
X179173Y1555867D03*
Y1560985D03*
X170512Y1560197D03*
Y1570434D03*
Y1580670D03*
X179173Y1566103D03*
Y1571221D03*
Y1576339D03*
X170512Y1565315D03*
Y1570434D03*
Y1575552D03*
Y1596024D03*
Y1585788D03*
X179173Y1581457D03*
Y1586575D03*
Y1591693D03*
X170512Y1580670D03*
Y1585788D03*
Y1590906D03*
Y1596024D03*
Y1611378D03*
Y1601142D03*
X179173Y1596811D03*
Y1601930D03*
Y1607048D03*
Y1612166D03*
X170512Y1601142D03*
Y1606260D03*
Y1611378D03*
Y1616496D03*
X179173Y1617284D03*
Y1622402D03*
X170512Y1616496D03*
Y1621615D03*
X187835Y1462953D03*
Y1468071D03*
Y1452717D03*
Y1457835D03*
Y1462953D03*
Y1478308D03*
Y1483426D03*
Y1468071D03*
Y1473189D03*
Y1478308D03*
Y1483426D03*
Y1488544D03*
Y1493662D03*
Y1498780D03*
Y1503898D03*
Y1509016D03*
Y1514134D03*
Y1519252D03*
Y1560197D03*
Y1565315D03*
Y1570434D03*
Y1575552D03*
Y1596024D03*
Y1580670D03*
Y1585788D03*
Y1590906D03*
Y1596024D03*
Y1611378D03*
Y1601142D03*
D03*
Y1606260D03*
Y1611378D03*
Y1616496D03*
D03*
Y1621615D03*
X283110Y1463741D03*
X291771Y1462953D03*
X283110Y1458622D03*
X291771Y1468071D03*
Y1452717D03*
X283110Y1453504D03*
X291771Y1457835D03*
X283110Y1458622D03*
X291771Y1462953D03*
X283110Y1463741D03*
Y1479095D03*
X291771Y1478308D03*
X283110Y1473977D03*
X291771Y1483426D03*
Y1468071D03*
X283110Y1468859D03*
X291771Y1473189D03*
X283110Y1473977D03*
X291771Y1478308D03*
X283110Y1479095D03*
X291771Y1498780D03*
X283110Y1494449D03*
X291771Y1493662D03*
X283110Y1489331D03*
X291771Y1483426D03*
X283110Y1484213D03*
X291771Y1488544D03*
X283110Y1489331D03*
X291771Y1493662D03*
X283110Y1494449D03*
X291771Y1498780D03*
Y1514134D03*
X283110Y1509804D03*
X291771Y1509016D03*
X283110Y1504685D03*
Y1499567D03*
X291771Y1503898D03*
X283110Y1504685D03*
X291771Y1509016D03*
X283110Y1509804D03*
Y1514922D03*
X291771Y1514134D03*
Y1519252D03*
X283110Y1560985D03*
X291771Y1565315D03*
X283110Y1555867D03*
X291771Y1560197D03*
X283110Y1560985D03*
Y1576339D03*
X291771Y1570434D03*
X283110Y1566103D03*
Y1581457D03*
X291771Y1580670D03*
Y1565315D03*
X283110Y1566103D03*
X291771Y1570434D03*
X283110Y1571221D03*
X291771Y1575552D03*
X283110Y1576339D03*
X291771Y1596024D03*
X283110Y1591693D03*
X291771Y1585788D03*
X283110Y1596811D03*
X291771Y1580670D03*
X283110Y1581457D03*
X291771Y1585788D03*
X283110Y1586575D03*
X291771Y1590906D03*
X283110Y1591693D03*
X291771Y1596024D03*
X283110Y1612166D03*
X291771Y1611378D03*
X283110Y1607048D03*
X291771Y1601142D03*
X283110Y1596811D03*
X291771Y1601142D03*
X283110Y1601930D03*
X291771Y1606260D03*
X283110Y1607048D03*
X291771Y1611378D03*
X283110Y1612166D03*
X291771Y1616496D03*
D03*
X283110Y1617284D03*
X291771Y1621615D03*
X283110Y1622402D03*
X300433Y1463741D03*
X309094Y1462953D03*
X300433Y1458622D03*
X309094Y1468071D03*
Y1452717D03*
X300433Y1453504D03*
X309094Y1457835D03*
X300433Y1458622D03*
X309094Y1462953D03*
X300433Y1463741D03*
Y1479095D03*
X309094Y1478308D03*
X300433Y1473977D03*
X309094Y1483426D03*
Y1468071D03*
X300433Y1468859D03*
X309094Y1473189D03*
X300433Y1473977D03*
X309094Y1478308D03*
X300433Y1479095D03*
X309094Y1498780D03*
X300433Y1494449D03*
X309094Y1493662D03*
X300433Y1489331D03*
X309094Y1483426D03*
X300433Y1484213D03*
X309094Y1488544D03*
X300433Y1489331D03*
X309094Y1493662D03*
X300433Y1494449D03*
X309094Y1498780D03*
Y1514134D03*
X300433Y1509804D03*
X309094Y1509016D03*
X300433Y1504685D03*
Y1499567D03*
X309094Y1503898D03*
X300433Y1504685D03*
X309094Y1509016D03*
X300433Y1509804D03*
X309094Y1514134D03*
X300433Y1514922D03*
X309094Y1519252D03*
X300433Y1560985D03*
X309094Y1565315D03*
X300433Y1555867D03*
Y1560985D03*
X309094Y1560197D03*
X300433Y1576339D03*
X309094Y1570434D03*
X300433Y1566103D03*
Y1581457D03*
X309094Y1580670D03*
Y1565315D03*
X300433Y1566103D03*
X309094Y1570434D03*
X300433Y1571221D03*
X309094Y1575552D03*
X300433Y1576339D03*
X309094Y1596024D03*
X300433Y1591693D03*
X309094Y1585788D03*
X300433Y1596811D03*
X309094Y1580670D03*
X300433Y1581457D03*
X309094Y1585788D03*
X300433Y1586575D03*
X309094Y1590906D03*
X300433Y1591693D03*
X309094Y1596024D03*
X300433Y1612166D03*
X309094Y1611378D03*
X300433Y1607048D03*
X309094Y1601142D03*
X300433Y1596811D03*
X309094Y1601142D03*
X300433Y1601930D03*
X309094Y1606260D03*
X300433Y1607048D03*
X309094Y1611378D03*
X300433Y1612166D03*
X309094Y1616496D03*
D03*
X300433Y1617284D03*
X309094Y1621615D03*
X300433Y1622402D03*
X326417Y1462953D03*
X317756Y1463741D03*
Y1458622D03*
X326417Y1468071D03*
Y1452717D03*
X317756Y1453504D03*
X326417Y1457835D03*
X317756Y1458622D03*
X326417Y1462953D03*
X317756Y1463741D03*
X326417Y1478308D03*
X317756Y1473977D03*
Y1479095D03*
X326417Y1483426D03*
Y1468071D03*
X317756Y1468859D03*
X326417Y1473189D03*
X317756Y1473977D03*
X326417Y1478308D03*
X317756Y1479095D03*
X326417Y1498780D03*
Y1493662D03*
X317756Y1494449D03*
Y1489331D03*
X326417Y1483426D03*
X317756Y1484213D03*
X326417Y1488544D03*
X317756Y1489331D03*
X326417Y1493662D03*
X317756Y1494449D03*
X326417Y1498780D03*
Y1514134D03*
X317756Y1509804D03*
X326417Y1509016D03*
X317756Y1504685D03*
Y1499567D03*
X326417Y1503898D03*
X317756Y1504685D03*
X326417Y1509016D03*
X317756Y1509804D03*
X326417Y1514134D03*
X317756Y1514922D03*
X326417Y1519252D03*
X317756Y1560985D03*
X326417Y1565315D03*
X317756Y1555867D03*
Y1560985D03*
X326417Y1560197D03*
X317756Y1576339D03*
X326417Y1570434D03*
X317756Y1566103D03*
X326417Y1580670D03*
X317756Y1581457D03*
X326417Y1565315D03*
X317756Y1566103D03*
X326417Y1570434D03*
X317756Y1571221D03*
X326417Y1575552D03*
X317756Y1576339D03*
X326417Y1596024D03*
Y1585788D03*
X317756Y1591693D03*
Y1596811D03*
X326417Y1580670D03*
X317756Y1581457D03*
X326417Y1585788D03*
X317756Y1586575D03*
X326417Y1590906D03*
X317756Y1591693D03*
X326417Y1596024D03*
X317756Y1612166D03*
X326417Y1611378D03*
X317756Y1607048D03*
X326417Y1601142D03*
X317756Y1596811D03*
X326417Y1601142D03*
X317756Y1601930D03*
X326417Y1606260D03*
X317756Y1607048D03*
X326417Y1611378D03*
X317756Y1612166D03*
X326417Y1616496D03*
D03*
X317756Y1617284D03*
X326417Y1621615D03*
X317756Y1622402D03*
X343740Y1462953D03*
X335078Y1458622D03*
Y1463741D03*
X343740Y1468071D03*
Y1452717D03*
X335078Y1453504D03*
X343740Y1457835D03*
X335078Y1458622D03*
X343740Y1462953D03*
X335078Y1463741D03*
Y1479095D03*
X343740Y1478308D03*
X335078Y1473977D03*
X343740Y1483426D03*
Y1468071D03*
X335078Y1468859D03*
X343740Y1473189D03*
X335078Y1473977D03*
X343740Y1478308D03*
X335078Y1479095D03*
X343740Y1498780D03*
Y1493662D03*
X335078Y1489331D03*
Y1494449D03*
X343740Y1483426D03*
X335078Y1484213D03*
X343740Y1488544D03*
X335078Y1489331D03*
X343740Y1493662D03*
X335078Y1494449D03*
X343740Y1498780D03*
Y1514134D03*
X335078Y1509804D03*
X343740Y1509016D03*
X335078Y1504685D03*
Y1499567D03*
X343740Y1503898D03*
X335078Y1504685D03*
X343740Y1509016D03*
X335078Y1509804D03*
X343740Y1514134D03*
X335078Y1514922D03*
X343740Y1519252D03*
X335078Y1560985D03*
X343740Y1565315D03*
X335078Y1555867D03*
Y1560985D03*
X343740Y1560197D03*
Y1570434D03*
X335078Y1566103D03*
Y1576339D03*
X343740Y1580670D03*
X335078Y1581457D03*
X343740Y1565315D03*
X335078Y1566103D03*
X343740Y1570434D03*
X335078Y1571221D03*
X343740Y1575552D03*
X335078Y1576339D03*
X343740Y1596024D03*
Y1585788D03*
X335078Y1591693D03*
Y1596811D03*
X343740Y1580670D03*
X335078Y1581457D03*
X343740Y1585788D03*
X335078Y1586575D03*
X343740Y1590906D03*
X335078Y1591693D03*
X343740Y1596024D03*
X335078Y1612166D03*
X343740Y1611378D03*
X335078Y1607048D03*
X343740Y1601142D03*
X335078Y1596811D03*
X343740Y1601142D03*
X335078Y1601930D03*
X343740Y1606260D03*
X335078Y1607048D03*
X343740Y1611378D03*
X335078Y1612166D03*
X343740Y1616496D03*
D03*
X335078Y1617284D03*
X343740Y1621615D03*
X335078Y1622402D03*
X352401Y1453504D03*
X361063Y1452717D03*
X352401Y1458622D03*
X361063Y1457835D03*
X352401Y1463741D03*
X361063Y1462953D03*
X352401Y1468859D03*
X361063Y1468071D03*
X352401Y1473977D03*
X361063Y1473189D03*
X352401Y1479095D03*
X361063Y1478308D03*
X352401Y1484213D03*
X361063Y1483426D03*
X352401Y1489331D03*
X361063Y1488544D03*
X352401Y1494449D03*
X361063Y1493662D03*
Y1498780D03*
X352401Y1499567D03*
Y1504685D03*
X361063Y1503898D03*
X352401Y1509804D03*
X361063Y1509016D03*
X352401Y1514922D03*
X361063Y1514134D03*
Y1519252D03*
X352401Y1555867D03*
Y1560985D03*
X361063Y1560197D03*
X352401Y1566103D03*
X361063Y1565315D03*
X352401Y1571221D03*
X361063Y1570434D03*
X352401Y1576339D03*
X361063Y1575552D03*
Y1596024D03*
X352401Y1581457D03*
X361063Y1580670D03*
X352401Y1586575D03*
X361063Y1585788D03*
X352401Y1591693D03*
X361063Y1590906D03*
Y1596024D03*
Y1611378D03*
Y1601142D03*
X352401Y1596811D03*
Y1601930D03*
X361063Y1601142D03*
X352401Y1607048D03*
X361063Y1606260D03*
X352401Y1612166D03*
X361063Y1611378D03*
Y1616496D03*
X352401Y1617284D03*
X361063Y1616496D03*
X352401Y1622402D03*
X361063Y1621615D03*
X456339Y1463741D03*
Y1458622D03*
Y1453504D03*
Y1458622D03*
Y1463741D03*
Y1479095D03*
Y1473977D03*
Y1468859D03*
Y1473977D03*
Y1479095D03*
Y1494449D03*
Y1489331D03*
Y1484213D03*
Y1489331D03*
Y1494449D03*
Y1509804D03*
Y1504685D03*
Y1499567D03*
Y1504685D03*
Y1509804D03*
Y1514922D03*
Y1560985D03*
Y1555867D03*
Y1560985D03*
Y1576339D03*
Y1566103D03*
Y1581457D03*
Y1566103D03*
Y1571221D03*
Y1576339D03*
Y1591693D03*
Y1596811D03*
Y1581457D03*
Y1586575D03*
Y1591693D03*
Y1612166D03*
Y1607048D03*
Y1596811D03*
Y1601930D03*
Y1607048D03*
Y1612166D03*
Y1617284D03*
Y1622402D03*
X473662Y1463741D03*
Y1458622D03*
X465000Y1462953D03*
Y1468071D03*
X473662Y1453504D03*
Y1458622D03*
Y1463741D03*
X465000Y1452717D03*
Y1457835D03*
Y1462953D03*
X473662Y1479095D03*
Y1473977D03*
X465000Y1478308D03*
Y1483426D03*
X473662Y1468859D03*
Y1473977D03*
Y1479095D03*
X465000Y1468071D03*
Y1473189D03*
Y1478308D03*
X473662Y1494449D03*
Y1489331D03*
X465000Y1498780D03*
Y1493662D03*
X473662Y1484213D03*
Y1489331D03*
Y1494449D03*
X465000Y1483426D03*
Y1488544D03*
Y1493662D03*
Y1498780D03*
X473662Y1509804D03*
Y1504685D03*
X465000Y1514134D03*
Y1509016D03*
X473662Y1499567D03*
Y1504685D03*
Y1509804D03*
Y1514922D03*
X465000Y1503898D03*
Y1509016D03*
Y1514134D03*
Y1519252D03*
X473662Y1560985D03*
X465000Y1565315D03*
X473662Y1555867D03*
Y1560985D03*
X465000Y1560197D03*
X473662Y1576339D03*
Y1566103D03*
X465000Y1570434D03*
X473662Y1581457D03*
X465000Y1580670D03*
X473662Y1566103D03*
Y1571221D03*
Y1576339D03*
X465000Y1565315D03*
Y1570434D03*
Y1575552D03*
X473662Y1591693D03*
X465000Y1596024D03*
Y1585788D03*
X473662Y1596811D03*
Y1581457D03*
Y1586575D03*
Y1591693D03*
X465000Y1580670D03*
Y1585788D03*
Y1590906D03*
Y1596024D03*
Y1611378D03*
Y1601142D03*
X473662Y1612166D03*
Y1607048D03*
Y1596811D03*
Y1601930D03*
Y1607048D03*
Y1612166D03*
X465000Y1601142D03*
Y1606260D03*
Y1611378D03*
Y1616496D03*
X473662Y1617284D03*
Y1622402D03*
X465000Y1616496D03*
Y1621615D03*
X490985Y1463741D03*
Y1458622D03*
X482323Y1462953D03*
Y1468071D03*
X490985Y1453504D03*
Y1458622D03*
Y1463741D03*
X482323Y1452717D03*
Y1457835D03*
Y1462953D03*
Y1478308D03*
X490985Y1479095D03*
Y1473977D03*
X482323Y1483426D03*
X490985Y1468859D03*
Y1473977D03*
Y1479095D03*
X482323Y1468071D03*
Y1473189D03*
Y1478308D03*
X490985Y1494449D03*
Y1489331D03*
X482323Y1498780D03*
Y1493662D03*
X490985Y1484213D03*
Y1489331D03*
Y1494449D03*
X482323Y1483426D03*
Y1488544D03*
Y1493662D03*
Y1498780D03*
Y1514134D03*
Y1509016D03*
X490985Y1509804D03*
Y1504685D03*
Y1499567D03*
Y1504685D03*
Y1509804D03*
Y1514922D03*
X482323Y1503898D03*
Y1509016D03*
Y1514134D03*
Y1519252D03*
X490985Y1560985D03*
X482323Y1565315D03*
X490985Y1555867D03*
Y1560985D03*
X482323Y1560197D03*
Y1570434D03*
X490985Y1576339D03*
Y1566103D03*
Y1581457D03*
X482323Y1580670D03*
X490985Y1566103D03*
Y1571221D03*
Y1576339D03*
X482323Y1565315D03*
Y1570434D03*
Y1575552D03*
X490985Y1591693D03*
X482323Y1596024D03*
Y1585788D03*
X490985Y1596811D03*
Y1581457D03*
Y1586575D03*
Y1591693D03*
X482323Y1580670D03*
Y1585788D03*
Y1590906D03*
Y1596024D03*
X490985Y1612166D03*
Y1607048D03*
X482323Y1611378D03*
Y1601142D03*
X490985Y1596811D03*
Y1601930D03*
Y1607048D03*
Y1612166D03*
X482323Y1601142D03*
Y1606260D03*
Y1611378D03*
Y1616496D03*
X490985Y1617284D03*
Y1622402D03*
X482323Y1616496D03*
Y1621615D03*
X508307Y1463741D03*
Y1458622D03*
X499646Y1462953D03*
Y1468071D03*
X508307Y1453504D03*
X499646Y1452717D03*
Y1457835D03*
Y1462953D03*
Y1478308D03*
X508307Y1473977D03*
Y1479095D03*
X499646Y1483426D03*
X508307Y1468859D03*
X499646Y1468071D03*
Y1473189D03*
Y1478308D03*
X508307Y1494449D03*
Y1489331D03*
X499646Y1498780D03*
Y1493662D03*
X508307Y1484213D03*
X499646Y1483426D03*
Y1488544D03*
Y1493662D03*
Y1498780D03*
Y1514134D03*
Y1509016D03*
X508307Y1509804D03*
Y1504685D03*
Y1499567D03*
Y1514922D03*
X499646Y1503898D03*
Y1509016D03*
Y1514134D03*
Y1519252D03*
X508307Y1560985D03*
X499646Y1565315D03*
X508307Y1555867D03*
X499646Y1560197D03*
Y1570434D03*
X508307Y1576339D03*
Y1566103D03*
Y1581457D03*
X499646Y1580670D03*
X508307Y1571221D03*
X499646Y1565315D03*
Y1570434D03*
Y1575552D03*
X508307Y1591693D03*
X499646Y1596024D03*
Y1585788D03*
X508307Y1596811D03*
Y1586575D03*
X499646Y1580670D03*
Y1585788D03*
Y1590906D03*
Y1596024D03*
Y1611378D03*
Y1601142D03*
X508307Y1607048D03*
Y1612166D03*
Y1601930D03*
X499646Y1601142D03*
Y1606260D03*
Y1611378D03*
Y1616496D03*
X508307Y1617284D03*
X499646Y1616496D03*
Y1621615D03*
X516969Y1462953D03*
Y1468071D03*
Y1452717D03*
Y1457835D03*
X508307Y1458622D03*
X516969Y1462953D03*
X508307Y1463741D03*
X516969Y1478308D03*
Y1483426D03*
Y1468071D03*
Y1473189D03*
X508307Y1473977D03*
X516969Y1478308D03*
X508307Y1479095D03*
X516969Y1498780D03*
Y1493662D03*
Y1483426D03*
Y1488544D03*
X508307Y1489331D03*
X516969Y1493662D03*
X508307Y1494449D03*
X516969Y1498780D03*
Y1514134D03*
Y1509016D03*
Y1503898D03*
X508307Y1504685D03*
X516969Y1509016D03*
X508307Y1509804D03*
X516969Y1514134D03*
Y1519252D03*
Y1565315D03*
X508307Y1560985D03*
X516969Y1560197D03*
Y1570434D03*
Y1580670D03*
Y1565315D03*
X508307Y1566103D03*
X516969Y1570434D03*
Y1575552D03*
X508307Y1576339D03*
X516969Y1596024D03*
Y1585788D03*
Y1580670D03*
X508307Y1581457D03*
X516969Y1585788D03*
Y1590906D03*
X508307Y1591693D03*
X516969Y1596024D03*
Y1611378D03*
Y1601142D03*
X508307Y1596811D03*
X516969Y1601142D03*
Y1606260D03*
X508307Y1607048D03*
X516969Y1611378D03*
X508307Y1612166D03*
X516969Y1616496D03*
D03*
Y1621615D03*
X508307Y1622402D03*
X525630Y1453504D03*
X534292Y1452717D03*
X525630Y1458622D03*
X534292Y1457835D03*
X525630Y1463741D03*
X534292Y1462953D03*
X525630Y1468859D03*
X534292Y1468071D03*
X525630Y1473977D03*
X534292Y1473189D03*
X525630Y1479095D03*
X534292Y1478308D03*
X525630Y1484213D03*
X534292Y1483426D03*
X525630Y1489331D03*
X534292Y1488544D03*
X525630Y1494449D03*
X534292Y1493662D03*
Y1498780D03*
X525630Y1499567D03*
Y1504685D03*
X534292Y1503898D03*
X525630Y1509804D03*
X534292Y1509016D03*
X525630Y1514922D03*
X534292Y1514134D03*
Y1519252D03*
X525630Y1555867D03*
Y1560985D03*
X534292Y1560197D03*
X525630Y1566103D03*
X534292Y1565315D03*
X525630Y1571221D03*
X534292Y1570434D03*
X525630Y1576339D03*
X534292Y1575552D03*
X525630Y1581457D03*
X534292Y1580670D03*
X525630Y1586575D03*
X534292Y1585788D03*
X525630Y1591693D03*
X534292Y1590906D03*
Y1596024D03*
X525630Y1596811D03*
Y1601930D03*
X534292Y1601142D03*
X525630Y1607048D03*
X534292Y1606260D03*
X525630Y1612166D03*
X534292Y1611378D03*
X525630Y1617284D03*
X534292Y1616496D03*
X525630Y1622402D03*
X534292Y1621615D03*
X638228Y1462953D03*
X629567Y1463741D03*
Y1458622D03*
X638228Y1468071D03*
X629567Y1453504D03*
X638228Y1457835D03*
X629567Y1458622D03*
Y1463741D03*
Y1479095D03*
Y1473977D03*
X638228Y1478308D03*
Y1483426D03*
X629567Y1468859D03*
X638228Y1473189D03*
X629567Y1473977D03*
Y1479095D03*
X638228Y1498780D03*
Y1493662D03*
X629567Y1494449D03*
Y1489331D03*
Y1484213D03*
X638228Y1488544D03*
X629567Y1489331D03*
Y1494449D03*
Y1509804D03*
Y1504685D03*
X638228Y1514134D03*
Y1509016D03*
X629567Y1499567D03*
X638228Y1503898D03*
X629567Y1504685D03*
Y1509804D03*
Y1514922D03*
X638228Y1519252D03*
X629567Y1560985D03*
X638228Y1565315D03*
X629567Y1555867D03*
X638228Y1560197D03*
X629567Y1560985D03*
Y1576339D03*
Y1566103D03*
X638228Y1570434D03*
Y1580670D03*
X629567Y1581457D03*
Y1566103D03*
Y1571221D03*
X638228Y1575552D03*
X629567Y1576339D03*
X638228Y1596024D03*
Y1585788D03*
X629567Y1591693D03*
Y1596811D03*
Y1581457D03*
Y1586575D03*
X638228Y1590906D03*
X629567Y1591693D03*
Y1612166D03*
Y1607048D03*
X638228Y1611378D03*
Y1601142D03*
X629567Y1596811D03*
Y1601930D03*
X638228Y1606260D03*
X629567Y1607048D03*
Y1612166D03*
X638228Y1616496D03*
X629567Y1617284D03*
X638228Y1621615D03*
X629567Y1622402D03*
X655551Y1462953D03*
X646890Y1463741D03*
Y1458622D03*
X655551Y1468071D03*
X646890Y1453504D03*
Y1458622D03*
Y1463741D03*
X638228Y1452717D03*
Y1462953D03*
X646890Y1479095D03*
Y1473977D03*
X655551Y1478308D03*
Y1483426D03*
X646890Y1468859D03*
Y1473977D03*
Y1479095D03*
X638228Y1468071D03*
Y1478308D03*
X655551Y1498780D03*
Y1493662D03*
X646890Y1494449D03*
Y1489331D03*
Y1484213D03*
Y1489331D03*
Y1494449D03*
X638228Y1483426D03*
Y1493662D03*
Y1498780D03*
X646890Y1509804D03*
Y1504685D03*
X655551Y1514134D03*
Y1509016D03*
X646890Y1499567D03*
Y1504685D03*
Y1509804D03*
Y1514922D03*
X638228Y1509016D03*
Y1514134D03*
X646890Y1560985D03*
X655551Y1565315D03*
X646890Y1555867D03*
Y1560985D03*
Y1576339D03*
Y1566103D03*
X655551Y1570434D03*
Y1580670D03*
X646890Y1581457D03*
Y1566103D03*
Y1571221D03*
Y1576339D03*
X638228Y1565315D03*
Y1570434D03*
X655551Y1596024D03*
Y1585788D03*
X646890Y1591693D03*
Y1596811D03*
Y1581457D03*
Y1586575D03*
Y1591693D03*
X638228Y1580670D03*
Y1585788D03*
Y1596024D03*
X646890Y1612166D03*
Y1607048D03*
X655551Y1611378D03*
Y1601142D03*
X646890Y1596811D03*
Y1601930D03*
Y1607048D03*
Y1612166D03*
X638228Y1601142D03*
Y1611378D03*
X655551Y1616496D03*
X646890Y1617284D03*
Y1622402D03*
X638228Y1616496D03*
X664213Y1463741D03*
Y1458622D03*
Y1453504D03*
Y1458622D03*
Y1463741D03*
X655551Y1452717D03*
Y1457835D03*
Y1462953D03*
X664213Y1479095D03*
Y1473977D03*
Y1468859D03*
Y1473977D03*
Y1479095D03*
X655551Y1468071D03*
Y1473189D03*
Y1478308D03*
X664213Y1494449D03*
Y1489331D03*
Y1484213D03*
Y1489331D03*
Y1494449D03*
X655551Y1483426D03*
Y1488544D03*
Y1493662D03*
Y1498780D03*
X664213Y1509804D03*
Y1504685D03*
Y1499567D03*
Y1504685D03*
Y1509804D03*
Y1514922D03*
X655551Y1503898D03*
Y1509016D03*
Y1514134D03*
Y1519252D03*
X664213Y1560985D03*
Y1555867D03*
Y1560985D03*
X655551Y1560197D03*
X664213Y1576339D03*
Y1566103D03*
Y1581457D03*
Y1566103D03*
Y1571221D03*
Y1576339D03*
X655551Y1565315D03*
Y1570434D03*
Y1575552D03*
X664213Y1591693D03*
Y1596811D03*
Y1581457D03*
Y1586575D03*
Y1591693D03*
X655551Y1580670D03*
Y1585788D03*
Y1590906D03*
Y1596024D03*
X664213Y1612166D03*
Y1607048D03*
Y1596811D03*
Y1601930D03*
Y1607048D03*
Y1612166D03*
X655551Y1601142D03*
Y1606260D03*
Y1611378D03*
X664213Y1617284D03*
Y1622402D03*
X655551Y1616496D03*
Y1621615D03*
X672874Y1462953D03*
X681535Y1463741D03*
Y1458622D03*
X672874Y1468071D03*
X681535Y1453504D03*
Y1458622D03*
Y1463741D03*
X672874Y1452717D03*
Y1457835D03*
Y1462953D03*
Y1478308D03*
X681535Y1479095D03*
Y1473977D03*
X672874Y1483426D03*
X681535Y1468859D03*
Y1473977D03*
Y1479095D03*
X672874Y1468071D03*
Y1473189D03*
Y1478308D03*
Y1498780D03*
Y1493662D03*
X681535Y1494449D03*
Y1489331D03*
Y1484213D03*
Y1489331D03*
Y1494449D03*
X672874Y1483426D03*
Y1488544D03*
Y1493662D03*
Y1498780D03*
Y1514134D03*
Y1509016D03*
X681535Y1509804D03*
Y1504685D03*
Y1499567D03*
Y1504685D03*
Y1509804D03*
Y1514922D03*
X672874Y1503898D03*
Y1509016D03*
Y1514134D03*
Y1519252D03*
X681535Y1560985D03*
X672874Y1565315D03*
X681535Y1555867D03*
Y1560985D03*
X672874Y1560197D03*
Y1570434D03*
X681535Y1576339D03*
Y1566103D03*
X672874Y1580670D03*
X681535Y1581457D03*
Y1566103D03*
Y1571221D03*
Y1576339D03*
X672874Y1565315D03*
Y1570434D03*
Y1575552D03*
Y1596024D03*
Y1585788D03*
X681535Y1591693D03*
Y1596811D03*
Y1581457D03*
Y1586575D03*
Y1591693D03*
X672874Y1580670D03*
Y1585788D03*
Y1590906D03*
Y1596024D03*
Y1611378D03*
Y1601142D03*
X681535Y1612166D03*
Y1607048D03*
Y1596811D03*
Y1601930D03*
Y1607048D03*
Y1612166D03*
X672874Y1601142D03*
Y1606260D03*
Y1611378D03*
Y1616496D03*
X681535Y1617284D03*
Y1622402D03*
X672874Y1616496D03*
Y1621615D03*
X690197Y1462953D03*
Y1468071D03*
X698858Y1453504D03*
Y1458622D03*
Y1463741D03*
X690197Y1452717D03*
Y1457835D03*
Y1462953D03*
Y1478308D03*
Y1483426D03*
X698858Y1468859D03*
Y1473977D03*
Y1479095D03*
X690197Y1468071D03*
Y1473189D03*
Y1478308D03*
Y1498780D03*
Y1493662D03*
X698858Y1484213D03*
Y1489331D03*
Y1494449D03*
X690197Y1483426D03*
Y1488544D03*
Y1493662D03*
Y1498780D03*
Y1514134D03*
Y1509016D03*
X698858Y1499567D03*
Y1504685D03*
Y1509804D03*
Y1514922D03*
X690197Y1503898D03*
Y1509016D03*
Y1514134D03*
Y1519252D03*
Y1565315D03*
X698858Y1555867D03*
Y1560985D03*
X690197Y1560197D03*
Y1570434D03*
Y1580670D03*
X698858Y1566103D03*
Y1571221D03*
Y1576339D03*
X690197Y1565315D03*
Y1570434D03*
Y1575552D03*
Y1596024D03*
Y1585788D03*
X698858Y1581457D03*
Y1586575D03*
Y1591693D03*
X690197Y1580670D03*
Y1585788D03*
Y1590906D03*
Y1596024D03*
Y1611378D03*
Y1601142D03*
X698858Y1596811D03*
Y1601930D03*
Y1607048D03*
Y1612166D03*
X690197Y1601142D03*
Y1606260D03*
Y1611378D03*
Y1616496D03*
X698858Y1617284D03*
Y1622402D03*
X690197Y1616496D03*
Y1621615D03*
X707520Y1452717D03*
Y1457835D03*
Y1462953D03*
Y1468071D03*
Y1473189D03*
Y1478308D03*
Y1483426D03*
Y1488544D03*
Y1493662D03*
Y1498780D03*
Y1503898D03*
Y1509016D03*
Y1514134D03*
Y1519252D03*
Y1560197D03*
Y1565315D03*
Y1570434D03*
Y1575552D03*
Y1580670D03*
Y1585788D03*
Y1590906D03*
Y1596024D03*
Y1601142D03*
Y1606260D03*
Y1611378D03*
Y1616496D03*
Y1621615D03*
X843012Y1592787D03*
Y1602787D03*
Y1612787D03*
Y1622787D03*
X853012Y1592787D03*
Y1602787D03*
Y1612787D03*
Y1622787D03*
X878012Y1592787D03*
Y1602787D03*
Y1612787D03*
Y1622787D03*
X888012Y1592787D03*
Y1602787D03*
Y1612787D03*
Y1622787D03*
X913012Y1592787D03*
Y1602787D03*
Y1612787D03*
Y1622787D03*
X923012Y1592787D03*
Y1602787D03*
Y1612787D03*
Y1622787D03*
X948012Y1592787D03*
Y1602787D03*
Y1612787D03*
Y1622787D03*
X958012Y1592787D03*
Y1602787D03*
Y1612787D03*
Y1622787D03*
X983012Y1592787D03*
X993012D03*
X983012Y1602787D03*
Y1612787D03*
X993012Y1602787D03*
Y1612787D03*
X983012Y1622787D03*
X993012D03*
X1018012Y1592787D03*
X1028012D03*
X1018012Y1602787D03*
Y1612787D03*
X1028012Y1602787D03*
Y1612787D03*
X1018012Y1622787D03*
X1028012D03*
X1140511Y1462953D03*
X1131850Y1463741D03*
Y1458622D03*
X1140511Y1468071D03*
Y1452717D03*
X1131850Y1453504D03*
X1140511Y1457835D03*
X1131850Y1458622D03*
X1140511Y1462953D03*
X1131850Y1463741D03*
Y1479095D03*
X1140511Y1478308D03*
X1131850Y1473977D03*
X1140511Y1483426D03*
Y1468071D03*
X1131850Y1468859D03*
X1140511Y1473189D03*
X1131850Y1473977D03*
X1140511Y1478308D03*
X1131850Y1479095D03*
X1140511Y1498780D03*
Y1493662D03*
X1131850Y1494449D03*
Y1489331D03*
X1140511Y1483426D03*
X1131850Y1484213D03*
X1140511Y1488544D03*
X1131850Y1489331D03*
X1140511Y1493662D03*
X1131850Y1494449D03*
X1140511Y1498780D03*
Y1514134D03*
X1131850Y1509804D03*
X1140511Y1509016D03*
X1131850Y1504685D03*
Y1499567D03*
X1140511Y1503898D03*
X1131850Y1504685D03*
X1140511Y1509016D03*
X1131850Y1509804D03*
Y1514922D03*
X1140511Y1514134D03*
Y1519252D03*
X1131850Y1560985D03*
X1140511Y1565315D03*
X1131850Y1555867D03*
X1140511Y1560197D03*
X1131850Y1560985D03*
Y1576339D03*
X1140511Y1570434D03*
X1131850Y1566103D03*
X1140511Y1580670D03*
X1131850Y1581457D03*
X1140511Y1565315D03*
X1131850Y1566103D03*
X1140511Y1570434D03*
X1131850Y1571221D03*
X1140511Y1575552D03*
X1131850Y1576339D03*
X1140511Y1596024D03*
Y1585788D03*
X1131850Y1591693D03*
Y1596811D03*
X1140511Y1580670D03*
X1131850Y1581457D03*
X1140511Y1585788D03*
X1131850Y1586575D03*
X1140511Y1590906D03*
X1131850Y1591693D03*
X1140511Y1596024D03*
X1131850Y1612166D03*
X1140511Y1611378D03*
X1131850Y1607048D03*
X1140511Y1601142D03*
X1131850Y1596811D03*
X1140511Y1601142D03*
X1131850Y1601930D03*
X1140511Y1606260D03*
X1131850Y1607048D03*
X1140511Y1611378D03*
X1131850Y1612166D03*
X1140511Y1616496D03*
D03*
X1131850Y1617284D03*
X1140511Y1621615D03*
X1131850Y1622402D03*
X1157834Y1462953D03*
X1149173Y1463741D03*
Y1458622D03*
X1157834Y1468071D03*
X1149173Y1453504D03*
X1157834Y1457835D03*
X1149173Y1458622D03*
Y1463741D03*
Y1479095D03*
Y1473977D03*
X1157834Y1478308D03*
Y1483426D03*
X1149173Y1468859D03*
X1157834Y1473189D03*
X1149173Y1473977D03*
Y1479095D03*
X1157834Y1498780D03*
Y1493662D03*
X1149173Y1494449D03*
Y1489331D03*
Y1484213D03*
X1157834Y1488544D03*
X1149173Y1489331D03*
Y1494449D03*
Y1509804D03*
Y1504685D03*
X1157834Y1514134D03*
Y1509016D03*
X1149173Y1499567D03*
X1157834Y1503898D03*
X1149173Y1504685D03*
Y1509804D03*
Y1514922D03*
X1157834Y1519252D03*
X1149173Y1560985D03*
X1157834Y1565315D03*
X1149173Y1555867D03*
Y1560985D03*
X1157834Y1560197D03*
X1149173Y1576339D03*
Y1566103D03*
X1157834Y1570434D03*
Y1580670D03*
X1149173Y1581457D03*
Y1566103D03*
Y1571221D03*
X1157834Y1575552D03*
X1149173Y1576339D03*
X1157834Y1596024D03*
Y1585788D03*
X1149173Y1591693D03*
Y1596811D03*
Y1581457D03*
Y1586575D03*
X1157834Y1590906D03*
X1149173Y1591693D03*
Y1612166D03*
Y1607048D03*
X1157834Y1611378D03*
Y1601142D03*
X1149173Y1596811D03*
Y1601930D03*
X1157834Y1606260D03*
X1149173Y1607048D03*
Y1612166D03*
X1157834Y1616496D03*
X1149173Y1617284D03*
X1157834Y1621615D03*
X1149173Y1622402D03*
X1175157Y1462953D03*
X1166496Y1463741D03*
Y1458622D03*
X1175157Y1468071D03*
X1166496Y1453504D03*
Y1458622D03*
Y1463741D03*
X1157834Y1452717D03*
Y1462953D03*
X1166496Y1479095D03*
Y1473977D03*
X1175157Y1478308D03*
Y1483426D03*
X1166496Y1468859D03*
Y1473977D03*
Y1479095D03*
X1157834Y1468071D03*
Y1478308D03*
X1175157Y1498780D03*
Y1493662D03*
X1166496Y1494449D03*
Y1489331D03*
Y1484213D03*
Y1489331D03*
Y1494449D03*
X1157834Y1483426D03*
Y1493662D03*
Y1498780D03*
X1166496Y1509804D03*
Y1504685D03*
X1175157Y1514134D03*
Y1509016D03*
X1166496Y1499567D03*
Y1504685D03*
Y1509804D03*
Y1514922D03*
X1157834Y1509016D03*
Y1514134D03*
X1166496Y1560985D03*
X1175157Y1565315D03*
X1166496Y1555867D03*
Y1560985D03*
Y1576339D03*
Y1566103D03*
X1175157Y1570434D03*
Y1580670D03*
X1166496Y1581457D03*
Y1566103D03*
Y1571221D03*
Y1576339D03*
X1157834Y1565315D03*
Y1570434D03*
X1175157Y1596024D03*
Y1585788D03*
X1166496Y1591693D03*
Y1596811D03*
Y1581457D03*
Y1586575D03*
Y1591693D03*
X1157834Y1580670D03*
Y1585788D03*
Y1596024D03*
X1166496Y1612166D03*
Y1607048D03*
X1175157Y1611378D03*
Y1601142D03*
X1166496Y1596811D03*
Y1601930D03*
Y1607048D03*
Y1612166D03*
X1157834Y1601142D03*
Y1611378D03*
X1175157Y1616496D03*
X1166496Y1617284D03*
Y1622402D03*
X1157834Y1616496D03*
X1183818Y1463741D03*
Y1458622D03*
Y1453504D03*
Y1458622D03*
Y1463741D03*
X1175157Y1452717D03*
Y1457835D03*
Y1462953D03*
X1183818Y1479095D03*
Y1473977D03*
Y1468859D03*
Y1473977D03*
Y1479095D03*
X1175157Y1468071D03*
Y1473189D03*
Y1478308D03*
X1183818Y1494449D03*
Y1489331D03*
Y1484213D03*
Y1489331D03*
Y1494449D03*
X1175157Y1483426D03*
Y1488544D03*
Y1493662D03*
Y1498780D03*
X1183818Y1509804D03*
Y1504685D03*
Y1499567D03*
Y1504685D03*
Y1509804D03*
Y1514922D03*
X1175157Y1503898D03*
Y1509016D03*
Y1514134D03*
Y1519252D03*
X1183818Y1560985D03*
Y1555867D03*
Y1560985D03*
X1175157Y1560197D03*
X1183818Y1576339D03*
Y1566103D03*
Y1581457D03*
Y1566103D03*
Y1571221D03*
Y1576339D03*
X1175157Y1565315D03*
Y1570434D03*
Y1575552D03*
X1183818Y1591693D03*
Y1596811D03*
Y1581457D03*
Y1586575D03*
Y1591693D03*
X1175157Y1580670D03*
Y1585788D03*
Y1590906D03*
Y1596024D03*
X1183818Y1612166D03*
Y1607048D03*
Y1596811D03*
Y1601930D03*
Y1607048D03*
Y1612166D03*
X1175157Y1601142D03*
Y1606260D03*
Y1611378D03*
X1183818Y1617284D03*
Y1622402D03*
X1175157Y1616496D03*
Y1621615D03*
X1192480Y1462953D03*
Y1468071D03*
X1201141Y1453504D03*
Y1458622D03*
Y1463741D03*
X1192480Y1452717D03*
Y1457835D03*
Y1462953D03*
Y1478308D03*
Y1483426D03*
X1201141Y1468859D03*
Y1473977D03*
Y1479095D03*
X1192480Y1468071D03*
Y1473189D03*
Y1478308D03*
Y1498780D03*
Y1493662D03*
X1201141Y1484213D03*
Y1489331D03*
Y1494449D03*
X1192480Y1483426D03*
Y1488544D03*
Y1493662D03*
Y1498780D03*
Y1514134D03*
Y1509016D03*
X1201141Y1499567D03*
Y1504685D03*
Y1509804D03*
Y1514922D03*
X1192480Y1503898D03*
Y1509016D03*
Y1514134D03*
Y1519252D03*
Y1565315D03*
X1201141Y1555867D03*
Y1560985D03*
X1192480Y1560197D03*
Y1570434D03*
Y1580670D03*
X1201141Y1566103D03*
Y1571221D03*
Y1576339D03*
X1192480Y1565315D03*
Y1570434D03*
Y1575552D03*
Y1596024D03*
Y1585788D03*
X1201141Y1581457D03*
Y1586575D03*
Y1591693D03*
X1192480Y1580670D03*
Y1585788D03*
Y1590906D03*
Y1596024D03*
Y1611378D03*
Y1601142D03*
X1201141Y1596811D03*
Y1601930D03*
Y1607048D03*
Y1612166D03*
X1192480Y1601142D03*
Y1606260D03*
Y1611378D03*
Y1616496D03*
X1201141Y1617284D03*
Y1622402D03*
X1192480Y1616496D03*
Y1621615D03*
X1209803Y1452717D03*
Y1457835D03*
Y1462953D03*
Y1468071D03*
Y1473189D03*
Y1478308D03*
Y1483426D03*
Y1488544D03*
Y1493662D03*
Y1498780D03*
Y1503898D03*
Y1509016D03*
Y1514134D03*
Y1519252D03*
Y1560197D03*
Y1565315D03*
Y1570434D03*
Y1575552D03*
Y1580670D03*
Y1585788D03*
Y1590906D03*
Y1596024D03*
Y1601142D03*
Y1606260D03*
Y1611378D03*
Y1616496D03*
Y1621615D03*
X1305079Y1463741D03*
Y1458622D03*
Y1479095D03*
Y1473977D03*
Y1494449D03*
Y1489331D03*
Y1509804D03*
Y1504685D03*
Y1560985D03*
Y1576339D03*
Y1566103D03*
Y1581457D03*
Y1591693D03*
Y1596811D03*
Y1612166D03*
Y1607048D03*
X1313740Y1462953D03*
Y1468071D03*
Y1452717D03*
X1305079Y1453504D03*
X1313740Y1457835D03*
X1305079Y1458622D03*
X1313740Y1462953D03*
X1305079Y1463741D03*
X1313740Y1478308D03*
Y1483426D03*
Y1468071D03*
X1305079Y1468859D03*
X1313740Y1473189D03*
X1305079Y1473977D03*
X1313740Y1478308D03*
X1305079Y1479095D03*
X1313740Y1498780D03*
Y1493662D03*
Y1483426D03*
X1305079Y1484213D03*
X1313740Y1488544D03*
X1305079Y1489331D03*
X1313740Y1493662D03*
X1305079Y1494449D03*
X1313740Y1498780D03*
Y1514134D03*
Y1509016D03*
X1305079Y1499567D03*
X1313740Y1503898D03*
X1305079Y1504685D03*
X1313740Y1509016D03*
X1305079Y1509804D03*
Y1514922D03*
X1313740Y1514134D03*
Y1519252D03*
Y1565315D03*
X1305079Y1555867D03*
X1313740Y1560197D03*
X1305079Y1560985D03*
X1313740Y1570434D03*
Y1580670D03*
Y1565315D03*
X1305079Y1566103D03*
X1313740Y1570434D03*
X1305079Y1571221D03*
X1313740Y1575552D03*
X1305079Y1576339D03*
X1313740Y1596024D03*
Y1585788D03*
Y1580670D03*
X1305079Y1581457D03*
X1313740Y1585788D03*
X1305079Y1586575D03*
X1313740Y1590906D03*
X1305079Y1591693D03*
X1313740Y1596024D03*
Y1611378D03*
Y1601142D03*
X1305079Y1596811D03*
X1313740Y1601142D03*
X1305079Y1601930D03*
X1313740Y1606260D03*
X1305079Y1607048D03*
X1313740Y1611378D03*
X1305079Y1612166D03*
X1313740Y1616496D03*
D03*
X1305079Y1617284D03*
X1313740Y1621615D03*
X1305079Y1622402D03*
X1322402Y1463741D03*
X1331063Y1462953D03*
X1322402Y1458622D03*
X1331063Y1468071D03*
Y1452717D03*
X1322402Y1453504D03*
X1331063Y1457835D03*
X1322402Y1458622D03*
X1331063Y1462953D03*
X1322402Y1463741D03*
Y1479095D03*
X1331063Y1478308D03*
X1322402Y1473977D03*
X1331063Y1483426D03*
Y1468071D03*
X1322402Y1468859D03*
X1331063Y1473189D03*
X1322402Y1473977D03*
X1331063Y1478308D03*
X1322402Y1479095D03*
X1331063Y1498780D03*
X1322402Y1494449D03*
X1331063Y1493662D03*
X1322402Y1489331D03*
X1331063Y1483426D03*
X1322402Y1484213D03*
X1331063Y1488544D03*
X1322402Y1489331D03*
X1331063Y1493662D03*
X1322402Y1494449D03*
X1331063Y1498780D03*
Y1514134D03*
X1322402Y1509804D03*
X1331063Y1509016D03*
X1322402Y1504685D03*
Y1499567D03*
X1331063Y1503898D03*
X1322402Y1504685D03*
X1331063Y1509016D03*
X1322402Y1509804D03*
X1331063Y1514134D03*
X1322402Y1514922D03*
X1331063Y1519252D03*
X1322402Y1560985D03*
X1331063Y1565315D03*
X1322402Y1555867D03*
Y1560985D03*
X1331063Y1560197D03*
X1322402Y1576339D03*
X1331063Y1570434D03*
X1322402Y1566103D03*
Y1581457D03*
X1331063Y1580670D03*
Y1565315D03*
X1322402Y1566103D03*
X1331063Y1570434D03*
X1322402Y1571221D03*
X1331063Y1575552D03*
X1322402Y1576339D03*
X1331063Y1596024D03*
X1322402Y1591693D03*
X1331063Y1585788D03*
X1322402Y1596811D03*
X1331063Y1580670D03*
X1322402Y1581457D03*
X1331063Y1585788D03*
X1322402Y1586575D03*
X1331063Y1590906D03*
X1322402Y1591693D03*
X1331063Y1596024D03*
X1322402Y1612166D03*
X1331063Y1611378D03*
X1322402Y1607048D03*
X1331063Y1601142D03*
X1322402Y1596811D03*
X1331063Y1601142D03*
X1322402Y1601930D03*
X1331063Y1606260D03*
X1322402Y1607048D03*
X1331063Y1611378D03*
X1322402Y1612166D03*
X1331063Y1616496D03*
D03*
X1322402Y1617284D03*
X1331063Y1621615D03*
X1322402Y1622402D03*
X1339725Y1463741D03*
X1348386Y1462953D03*
X1339725Y1458622D03*
X1348386Y1468071D03*
Y1452717D03*
X1339725Y1453504D03*
X1348386Y1457835D03*
X1339725Y1458622D03*
X1348386Y1462953D03*
X1339725Y1463741D03*
Y1479095D03*
X1348386Y1478308D03*
X1339725Y1473977D03*
X1348386Y1483426D03*
Y1468071D03*
X1339725Y1468859D03*
X1348386Y1473189D03*
X1339725Y1473977D03*
X1348386Y1478308D03*
X1339725Y1479095D03*
X1348386Y1498780D03*
X1339725Y1494449D03*
X1348386Y1493662D03*
X1339725Y1489331D03*
X1348386Y1483426D03*
X1339725Y1484213D03*
X1348386Y1488544D03*
X1339725Y1489331D03*
X1348386Y1493662D03*
X1339725Y1494449D03*
X1348386Y1498780D03*
Y1514134D03*
X1339725Y1509804D03*
X1348386Y1509016D03*
X1339725Y1504685D03*
Y1499567D03*
X1348386Y1503898D03*
X1339725Y1504685D03*
X1348386Y1509016D03*
X1339725Y1509804D03*
X1348386Y1514134D03*
X1339725Y1514922D03*
X1348386Y1519252D03*
X1339725Y1560985D03*
X1348386Y1565315D03*
X1339725Y1555867D03*
Y1560985D03*
X1348386Y1560197D03*
X1339725Y1576339D03*
X1348386Y1570434D03*
X1339725Y1566103D03*
Y1581457D03*
X1348386Y1580670D03*
Y1565315D03*
X1339725Y1566103D03*
X1348386Y1570434D03*
X1339725Y1571221D03*
X1348386Y1575552D03*
X1339725Y1576339D03*
X1348386Y1596024D03*
X1339725Y1591693D03*
X1348386Y1585788D03*
X1339725Y1596811D03*
X1348386Y1580670D03*
X1339725Y1581457D03*
X1348386Y1585788D03*
X1339725Y1586575D03*
X1348386Y1590906D03*
X1339725Y1591693D03*
X1348386Y1596024D03*
X1339725Y1612166D03*
X1348386Y1611378D03*
X1339725Y1607048D03*
X1348386Y1601142D03*
X1339725Y1596811D03*
X1348386Y1601142D03*
X1339725Y1601930D03*
X1348386Y1606260D03*
X1339725Y1607048D03*
X1348386Y1611378D03*
X1339725Y1612166D03*
X1348386Y1616496D03*
D03*
X1339725Y1617284D03*
X1348386Y1621615D03*
X1339725Y1622402D03*
X1365709Y1462953D03*
X1357047Y1463741D03*
Y1458622D03*
X1365709Y1468071D03*
Y1452717D03*
X1357047Y1453504D03*
X1365709Y1457835D03*
X1357047Y1458622D03*
X1365709Y1462953D03*
X1357047Y1463741D03*
Y1479095D03*
X1365709Y1478308D03*
X1357047Y1473977D03*
X1365709Y1483426D03*
Y1468071D03*
X1357047Y1468859D03*
X1365709Y1473189D03*
X1357047Y1473977D03*
X1365709Y1478308D03*
X1357047Y1479095D03*
X1365709Y1498780D03*
Y1493662D03*
X1357047Y1494449D03*
Y1489331D03*
X1365709Y1483426D03*
X1357047Y1484213D03*
X1365709Y1488544D03*
X1357047Y1489331D03*
X1365709Y1493662D03*
X1357047Y1494449D03*
X1365709Y1498780D03*
Y1514134D03*
X1357047Y1509804D03*
X1365709Y1509016D03*
X1357047Y1504685D03*
Y1499567D03*
X1365709Y1503898D03*
X1357047Y1504685D03*
X1365709Y1509016D03*
X1357047Y1509804D03*
X1365709Y1514134D03*
X1357047Y1514922D03*
X1365709Y1519252D03*
X1357047Y1560985D03*
X1365709Y1565315D03*
X1357047Y1555867D03*
Y1560985D03*
X1365709Y1560197D03*
X1357047Y1576339D03*
X1365709Y1570434D03*
X1357047Y1566103D03*
X1365709Y1580670D03*
X1357047Y1581457D03*
X1365709Y1565315D03*
X1357047Y1566103D03*
X1365709Y1570434D03*
X1357047Y1571221D03*
X1365709Y1575552D03*
X1357047Y1576339D03*
X1365709Y1596024D03*
Y1585788D03*
X1357047Y1591693D03*
Y1596811D03*
X1365709Y1580670D03*
X1357047Y1581457D03*
X1365709Y1585788D03*
X1357047Y1586575D03*
X1365709Y1590906D03*
X1357047Y1591693D03*
X1365709Y1596024D03*
X1357047Y1612166D03*
X1365709Y1611378D03*
X1357047Y1607048D03*
X1365709Y1601142D03*
X1357047Y1596811D03*
X1365709Y1601142D03*
X1357047Y1601930D03*
X1365709Y1606260D03*
X1357047Y1607048D03*
X1365709Y1611378D03*
X1357047Y1612166D03*
X1365709Y1616496D03*
D03*
X1357047Y1617284D03*
X1365709Y1621615D03*
X1357047Y1622402D03*
X1374370Y1453504D03*
X1383032Y1452717D03*
X1374370Y1458622D03*
X1383032Y1457835D03*
X1374370Y1463741D03*
X1383032Y1462953D03*
X1374370Y1468859D03*
X1383032Y1468071D03*
X1374370Y1473977D03*
X1383032Y1473189D03*
X1374370Y1479095D03*
X1383032Y1478308D03*
X1374370Y1484213D03*
X1383032Y1483426D03*
X1374370Y1489331D03*
X1383032Y1488544D03*
X1374370Y1494449D03*
X1383032Y1493662D03*
Y1498780D03*
X1374370Y1499567D03*
Y1504685D03*
X1383032Y1503898D03*
X1374370Y1509804D03*
X1383032Y1509016D03*
X1374370Y1514922D03*
X1383032Y1514134D03*
Y1519252D03*
X1374370Y1555867D03*
Y1560985D03*
X1383032Y1560197D03*
X1374370Y1566103D03*
X1383032Y1565315D03*
X1374370Y1571221D03*
X1383032Y1570434D03*
X1374370Y1576339D03*
X1383032Y1575552D03*
X1374370Y1581457D03*
X1383032Y1580670D03*
X1374370Y1586575D03*
X1383032Y1585788D03*
X1374370Y1591693D03*
X1383032Y1590906D03*
Y1596024D03*
X1374370Y1596811D03*
Y1601930D03*
X1383032Y1601142D03*
X1374370Y1607048D03*
X1383032Y1606260D03*
X1374370Y1612166D03*
X1383032Y1611378D03*
X1374370Y1617284D03*
X1383032Y1616496D03*
X1374370Y1622402D03*
X1383032Y1621615D03*
X1478307Y1463741D03*
Y1458622D03*
Y1453504D03*
Y1458622D03*
Y1463741D03*
Y1479095D03*
Y1473977D03*
Y1468859D03*
Y1473977D03*
Y1479095D03*
Y1494449D03*
Y1489331D03*
Y1484213D03*
Y1489331D03*
Y1494449D03*
Y1509804D03*
Y1504685D03*
Y1499567D03*
Y1504685D03*
Y1509804D03*
Y1514922D03*
Y1560985D03*
Y1555867D03*
Y1560985D03*
Y1576339D03*
Y1566103D03*
Y1581457D03*
Y1566103D03*
Y1571221D03*
Y1576339D03*
Y1591693D03*
Y1596811D03*
Y1581457D03*
Y1586575D03*
Y1591693D03*
Y1612166D03*
Y1607048D03*
Y1596811D03*
Y1601930D03*
Y1607048D03*
Y1612166D03*
Y1617284D03*
Y1622402D03*
X1495630Y1463741D03*
Y1458622D03*
X1486968Y1462953D03*
Y1468071D03*
X1495630Y1453504D03*
Y1458622D03*
Y1463741D03*
X1486968Y1452717D03*
Y1457835D03*
Y1462953D03*
Y1478308D03*
X1495630Y1479095D03*
Y1473977D03*
X1486968Y1483426D03*
X1495630Y1468859D03*
Y1473977D03*
Y1479095D03*
X1486968Y1468071D03*
Y1473189D03*
Y1478308D03*
X1495630Y1494449D03*
Y1489331D03*
X1486968Y1498780D03*
Y1493662D03*
X1495630Y1484213D03*
Y1489331D03*
Y1494449D03*
X1486968Y1483426D03*
Y1488544D03*
Y1493662D03*
Y1498780D03*
Y1514134D03*
Y1509016D03*
X1495630Y1509804D03*
Y1504685D03*
Y1499567D03*
Y1504685D03*
Y1509804D03*
Y1514922D03*
X1486968Y1503898D03*
Y1509016D03*
Y1514134D03*
Y1519252D03*
X1495630Y1560985D03*
X1486968Y1565315D03*
X1495630Y1555867D03*
Y1560985D03*
X1486968Y1560197D03*
Y1570434D03*
X1495630Y1576339D03*
Y1566103D03*
Y1581457D03*
X1486968Y1580670D03*
X1495630Y1566103D03*
Y1571221D03*
Y1576339D03*
X1486968Y1565315D03*
Y1570434D03*
Y1575552D03*
X1495630Y1591693D03*
X1486968Y1596024D03*
Y1585788D03*
X1495630Y1596811D03*
Y1581457D03*
Y1586575D03*
Y1591693D03*
X1486968Y1580670D03*
Y1585788D03*
Y1590906D03*
Y1596024D03*
Y1611378D03*
Y1601142D03*
X1495630Y1612166D03*
Y1607048D03*
Y1596811D03*
Y1601930D03*
Y1607048D03*
Y1612166D03*
X1486968Y1601142D03*
Y1606260D03*
Y1611378D03*
Y1616496D03*
X1495630Y1617284D03*
Y1622402D03*
X1486968Y1616496D03*
Y1621615D03*
X1512953Y1463741D03*
Y1458622D03*
X1504291Y1462953D03*
Y1468071D03*
X1512953Y1453504D03*
Y1458622D03*
Y1463741D03*
X1504291Y1452717D03*
Y1457835D03*
Y1462953D03*
Y1478308D03*
X1512953Y1479095D03*
Y1473977D03*
X1504291Y1483426D03*
X1512953Y1468859D03*
Y1473977D03*
Y1479095D03*
X1504291Y1468071D03*
Y1473189D03*
Y1478308D03*
X1512953Y1494449D03*
Y1489331D03*
X1504291Y1498780D03*
Y1493662D03*
X1512953Y1484213D03*
Y1489331D03*
Y1494449D03*
X1504291Y1483426D03*
Y1488544D03*
Y1493662D03*
Y1498780D03*
Y1514134D03*
Y1509016D03*
X1512953Y1509804D03*
Y1504685D03*
Y1499567D03*
Y1504685D03*
Y1509804D03*
Y1514922D03*
X1504291Y1503898D03*
Y1509016D03*
Y1514134D03*
Y1519252D03*
X1512953Y1560985D03*
X1504291Y1565315D03*
X1512953Y1555867D03*
Y1560985D03*
X1504291Y1560197D03*
Y1570434D03*
X1512953Y1576339D03*
Y1566103D03*
Y1581457D03*
X1504291Y1580670D03*
X1512953Y1566103D03*
Y1571221D03*
Y1576339D03*
X1504291Y1565315D03*
Y1570434D03*
Y1575552D03*
X1512953Y1591693D03*
X1504291Y1596024D03*
Y1585788D03*
X1512953Y1596811D03*
Y1581457D03*
Y1586575D03*
Y1591693D03*
X1504291Y1580670D03*
Y1585788D03*
Y1590906D03*
Y1596024D03*
Y1611378D03*
Y1601142D03*
X1512953Y1612166D03*
Y1607048D03*
Y1596811D03*
Y1601930D03*
Y1607048D03*
Y1612166D03*
X1504291Y1601142D03*
Y1606260D03*
Y1611378D03*
Y1616496D03*
X1512953Y1617284D03*
Y1622402D03*
X1504291Y1616496D03*
Y1621615D03*
X1530275Y1463741D03*
Y1458622D03*
X1521614Y1462953D03*
Y1468071D03*
X1530275Y1453504D03*
Y1458622D03*
Y1463741D03*
X1521614Y1452717D03*
Y1457835D03*
Y1462953D03*
Y1478308D03*
X1530275Y1479095D03*
Y1473977D03*
X1521614Y1483426D03*
X1530275Y1468859D03*
Y1473977D03*
Y1479095D03*
X1521614Y1468071D03*
Y1473189D03*
Y1478308D03*
X1530275Y1494449D03*
Y1489331D03*
X1521614Y1498780D03*
Y1493662D03*
X1530275Y1484213D03*
Y1489331D03*
Y1494449D03*
X1521614Y1483426D03*
Y1488544D03*
Y1493662D03*
Y1498780D03*
Y1514134D03*
Y1509016D03*
X1530275Y1509804D03*
Y1504685D03*
Y1499567D03*
Y1504685D03*
Y1509804D03*
Y1514922D03*
X1521614Y1503898D03*
Y1509016D03*
Y1514134D03*
Y1519252D03*
X1530275Y1560985D03*
X1521614Y1565315D03*
X1530275Y1555867D03*
Y1560985D03*
X1521614Y1560197D03*
Y1570434D03*
X1530275Y1576339D03*
Y1566103D03*
Y1581457D03*
X1521614Y1580670D03*
X1530275Y1566103D03*
Y1571221D03*
Y1576339D03*
X1521614Y1565315D03*
Y1570434D03*
Y1575552D03*
X1530275Y1591693D03*
X1521614Y1596024D03*
Y1585788D03*
X1530275Y1596811D03*
Y1581457D03*
Y1586575D03*
Y1591693D03*
X1521614Y1580670D03*
Y1585788D03*
Y1590906D03*
Y1596024D03*
Y1611378D03*
Y1601142D03*
X1530275Y1612166D03*
Y1607048D03*
Y1596811D03*
Y1601930D03*
Y1607048D03*
Y1612166D03*
X1521614Y1601142D03*
Y1606260D03*
Y1611378D03*
Y1616496D03*
X1530275Y1617284D03*
Y1622402D03*
X1521614Y1616496D03*
Y1621615D03*
X1538937Y1462953D03*
Y1468071D03*
X1547598Y1453504D03*
X1538937Y1452717D03*
Y1457835D03*
Y1462953D03*
Y1478308D03*
Y1483426D03*
X1547598Y1468859D03*
X1538937Y1468071D03*
Y1473189D03*
Y1478308D03*
Y1498780D03*
Y1493662D03*
X1547598Y1484213D03*
X1538937Y1483426D03*
Y1488544D03*
Y1493662D03*
Y1498780D03*
Y1514134D03*
Y1509016D03*
X1547598Y1499567D03*
Y1514922D03*
X1538937Y1503898D03*
Y1509016D03*
Y1514134D03*
Y1519252D03*
Y1565315D03*
X1547598Y1555867D03*
X1538937Y1560197D03*
Y1570434D03*
Y1580670D03*
X1547598Y1571221D03*
X1538937Y1565315D03*
Y1570434D03*
Y1575552D03*
Y1596024D03*
Y1585788D03*
X1547598Y1586575D03*
X1538937Y1580670D03*
Y1585788D03*
Y1590906D03*
Y1596024D03*
Y1611378D03*
Y1601142D03*
X1547598Y1601930D03*
X1538937Y1601142D03*
Y1606260D03*
Y1611378D03*
Y1616496D03*
X1547598Y1617284D03*
X1538937Y1616496D03*
Y1621615D03*
X1556260Y1452717D03*
X1547598Y1458622D03*
X1556260Y1457835D03*
X1547598Y1463741D03*
X1556260Y1462953D03*
Y1468071D03*
X1547598Y1473977D03*
X1556260Y1473189D03*
X1547598Y1479095D03*
X1556260Y1478308D03*
Y1483426D03*
X1547598Y1489331D03*
X1556260Y1488544D03*
X1547598Y1494449D03*
X1556260Y1493662D03*
Y1498780D03*
X1547598Y1504685D03*
X1556260Y1503898D03*
X1547598Y1509804D03*
X1556260Y1509016D03*
Y1514134D03*
Y1519252D03*
X1547598Y1560985D03*
X1556260Y1560197D03*
X1547598Y1566103D03*
X1556260Y1565315D03*
Y1570434D03*
X1547598Y1576339D03*
X1556260Y1575552D03*
X1547598Y1581457D03*
X1556260Y1580670D03*
Y1585788D03*
X1547598Y1591693D03*
X1556260Y1590906D03*
Y1596024D03*
X1547598Y1596811D03*
X1556260Y1601142D03*
X1547598Y1607048D03*
X1556260Y1606260D03*
X1547598Y1612166D03*
X1556260Y1611378D03*
Y1616496D03*
X1547598Y1622402D03*
X1556260Y1621615D03*
X1660196Y1462953D03*
X1651535Y1463741D03*
Y1458622D03*
X1660196Y1468071D03*
Y1452717D03*
X1651535Y1453504D03*
X1660196Y1457835D03*
X1651535Y1458622D03*
X1660196Y1462953D03*
X1651535Y1463741D03*
Y1479095D03*
X1660196Y1478308D03*
X1651535Y1473977D03*
X1660196Y1483426D03*
Y1468071D03*
X1651535Y1468859D03*
X1660196Y1473189D03*
X1651535Y1473977D03*
X1660196Y1478308D03*
X1651535Y1479095D03*
X1660196Y1498780D03*
Y1493662D03*
X1651535Y1494449D03*
Y1489331D03*
X1660196Y1483426D03*
X1651535Y1484213D03*
X1660196Y1488544D03*
X1651535Y1489331D03*
X1660196Y1493662D03*
X1651535Y1494449D03*
X1660196Y1498780D03*
Y1514134D03*
X1651535Y1509804D03*
X1660196Y1509016D03*
X1651535Y1504685D03*
Y1499567D03*
X1660196Y1503898D03*
X1651535Y1504685D03*
X1660196Y1509016D03*
X1651535Y1509804D03*
Y1514922D03*
X1660196Y1514134D03*
Y1519252D03*
X1651535Y1560985D03*
X1660196Y1565315D03*
X1651535Y1555867D03*
X1660196Y1560197D03*
X1651535Y1560985D03*
Y1576339D03*
X1660196Y1570434D03*
X1651535Y1566103D03*
X1660196Y1580670D03*
X1651535Y1581457D03*
X1660196Y1565315D03*
X1651535Y1566103D03*
X1660196Y1570434D03*
X1651535Y1571221D03*
X1660196Y1575552D03*
X1651535Y1576339D03*
X1660196Y1596024D03*
Y1585788D03*
X1651535Y1591693D03*
Y1596811D03*
X1660196Y1580670D03*
X1651535Y1581457D03*
X1660196Y1585788D03*
X1651535Y1586575D03*
X1660196Y1590906D03*
X1651535Y1591693D03*
X1660196Y1596024D03*
X1651535Y1612166D03*
X1660196Y1611378D03*
X1651535Y1607048D03*
X1660196Y1601142D03*
X1651535Y1596811D03*
X1660196Y1601142D03*
X1651535Y1601930D03*
X1660196Y1606260D03*
X1651535Y1607048D03*
X1660196Y1611378D03*
X1651535Y1612166D03*
X1660196Y1616496D03*
D03*
X1651535Y1617284D03*
X1660196Y1621615D03*
X1651535Y1622402D03*
X1677519Y1462953D03*
X1668858Y1463741D03*
Y1458622D03*
X1677519Y1468071D03*
X1668858Y1453504D03*
X1677519Y1457835D03*
X1668858Y1458622D03*
Y1463741D03*
Y1479095D03*
Y1473977D03*
X1677519Y1478308D03*
Y1483426D03*
X1668858Y1468859D03*
X1677519Y1473189D03*
X1668858Y1473977D03*
Y1479095D03*
X1677519Y1498780D03*
Y1493662D03*
X1668858Y1494449D03*
Y1489331D03*
Y1484213D03*
X1677519Y1488544D03*
X1668858Y1489331D03*
Y1494449D03*
Y1509804D03*
Y1504685D03*
X1677519Y1514134D03*
Y1509016D03*
X1668858Y1499567D03*
X1677519Y1503898D03*
X1668858Y1504685D03*
Y1509804D03*
Y1514922D03*
X1677519Y1519252D03*
X1668858Y1560985D03*
X1677519Y1565315D03*
X1668858Y1555867D03*
Y1560985D03*
X1677519Y1560197D03*
X1668858Y1576339D03*
Y1566103D03*
X1677519Y1570434D03*
Y1580670D03*
X1668858Y1581457D03*
Y1566103D03*
Y1571221D03*
X1677519Y1575552D03*
X1668858Y1576339D03*
X1677519Y1596024D03*
Y1585788D03*
X1668858Y1591693D03*
Y1596811D03*
Y1581457D03*
Y1586575D03*
X1677519Y1590906D03*
X1668858Y1591693D03*
Y1612166D03*
Y1607048D03*
X1677519Y1611378D03*
Y1601142D03*
X1668858Y1596811D03*
Y1601930D03*
X1677519Y1606260D03*
X1668858Y1607048D03*
Y1612166D03*
X1677519Y1616496D03*
X1668858Y1617284D03*
X1677519Y1621615D03*
X1668858Y1622402D03*
X1694842Y1462953D03*
X1686181Y1463741D03*
Y1458622D03*
X1694842Y1468071D03*
X1686181Y1453504D03*
Y1458622D03*
Y1463741D03*
X1677519Y1452717D03*
Y1462953D03*
X1686181Y1479095D03*
Y1473977D03*
X1694842Y1478308D03*
Y1483426D03*
X1686181Y1468859D03*
Y1473977D03*
Y1479095D03*
X1677519Y1468071D03*
Y1478308D03*
X1694842Y1498780D03*
Y1493662D03*
X1686181Y1494449D03*
Y1489331D03*
Y1484213D03*
Y1489331D03*
Y1494449D03*
X1677519Y1483426D03*
Y1493662D03*
Y1498780D03*
X1686181Y1509804D03*
Y1504685D03*
X1694842Y1514134D03*
Y1509016D03*
X1686181Y1499567D03*
Y1504685D03*
Y1509804D03*
Y1514922D03*
X1677519Y1509016D03*
Y1514134D03*
X1686181Y1560985D03*
X1694842Y1565315D03*
X1686181Y1555867D03*
Y1560985D03*
Y1576339D03*
Y1566103D03*
X1694842Y1570434D03*
Y1580670D03*
X1686181Y1581457D03*
Y1566103D03*
Y1571221D03*
Y1576339D03*
X1677519Y1565315D03*
Y1570434D03*
X1694842Y1596024D03*
Y1585788D03*
X1686181Y1591693D03*
Y1596811D03*
Y1581457D03*
Y1586575D03*
Y1591693D03*
X1677519Y1580670D03*
Y1585788D03*
Y1596024D03*
X1686181Y1612166D03*
Y1607048D03*
X1694842Y1611378D03*
Y1601142D03*
X1686181Y1596811D03*
Y1601930D03*
Y1607048D03*
Y1612166D03*
X1677519Y1601142D03*
Y1611378D03*
X1694842Y1616496D03*
X1686181Y1617284D03*
Y1622402D03*
X1677519Y1616496D03*
X1703503Y1463741D03*
Y1458622D03*
Y1453504D03*
Y1458622D03*
Y1463741D03*
X1694842Y1452717D03*
Y1457835D03*
Y1462953D03*
X1703503Y1479095D03*
Y1473977D03*
Y1468859D03*
Y1473977D03*
Y1479095D03*
X1694842Y1468071D03*
Y1473189D03*
Y1478308D03*
X1703503Y1494449D03*
Y1489331D03*
Y1484213D03*
Y1489331D03*
Y1494449D03*
X1694842Y1483426D03*
Y1488544D03*
Y1493662D03*
Y1498780D03*
X1703503Y1509804D03*
Y1504685D03*
Y1499567D03*
Y1504685D03*
Y1509804D03*
Y1514922D03*
X1694842Y1503898D03*
Y1509016D03*
Y1514134D03*
Y1519252D03*
X1703503Y1560985D03*
Y1555867D03*
Y1560985D03*
X1694842Y1560197D03*
X1703503Y1576339D03*
Y1566103D03*
Y1581457D03*
Y1566103D03*
Y1571221D03*
Y1576339D03*
X1694842Y1565315D03*
Y1570434D03*
Y1575552D03*
X1703503Y1591693D03*
Y1596811D03*
Y1581457D03*
Y1586575D03*
Y1591693D03*
X1694842Y1580670D03*
Y1585788D03*
Y1590906D03*
Y1596024D03*
X1703503Y1612166D03*
Y1607048D03*
Y1596811D03*
Y1601930D03*
Y1607048D03*
Y1612166D03*
X1694842Y1601142D03*
Y1606260D03*
Y1611378D03*
X1703503Y1617284D03*
Y1622402D03*
X1694842Y1616496D03*
Y1621615D03*
X1712165Y1462953D03*
Y1468071D03*
X1720826Y1453504D03*
Y1458622D03*
Y1463741D03*
X1712165Y1452717D03*
Y1457835D03*
Y1462953D03*
Y1478308D03*
Y1483426D03*
X1720826Y1468859D03*
Y1473977D03*
Y1479095D03*
X1712165Y1468071D03*
Y1473189D03*
Y1478308D03*
Y1498780D03*
Y1493662D03*
X1720826Y1484213D03*
Y1489331D03*
Y1494449D03*
X1712165Y1483426D03*
Y1488544D03*
Y1493662D03*
Y1498780D03*
Y1514134D03*
Y1509016D03*
X1720826Y1499567D03*
Y1504685D03*
Y1509804D03*
Y1514922D03*
X1712165Y1503898D03*
Y1509016D03*
Y1514134D03*
Y1519252D03*
Y1565315D03*
X1720826Y1555867D03*
Y1560985D03*
X1712165Y1560197D03*
Y1570434D03*
Y1580670D03*
X1720826Y1566103D03*
Y1571221D03*
Y1576339D03*
X1712165Y1565315D03*
Y1570434D03*
Y1575552D03*
Y1596024D03*
Y1585788D03*
X1720826Y1581457D03*
Y1586575D03*
Y1591693D03*
X1712165Y1580670D03*
Y1585788D03*
Y1590906D03*
Y1596024D03*
Y1611378D03*
Y1601142D03*
X1720826Y1596811D03*
Y1601930D03*
Y1607048D03*
Y1612166D03*
X1712165Y1601142D03*
Y1606260D03*
Y1611378D03*
Y1616496D03*
X1720826Y1617284D03*
Y1622402D03*
X1712165Y1616496D03*
Y1621615D03*
X1729488Y1452717D03*
Y1457835D03*
Y1462953D03*
Y1468071D03*
Y1473189D03*
Y1478308D03*
Y1483426D03*
Y1488544D03*
Y1493662D03*
Y1498780D03*
Y1503898D03*
Y1509016D03*
Y1514134D03*
Y1519252D03*
Y1560197D03*
Y1565315D03*
Y1570434D03*
Y1575552D03*
Y1580670D03*
Y1585788D03*
Y1590906D03*
Y1596024D03*
Y1601142D03*
Y1606260D03*
Y1611378D03*
Y1616496D03*
Y1621615D03*
X2575564Y2358401D03*
X2589291Y2718713D03*
X2609880Y1974066D03*
X2644196Y1260303D03*
Y1610321D03*
X2785168Y666763D03*
Y766213D03*
Y799363D03*
X3481496Y2749598D03*
G54D24*
X173829Y455492D03*
Y583957D03*
X202844Y455492D03*
Y583957D03*
X266841Y421555D03*
Y550020D03*
X295856Y421555D03*
Y550020D03*
X630915Y455492D03*
Y583957D03*
X659930Y455492D03*
Y583957D03*
X723927Y421555D03*
Y550020D03*
X752942Y421555D03*
Y550020D03*
X1088002Y455492D03*
Y583957D03*
X1117017Y455492D03*
Y583957D03*
X1181014Y421555D03*
Y550020D03*
X1210029Y421555D03*
Y550020D03*
X1545089Y455492D03*
Y583957D03*
X1574104Y455492D03*
Y583957D03*
X1638101Y421555D03*
Y550020D03*
X1667116Y421555D03*
Y550020D03*
X2785168Y600463D03*
G54D33*
X1795453Y812874D03*
Y834922D03*
X2785168Y70063D03*
G54D15*
X23622Y1604724D03*
X62205Y765197D03*
X74016Y333464D03*
X102224Y70866D03*
X409488Y1604724D03*
X433130Y70866D03*
X463387Y286221D03*
X463386Y765197D03*
X661674Y23622D03*
X785039Y1547638D03*
X890217Y23622D03*
X920473Y765196D03*
X1055905Y1547637D03*
X1118760Y23622D03*
X1347303Y70866D03*
X1377559Y286220D03*
Y765197D03*
X1431457Y1604724D03*
X1575846Y23622D03*
X1766929Y333464D03*
X1778740Y765197D03*
X1795010Y23622D03*
X1817323Y1604724D03*
X2785168Y434713D03*
G54D25*
X710406Y-26826D03*
Y-36826D03*
D03*
Y-26826D03*
X735406D03*
Y-36826D03*
D03*
Y-26826D03*
X830406Y-76006D03*
D03*
Y-66006D03*
D03*
X855406Y-76006D03*
D03*
Y-66006D03*
D03*
X939542Y-36798D03*
Y-26798D03*
D03*
Y-36798D03*
X964386Y-75978D03*
D03*
Y-65978D03*
D03*
X964542Y-36798D03*
Y-26798D03*
D03*
Y-36798D03*
X989386Y-75978D03*
D03*
Y-65978D03*
D03*
X993906Y-46826D03*
Y-36826D03*
D03*
Y-26826D03*
X1018906Y-46826D03*
Y-36826D03*
D03*
Y-26826D03*
X1063906Y-76006D03*
Y-86006D03*
Y-76006D03*
Y-66006D03*
X1088906Y-76006D03*
Y-86006D03*
Y-76006D03*
Y-66006D03*
X1217686Y-85978D03*
Y-75978D03*
D03*
Y-65978D03*
X1223042Y-46928D03*
Y-36928D03*
Y-26928D03*
Y-36928D03*
X1242686Y-85978D03*
Y-75978D03*
D03*
Y-65978D03*
X1248042Y-46928D03*
Y-36928D03*
Y-26928D03*
Y-36928D03*
X1280406Y-46956D03*
Y-36956D03*
D03*
Y-26956D03*
X1305406Y-46956D03*
Y-36956D03*
D03*
Y-26956D03*
X1320406Y-76006D03*
Y-86006D03*
Y-76006D03*
Y-66006D03*
X1345406Y-76006D03*
Y-86006D03*
Y-76006D03*
Y-66006D03*
X1474186Y-85978D03*
Y-75978D03*
D03*
Y-65978D03*
X1499186Y-85978D03*
Y-75978D03*
D03*
Y-65978D03*
X1509542Y-47058D03*
Y-37058D03*
Y-27058D03*
Y-37058D03*
X1534542Y-47058D03*
Y-37058D03*
Y-27058D03*
Y-37058D03*
X1564906Y-47086D03*
Y-37086D03*
D03*
Y-27086D03*
X1574906Y-76006D03*
Y-86006D03*
Y-76006D03*
Y-66006D03*
X1589906Y-47086D03*
Y-37086D03*
D03*
Y-27086D03*
X1599906Y-76006D03*
Y-86006D03*
Y-76006D03*
Y-66006D03*
X1728686Y-85978D03*
Y-75978D03*
D03*
Y-65978D03*
X1753686Y-85978D03*
Y-75978D03*
D03*
Y-65978D03*
X1794042Y-47188D03*
Y-37188D03*
Y-27188D03*
Y-37188D03*
X1819042Y-47188D03*
Y-37188D03*
Y-27188D03*
Y-37188D03*
X2785168Y368413D03*
G54D34*
X1803917Y823898D03*
X2785168Y36913D03*
G54D16*
X28819Y81575D03*
X73307Y61614D03*
X131181Y81575D03*
X175669Y61614D03*
X233543Y81575D03*
X278032Y61614D03*
X335906Y81575D03*
X380394Y61614D03*
X485886Y81595D03*
X530394Y61614D03*
X588248Y81594D03*
X632756Y61614D03*
X690611Y81595D03*
X735118Y61614D03*
X792973Y81595D03*
X837480Y61614D03*
X942973Y81595D03*
X987480Y61614D03*
X1045335Y81595D03*
X1089843Y61614D03*
X1147697Y81595D03*
X1192205Y61614D03*
X1250060Y81595D03*
X1294567Y61614D03*
X1400060Y81595D03*
X1444567Y61614D03*
X1502441Y81575D03*
X1546929Y61614D03*
X1604784Y81595D03*
X1649291Y61614D03*
X1707146Y81595D03*
X1751654Y61614D03*
X2785168Y534163D03*
G54D17*
X51043Y60709D03*
Y150197D03*
X153405Y60709D03*
Y150197D03*
X190325Y368760D03*
Y455492D03*
Y503760D03*
Y583957D03*
Y636752D03*
X255767Y60709D03*
Y150197D03*
X279360Y368760D03*
Y421555D03*
Y501752D03*
Y550020D03*
Y636752D03*
X358129Y60709D03*
Y150197D03*
X508130Y60709D03*
Y150197D03*
X610492Y60709D03*
Y150197D03*
X647411Y368760D03*
Y455492D03*
Y503760D03*
Y583957D03*
Y636752D03*
X712854Y60709D03*
Y150197D03*
X736446Y368760D03*
Y421555D03*
Y501752D03*
Y550020D03*
Y636752D03*
X815216Y60709D03*
Y150197D03*
X965216Y60709D03*
Y150197D03*
X1067578Y60709D03*
Y150197D03*
X1104498Y368760D03*
Y455492D03*
Y503760D03*
Y583957D03*
Y636752D03*
X1169940Y60709D03*
Y150197D03*
X1193533Y368760D03*
Y421555D03*
Y501752D03*
Y550020D03*
Y636752D03*
X1272302Y60709D03*
Y150197D03*
X1422303Y60709D03*
Y150197D03*
X1524665Y60709D03*
Y150197D03*
X1561585Y368760D03*
Y455492D03*
Y503760D03*
Y583957D03*
Y636752D03*
X1627027Y60709D03*
Y150197D03*
X1650620Y368760D03*
Y421555D03*
Y501752D03*
Y550020D03*
Y636752D03*
X1729389Y60709D03*
Y150197D03*
X2785168Y-29387D03*
Y3763D03*
G54D35*
X1817323Y1567323D03*
X2785168Y235813D03*
G54D26*
X770472Y1490945D03*
X820079Y388583D03*
X1020866D03*
X1070472Y1490945D03*
X2785168Y136363D03*
G54D36*
G01X-67229Y-6250D02*
X-71879D01*
Y6250D01*
X-67229D01*
G01X-48629Y-6250D02*
X-43979D01*
Y6250D01*
X-48629D01*
G01X-10000Y0D02*
X-34604D01*
G01X-20602Y-468335D02*
Y-543335D01*
X479398D01*
Y-468335D01*
X-20602D01*
G01X-8602Y-533335D02*
Y-538335D01*
G01X-10059Y-533335D02*
X-7145D01*
G01X-2235Y-538335D02*
X-4769D01*
Y-533335D01*
X-2235D01*
G01X-3249Y-535752D02*
X-4769D01*
G01X331Y-533335D02*
Y-538335D01*
X2865D01*
G01X6698Y-538502D02*
X6571Y-538418D01*
Y-538252D01*
X6698Y-538168D01*
X6825Y-538252D01*
Y-538418D01*
X6698Y-538502D01*
G01Y-536252D02*
X6571Y-536168D01*
Y-536002D01*
X6698Y-535918D01*
X6825Y-536002D01*
Y-536168D01*
X6698Y-536252D01*
G01X11481Y-540002D02*
X10848Y-539168D01*
X10531Y-538335D01*
Y-535002D01*
X10848Y-534168D01*
X11481Y-533335D01*
G01X16898D02*
X16391Y-533502D01*
X16011Y-533918D01*
X15758Y-534418D01*
X15568Y-535085D01*
X15505Y-535835D01*
X15568Y-536585D01*
X15758Y-537252D01*
X16011Y-537752D01*
X16391Y-538168D01*
X16898Y-538335D01*
X17405Y-538168D01*
X17785Y-537752D01*
X18038Y-537252D01*
X18228Y-536585D01*
X18291Y-535835D01*
X18228Y-535085D01*
X18038Y-534418D01*
X17785Y-533918D01*
X17405Y-533502D01*
X16898Y-533335D01*
G01X20605Y-537335D02*
X20985Y-537918D01*
X21491Y-538252D01*
X22061Y-538335D01*
X22568Y-538252D01*
X23075Y-537835D01*
X23391Y-537335D01*
X23455Y-536835D01*
X23328Y-536252D01*
X22885Y-535835D01*
X22441Y-535668D01*
X21871D01*
G01X22441D02*
X22821Y-535418D01*
X23138Y-535002D01*
X23265Y-534502D01*
X23138Y-534002D01*
X22821Y-533585D01*
X22251Y-533335D01*
X21681Y-533418D01*
X21111Y-533752D01*
G01X27415Y-540002D02*
X28048Y-539168D01*
X28365Y-538335D01*
Y-535002D01*
X28048Y-534168D01*
X27415Y-533335D01*
G01X30805Y-537335D02*
X31185Y-537918D01*
X31691Y-538252D01*
X32261Y-538335D01*
X32768Y-538252D01*
X33275Y-537835D01*
X33591Y-537335D01*
X33655Y-536835D01*
X33528Y-536252D01*
X33085Y-535835D01*
X32641Y-535668D01*
X32071D01*
G01X32641D02*
X33021Y-535418D01*
X33338Y-535002D01*
X33465Y-534502D01*
X33338Y-534002D01*
X33021Y-533585D01*
X32451Y-533335D01*
X31881Y-533418D01*
X31311Y-533752D01*
G01X36095Y-534168D02*
X36475Y-533668D01*
X36918Y-533418D01*
X37425Y-533335D01*
X38058Y-533502D01*
X38501Y-533918D01*
X38628Y-534418D01*
X38565Y-534918D01*
X38311Y-535335D01*
X37045Y-536168D01*
X36475Y-536752D01*
X36095Y-537585D01*
X35968Y-538335D01*
X38628D01*
G01X42271D02*
X42398Y-537252D01*
X42588Y-536335D01*
X42841Y-535502D01*
X43158Y-534585D01*
X43665Y-533335D01*
X41131D01*
G01X46675Y-536668D02*
X48321D01*
G01X51395Y-534168D02*
X51775Y-533668D01*
X52218Y-533418D01*
X52725Y-533335D01*
X53358Y-533502D01*
X53801Y-533918D01*
X53928Y-534418D01*
X53865Y-534918D01*
X53611Y-535335D01*
X52345Y-536168D01*
X51775Y-536752D01*
X51395Y-537585D01*
X51268Y-538335D01*
X53928D01*
G01X56305Y-537335D02*
X56685Y-537918D01*
X57191Y-538252D01*
X57761Y-538335D01*
X58268Y-538252D01*
X58775Y-537835D01*
X59091Y-537335D01*
X59155Y-536835D01*
X59028Y-536252D01*
X58585Y-535835D01*
X58141Y-535668D01*
X57571D01*
G01X58141D02*
X58521Y-535418D01*
X58838Y-535002D01*
X58965Y-534502D01*
X58838Y-534002D01*
X58521Y-533585D01*
X57951Y-533335D01*
X57381Y-533418D01*
X56811Y-533752D01*
G01X63558Y-538335D02*
Y-533335D01*
X61215Y-536918D01*
X64381D01*
G01X66505Y-537585D02*
X66885Y-538002D01*
X67328Y-538252D01*
X67898Y-538335D01*
X68468Y-538168D01*
X68911Y-537835D01*
X69228Y-537252D01*
X69291Y-536585D01*
X69165Y-535918D01*
X68848Y-535502D01*
X68405Y-535168D01*
X67961Y-535085D01*
X67518Y-535168D01*
X66948Y-535502D01*
X67138Y-533335D01*
X68848D01*
G01X76895Y-538335D02*
Y-533335D01*
X79301D01*
G01X78415Y-535752D02*
X76895D01*
G01X81615Y-538335D02*
X83198Y-533335D01*
X84781Y-538335D01*
G01X84211Y-536585D02*
X82185D01*
G01X86968Y-538335D02*
X89628Y-533335D01*
G01X86968D02*
X89628Y-538335D01*
G01X93398Y-538502D02*
X93271Y-538418D01*
Y-538252D01*
X93398Y-538168D01*
X93525Y-538252D01*
Y-538418D01*
X93398Y-538502D01*
G01Y-536252D02*
X93271Y-536168D01*
Y-536002D01*
X93398Y-535918D01*
X93525Y-536002D01*
Y-536168D01*
X93398Y-536252D01*
G01X98181Y-540002D02*
X97548Y-539168D01*
X97231Y-538335D01*
Y-535002D01*
X97548Y-534168D01*
X98181Y-533335D01*
G01X103598D02*
X103091Y-533502D01*
X102711Y-533918D01*
X102458Y-534418D01*
X102268Y-535085D01*
X102205Y-535835D01*
X102268Y-536585D01*
X102458Y-537252D01*
X102711Y-537752D01*
X103091Y-538168D01*
X103598Y-538335D01*
X104105Y-538168D01*
X104485Y-537752D01*
X104738Y-537252D01*
X104928Y-536585D01*
X104991Y-535835D01*
X104928Y-535085D01*
X104738Y-534418D01*
X104485Y-533918D01*
X104105Y-533502D01*
X103598Y-533335D01*
G01X107305Y-537335D02*
X107685Y-537918D01*
X108191Y-538252D01*
X108761Y-538335D01*
X109268Y-538252D01*
X109775Y-537835D01*
X110091Y-537335D01*
X110155Y-536835D01*
X110028Y-536252D01*
X109585Y-535835D01*
X109141Y-535668D01*
X108571D01*
G01X109141D02*
X109521Y-535418D01*
X109838Y-535002D01*
X109965Y-534502D01*
X109838Y-534002D01*
X109521Y-533585D01*
X108951Y-533335D01*
X108381Y-533418D01*
X107811Y-533752D01*
G01X114115Y-540002D02*
X114748Y-539168D01*
X115065Y-538335D01*
Y-535002D01*
X114748Y-534168D01*
X114115Y-533335D01*
G01X117505Y-537335D02*
X117885Y-537918D01*
X118391Y-538252D01*
X118961Y-538335D01*
X119468Y-538252D01*
X119975Y-537835D01*
X120291Y-537335D01*
X120355Y-536835D01*
X120228Y-536252D01*
X119785Y-535835D01*
X119341Y-535668D01*
X118771D01*
G01X119341D02*
X119721Y-535418D01*
X120038Y-535002D01*
X120165Y-534502D01*
X120038Y-534002D01*
X119721Y-533585D01*
X119151Y-533335D01*
X118581Y-533418D01*
X118011Y-533752D01*
G01X122921Y-537752D02*
X123365Y-538168D01*
X123871Y-538335D01*
X124378Y-538168D01*
X124821Y-537668D01*
X125138Y-536918D01*
X125265Y-536168D01*
Y-535252D01*
X125138Y-534502D01*
X124821Y-533835D01*
X124441Y-533502D01*
X123998Y-533335D01*
X123491Y-533502D01*
X123111Y-533835D01*
X122858Y-534335D01*
X122731Y-535002D01*
X122858Y-535585D01*
X123175Y-536168D01*
X123555Y-536502D01*
X123998Y-536585D01*
X124505Y-536418D01*
X124885Y-536002D01*
X125265Y-535252D01*
G01X128971Y-538335D02*
X129098Y-537252D01*
X129288Y-536335D01*
X129541Y-535502D01*
X129858Y-534585D01*
X130365Y-533335D01*
X127831D01*
G01X133375Y-536668D02*
X135021D01*
G01X137905Y-537335D02*
X138285Y-537918D01*
X138791Y-538252D01*
X139361Y-538335D01*
X139868Y-538252D01*
X140375Y-537835D01*
X140691Y-537335D01*
X140755Y-536835D01*
X140628Y-536252D01*
X140185Y-535835D01*
X139741Y-535668D01*
X139171D01*
G01X139741D02*
X140121Y-535418D01*
X140438Y-535002D01*
X140565Y-534502D01*
X140438Y-534002D01*
X140121Y-533585D01*
X139551Y-533335D01*
X138981Y-533418D01*
X138411Y-533752D01*
G01X143195Y-536252D02*
X143638Y-535668D01*
X144018Y-535335D01*
X144525Y-535168D01*
X144968Y-535335D01*
X145285Y-535668D01*
X145538Y-536168D01*
X145601Y-536752D01*
X145538Y-537252D01*
X145285Y-537752D01*
X144905Y-538168D01*
X144461Y-538335D01*
X143955Y-538168D01*
X143511Y-537668D01*
X143258Y-536918D01*
X143195Y-536085D01*
X143321Y-535002D01*
X143511Y-534418D01*
X143828Y-533835D01*
X144271Y-533418D01*
X144715Y-533335D01*
X145158Y-533502D01*
X145475Y-533918D01*
G01X149498Y-538335D02*
Y-533335D01*
X148738Y-534335D01*
G01Y-538335D02*
X150258D01*
G01X155358D02*
Y-533335D01*
X153015Y-536918D01*
X156181D01*
G01X6250Y-68232D02*
Y-72882D01*
X-6250D01*
Y-68232D01*
G01X6250Y-49632D02*
Y-44982D01*
X-6250D01*
Y-49632D01*
G01X0Y-10000D02*
Y-35607D01*
G01X795131Y1645405D02*
G03X789296Y1647992I-5835J-5287D01*
G01X7874D01*
G03X0Y1640118I0J-7874D01*
G01Y970427D01*
G03X2306Y964859I7874J0D01*
G01X12654Y954511D01*
G02X14961Y948943I-5568J-5569D01*
G01Y344836D01*
G02X12654Y339269I-7873J1D01*
G01X2306Y328920D01*
G03X0Y323353I5567J-5567D01*
G01Y7874D01*
G03X7874Y0I7874J0D01*
G01X23484D01*
G03X31358Y7874I0J7874D01*
G01Y46654D01*
G02X35295Y50591I3937J0D01*
G01X66791D01*
G02X70728Y46654I0J-3937D01*
G01Y7874D01*
G03X78602Y0I7874J0D01*
G01X125846D01*
G03X133720Y7874I0J7874D01*
G01Y46654D01*
G02X137657Y50591I3937J0D01*
G01X169154D01*
G02X173091Y46654I0J-3937D01*
G01Y7874D01*
G03X180965Y0I7874J0D01*
G01X228209D01*
G03X236083Y7874I0J7874D01*
G01Y46654D01*
G02X240020Y50591I3937J0D01*
G01X271516D01*
G02X275453Y46654I0J-3937D01*
G01Y7874D01*
G03X283327Y0I7874J0D01*
G01X330571D01*
G03X338445Y7874I0J7874D01*
G01Y46654D01*
G02X342382Y50591I3937J0D01*
G01X373878D01*
G02X377815Y46654I0J-3937D01*
G01Y7874D01*
G03X385689Y0I7874J0D01*
G01X480571D01*
G03X488445Y7874I0J7874D01*
G01Y46654D01*
G02X492382Y50591I3937J0D01*
G01X523878D01*
G02X527815Y46654I0J-3937D01*
G01Y7874D01*
G03X535689Y0I7874J0D01*
G01X582933D01*
G03X590807Y7874I0J7874D01*
G01Y46654D01*
G02X594744Y50591I3937J0D01*
G01X626240D01*
G02X630177Y46654I0J-3937D01*
G01Y7874D01*
G03X638051Y0I7874J0D01*
G01X685295D01*
G03X693169Y7874I0J7874D01*
G01Y46654D01*
G02X697106Y50591I3937J0D01*
G01X728602D01*
G02X732539Y46654I0J-3937D01*
G01Y7874D01*
G03X740413Y0I7874J0D01*
G01X787657D01*
G03X795531Y7874I0J7874D01*
G01Y46654D01*
G02X799469Y50591I3937J0D01*
G01X830965D01*
G02X834902Y46654I0J-3937D01*
G01Y7874D01*
G03X842776Y0I7874J0D01*
G01X937657D01*
G03X945531Y7874I0J7874D01*
G01Y46654D01*
G02X949469Y50591I3938J0D01*
G01X980965D01*
G02X984902Y46654I0J-3937D01*
G01Y7874D01*
G03X992776Y0I7874J0D01*
G01X1040020D01*
G03X1047894Y7874I0J7874D01*
G01Y46654D01*
G02X1051831Y50591I3937J0D01*
G01X1083327D01*
G02X1087264Y46654I0J-3937D01*
G01Y7874D01*
G03X1095138Y0I7874J0D01*
G01X1142382D01*
G03X1150256Y7874I0J7874D01*
G01Y46654D01*
G02X1154193Y50591I3937J0D01*
G01X1185689D01*
G02X1189626Y46654I0J-3937D01*
G01Y7874D01*
G03X1197500Y0I7874J0D01*
G01X1244744D01*
G03X1252618Y7874I0J7874D01*
G01Y46654D01*
G02X1256555Y50591I3937J0D01*
G01X1288051D01*
G02X1291988Y46654I0J-3937D01*
G01Y7874D01*
G03X1299862Y0I7874J0D01*
G01X1394744D01*
G03X1402618Y7874I0J7874D01*
G01Y46654D01*
G02X1406555Y50591I3937J0D01*
G01X1438051D01*
G02X1441988Y46654I0J-3937D01*
G01Y7874D01*
G03X1449862Y0I7874J0D01*
G01X1497106D01*
G03X1504980Y7874I0J7874D01*
G01Y46654D01*
G02X1508917Y50591I3937J0D01*
G01X1540413D01*
G02X1544350Y46654I0J-3937D01*
G01Y7874D01*
G03X1552224Y0I7874J0D01*
G01X1599469D01*
G03X1607343Y7874I0J7874D01*
G01Y46654D01*
G02X1611280Y50591I3937J0D01*
G01X1642776D01*
G02X1646713Y46654I0J-3937D01*
G01Y7874D01*
G03X1654587Y0I7874J0D01*
G01X1701831D01*
G03X1709705Y7874I0J7874D01*
G01Y46654D01*
G02X1713642Y50591I3937J0D01*
G01X1745138D01*
G02X1749075Y46654I0J-3937D01*
G01Y7874D01*
G03X1756949Y0I7874J0D01*
G01X1833071D01*
G03X1840945Y7874I0J7874D01*
G01Y323353D01*
G03X1838639Y328920I-7873J0D01*
G01X1828291Y339269D01*
G02X1825984Y344836I5566J5568D01*
G01Y948943D01*
G02X1828291Y954511I7875J-1D01*
G01X1838639Y964859D01*
G03X1840945Y970427I-5568J5568D01*
G01Y1640118D01*
G03X1833071Y1647992I-7874J0D01*
G01X1081727D01*
G03X1075892Y1645405I0J-7874D01*
G02X1070057Y1642819I-5834J5288D01*
G01X800966D01*
G02X795131Y1645405I-1J7874D01*
G01X20472Y1567322D02*
X-8447Y1564071D01*
G01X0Y1657992D02*
Y1857992D01*
G01X7000Y1689571D02*
X0Y1688071D01*
X7000Y1686571D01*
Y1689571D01*
G01D02*
X0Y1688071D01*
X7000Y1686571D01*
Y1689571D01*
G01X0Y1761825D02*
Y1820880D01*
G01X31496Y1761825D02*
X0D01*
G01Y1820880D02*
X31496D01*
G01X742748Y1847992D02*
X0D01*
G01X7000Y1849492D02*
X0Y1847992D01*
X7000Y1846492D01*
Y1849492D01*
G01X7480Y1226024D02*
G02X20079I6299J0D01*
G02X7480I-6299J0D01*
G01X20472Y1573425D02*
X26772D01*
G02Y1561220I0J-6103D01*
G01X20472D01*
G02Y1573425I0J6102D01*
G01X13683Y1565049D02*
X20472Y1567322D01*
X13348Y1568031D01*
X13683Y1565049D01*
G01X12598Y1604724D02*
G02X34646I11024J0D01*
G02X12598I-11024J0D01*
G01X8050Y1762763D02*
X4950D01*
Y1763683D01*
X5105Y1763990D01*
X5467Y1764220D01*
X5880Y1764297D01*
X6293Y1764220D01*
X6603Y1764028D01*
X6758Y1763683D01*
Y1762763D01*
G01X5208Y1767473D02*
X5053Y1767243D01*
X4950Y1766975D01*
Y1766668D01*
X5105Y1766323D01*
X5363Y1766055D01*
X5673Y1765863D01*
X6190Y1765710D01*
X6655Y1765672D01*
X7120Y1765748D01*
X7430Y1765863D01*
X7740Y1766093D01*
X7947Y1766362D01*
X8050Y1766630D01*
Y1766898D01*
X7947Y1767167D01*
X7792Y1767397D01*
X7585Y1767588D01*
G01X6397Y1770037D02*
X6242Y1770190D01*
X5983Y1770305D01*
X5622Y1770382D01*
X5312Y1770305D01*
X5105Y1770152D01*
X4950Y1769883D01*
Y1768848D01*
X8050D01*
Y1770113D01*
X7843Y1770382D01*
X7533Y1770535D01*
X7172Y1770612D01*
X6810Y1770535D01*
X6500Y1770305D01*
X6397Y1770037D01*
Y1768848D01*
G01X4950Y1774972D02*
X8050Y1775930D01*
X4950Y1776888D01*
G01X8050Y1779797D02*
Y1778263D01*
X4950D01*
Y1779797D01*
G01X6448Y1779183D02*
Y1778263D01*
G01X8050Y1781248D02*
X4950D01*
X8050Y1783012D01*
X4950D01*
G01X8050Y1784387D02*
X4950D01*
Y1785153D01*
X5105Y1785460D01*
X5312Y1785690D01*
X5622Y1785882D01*
X5983Y1786035D01*
X6500Y1786073D01*
X7017Y1786035D01*
X7378Y1785882D01*
X7688Y1785690D01*
X7895Y1785460D01*
X8050Y1785153D01*
Y1784387D01*
G01Y1788330D02*
X7998Y1788023D01*
X7792Y1787755D01*
X7482Y1787525D01*
X7120Y1787372D01*
X6707Y1787295D01*
X6293D01*
X5880Y1787372D01*
X5518Y1787525D01*
X5208Y1787755D01*
X5002Y1788023D01*
X4950Y1788330D01*
X5002Y1788637D01*
X5208Y1788905D01*
X5518Y1789135D01*
X5880Y1789288D01*
X6293Y1789365D01*
X6707D01*
X7120Y1789288D01*
X7482Y1789135D01*
X7792Y1788905D01*
X7998Y1788637D01*
X8050Y1788330D01*
G01Y1790663D02*
X4950D01*
Y1791622D01*
X5105Y1791928D01*
X5312Y1792120D01*
X5725Y1792197D01*
X6138Y1792120D01*
X6397Y1791890D01*
X6552Y1791622D01*
Y1790663D01*
G01Y1791622D02*
X8050Y1792197D01*
G01X10350Y1771163D02*
X13450D01*
Y1772697D01*
G01Y1775030D02*
X13398Y1774723D01*
X13192Y1774455D01*
X12882Y1774225D01*
X12520Y1774072D01*
X12107Y1773995D01*
X11693D01*
X11280Y1774072D01*
X10918Y1774225D01*
X10608Y1774455D01*
X10402Y1774723D01*
X10350Y1775030D01*
X10402Y1775337D01*
X10608Y1775605D01*
X10918Y1775835D01*
X11280Y1775988D01*
X11693Y1776065D01*
X12107D01*
X12520Y1775988D01*
X12882Y1775835D01*
X13192Y1775605D01*
X13398Y1775337D01*
X13450Y1775030D01*
G01X11900Y1778360D02*
Y1779127D01*
X12830D01*
X13140Y1778897D01*
X13347Y1778628D01*
X13450Y1778245D01*
X13347Y1777862D01*
X13140Y1777593D01*
X12830Y1777363D01*
X12468Y1777210D01*
X12055Y1777133D01*
X11693D01*
X11383Y1777210D01*
X11022Y1777363D01*
X10712Y1777593D01*
X10505Y1777823D01*
X10350Y1778130D01*
Y1778398D01*
X10453Y1778705D01*
X10660Y1778935D01*
G01X13450Y1781230D02*
X13398Y1780923D01*
X13192Y1780655D01*
X12882Y1780425D01*
X12520Y1780272D01*
X12107Y1780195D01*
X11693D01*
X11280Y1780272D01*
X10918Y1780425D01*
X10608Y1780655D01*
X10402Y1780923D01*
X10350Y1781230D01*
X10402Y1781537D01*
X10608Y1781805D01*
X10918Y1782035D01*
X11280Y1782188D01*
X11693Y1782265D01*
X12107D01*
X12520Y1782188D01*
X12882Y1782035D01*
X13192Y1781805D01*
X13398Y1781537D01*
X13450Y1781230D01*
G01X24882Y81575D02*
G02X32756I3937J0D01*
G02X24882I-3937J0D01*
G01X31496Y1820880D02*
Y1761825D01*
G01X51181Y765197D02*
G02X73228I11023J0D01*
G02X51181I-11024J0D01*
G01X62992Y333465D02*
G02X85039I11024J0D01*
G02X62992I-11023J0D01*
G01X69370Y61614D02*
G02X77244I3937J0D01*
G02X69370I-3937J0D01*
G01X73031Y1186654D02*
G02X85630I6299J0D01*
G02X73031I-6300J0D01*
G01X91201Y70866D02*
G02X113248I11024J0D01*
G02X91201I-11023J0D01*
G01X99302Y967455D02*
X158357D01*
Y935959D01*
X99302D01*
Y967455D01*
G01X107874Y1066535D02*
G02X125591I8859J0D01*
G02X107874I-8858J0D01*
G01Y1263386D02*
G02X125591I8859J0D01*
G02X107874I-8858J0D01*
G01X107082Y1617502D02*
Y1626602D01*
X190782D01*
Y1449502D01*
X107082D01*
Y1617502D01*
G01X129493Y-322457D02*
Y-327107D01*
X116993D01*
Y-322457D01*
G01X129493Y-254257D02*
Y-249607D01*
X116993D01*
Y-254257D01*
G01X116731Y1253386D02*
Y-177446D01*
X126605Y-233645D01*
X126394Y-240232D01*
G01X127244Y81575D02*
G02X135118I3937J0D01*
G02X127244I-3937J0D01*
G01X126731Y1066535D02*
X2083393D01*
G01X126731Y1263386D02*
X2093000D01*
G01X152710Y1697631D02*
X127758Y1624222D01*
X129483Y1626301D01*
X127689Y1626823D01*
X127758Y1624222D01*
G01X162882Y1696402D02*
X137930Y1622993D01*
X139655Y1625072D01*
X137861Y1625594D01*
X137930Y1622993D01*
G01X174398Y-468335D02*
Y-543335D01*
G01Y-518335D02*
X277398D01*
Y-493335D01*
G01X174398D02*
X277398D01*
G01X171732Y61614D02*
G02X179606I3937J0D01*
G02X171732I-3937J0D01*
G01X229606Y81575D02*
G02X237480I3937J0D01*
G02X229606I-3937J0D01*
G01X241644Y1580079D02*
G02X229144I-6250J0D01*
G02X241644I6250J0D01*
G01X241683Y1606142D02*
G02X229183I-6250J0D01*
G02X241683I6250J0D01*
G01X241644Y1626339D02*
G02X229144I-6250J0D01*
G02X241644I6250J0D01*
G01X237227Y2677354D02*
X224727D01*
X227227Y2675494D01*
G01X237227D02*
Y2679214D01*
G01X224727Y2689754D02*
X225144Y2688514D01*
X226185Y2687584D01*
X227435Y2686964D01*
X229102Y2686499D01*
X230977Y2686344D01*
X232852Y2686499D01*
X234519Y2686964D01*
X235769Y2687584D01*
X236810Y2688514D01*
X237227Y2689754D01*
X236810Y2690994D01*
X235769Y2691924D01*
X234519Y2692544D01*
X232852Y2693009D01*
X230977Y2693164D01*
X229102Y2693009D01*
X227435Y2692544D01*
X226185Y2691924D01*
X225144Y2690994D01*
X224727Y2689754D01*
G01X237227Y2698124D02*
X224727D01*
X235144Y2702154D01*
X224727Y2706184D01*
X237227D01*
G01Y2710524D02*
X224727D01*
X235144Y2714554D01*
X224727Y2718584D01*
X237227D01*
G01X246086Y2682174D02*
Y2650678D01*
G01D02*
Y2701859D01*
G01X312316Y2682174D02*
X238212D01*
G01X246086Y2753040D02*
Y2701859D01*
G01Y2721544D02*
Y2753040D01*
G01X311462Y2721544D02*
X238212D01*
G01X235456Y2932722D02*
Y2940722D01*
X234256Y2939122D01*
G01Y2932722D02*
X236656D01*
G01X243456Y2940722D02*
X242656Y2940455D01*
X242056Y2939789D01*
X241656Y2938989D01*
X241356Y2937922D01*
X241256Y2936722D01*
X241356Y2935522D01*
X241656Y2934455D01*
X242056Y2933655D01*
X242656Y2932989D01*
X243456Y2932722D01*
X244256Y2932989D01*
X244856Y2933655D01*
X245256Y2934455D01*
X245556Y2935522D01*
X245656Y2936722D01*
X245556Y2937922D01*
X245256Y2938989D01*
X244856Y2939789D01*
X244256Y2940455D01*
X243456Y2940722D01*
G01X251456Y2932455D02*
X251256Y2932589D01*
Y2932855D01*
X251456Y2932989D01*
X251656Y2932855D01*
Y2932589D01*
X251456Y2932455D01*
G01X257556Y2932722D02*
Y2940722D01*
X261356D01*
G01X259956Y2936855D02*
X257556D01*
G01X267456Y2932722D02*
X266656Y2932855D01*
X265956Y2933389D01*
X265356Y2934189D01*
X264956Y2935122D01*
X264756Y2936189D01*
Y2937255D01*
X264956Y2938322D01*
X265356Y2939255D01*
X265956Y2940055D01*
X266656Y2940589D01*
X267456Y2940722D01*
X268256Y2940589D01*
X268956Y2940055D01*
X269556Y2939255D01*
X269956Y2938322D01*
X270156Y2937255D01*
Y2936189D01*
X269956Y2935122D01*
X269556Y2934189D01*
X268956Y2933389D01*
X268256Y2932855D01*
X267456Y2932722D01*
G01X273456D02*
Y2940722D01*
X275956D01*
X276756Y2940322D01*
X277256Y2939789D01*
X277456Y2938722D01*
X277256Y2937655D01*
X276656Y2936989D01*
X275956Y2936589D01*
X273456D01*
G01X275956D02*
X277456Y2932722D01*
G01X291456Y2940722D02*
Y2932722D01*
G01X289156Y2940722D02*
X293756D01*
G01X297356Y2932722D02*
Y2940722D01*
G01X301556D02*
Y2932722D01*
G01Y2936722D02*
X297356D01*
G01X309456Y2932722D02*
X305456D01*
Y2940722D01*
X309456D01*
G01X307856Y2936855D02*
X305456D01*
G01X321456Y2932722D02*
Y2940722D01*
X323856D01*
X324656Y2940322D01*
X325256Y2939389D01*
X325456Y2938322D01*
X325256Y2937255D01*
X324756Y2936455D01*
X323856Y2936055D01*
X321456D01*
G01X331456Y2940722D02*
Y2932722D01*
G01X329156Y2940722D02*
X333756D01*
G01X337356Y2932722D02*
Y2940722D01*
G01X341556D02*
Y2932722D01*
G01Y2936722D02*
X337356D01*
G01X355456Y2940722D02*
Y2932722D01*
G01X353156Y2940722D02*
X357756D01*
G01X363456Y2932722D02*
X362656Y2932855D01*
X361956Y2933389D01*
X361356Y2934189D01*
X360956Y2935122D01*
X360756Y2936189D01*
Y2937255D01*
X360956Y2938322D01*
X361356Y2939255D01*
X361956Y2940055D01*
X362656Y2940589D01*
X363456Y2940722D01*
X364256Y2940589D01*
X364956Y2940055D01*
X365556Y2939255D01*
X365956Y2938322D01*
X366156Y2937255D01*
Y2936189D01*
X365956Y2935122D01*
X365556Y2934189D01*
X364956Y2933389D01*
X364256Y2932855D01*
X363456Y2932722D01*
G01X371456D02*
X370656Y2932855D01*
X369956Y2933389D01*
X369356Y2934189D01*
X368956Y2935122D01*
X368756Y2936189D01*
Y2937255D01*
X368956Y2938322D01*
X369356Y2939255D01*
X369956Y2940055D01*
X370656Y2940589D01*
X371456Y2940722D01*
X372256Y2940589D01*
X372956Y2940055D01*
X373556Y2939255D01*
X373956Y2938322D01*
X374156Y2937255D01*
Y2936189D01*
X373956Y2935122D01*
X373556Y2934189D01*
X372956Y2933389D01*
X372256Y2932855D01*
X371456Y2932722D01*
G01X377456Y2940722D02*
Y2932722D01*
X381456D01*
G01X386256Y2940722D02*
X388656D01*
G01X387456D02*
Y2932722D01*
G01X386256D02*
X388656D01*
G01X393156D02*
Y2940722D01*
X397756Y2932722D01*
Y2940722D01*
G01X404056Y2936722D02*
X406056D01*
Y2934322D01*
X405456Y2933522D01*
X404756Y2932989D01*
X403756Y2932722D01*
X402756Y2932989D01*
X402056Y2933522D01*
X401456Y2934322D01*
X401056Y2935255D01*
X400856Y2936322D01*
Y2937255D01*
X401056Y2938055D01*
X401456Y2938989D01*
X402056Y2939789D01*
X402656Y2940322D01*
X403456Y2940722D01*
X404156D01*
X404956Y2940455D01*
X405556Y2939922D01*
G01X417356Y2932722D02*
Y2940722D01*
G01X421556D02*
Y2932722D01*
G01Y2936722D02*
X417356D01*
G01X427456Y2932722D02*
X426656Y2932855D01*
X425956Y2933389D01*
X425356Y2934189D01*
X424956Y2935122D01*
X424756Y2936189D01*
Y2937255D01*
X424956Y2938322D01*
X425356Y2939255D01*
X425956Y2940055D01*
X426656Y2940589D01*
X427456Y2940722D01*
X428256Y2940589D01*
X428956Y2940055D01*
X429556Y2939255D01*
X429956Y2938322D01*
X430156Y2937255D01*
Y2936189D01*
X429956Y2935122D01*
X429556Y2934189D01*
X428956Y2933389D01*
X428256Y2932855D01*
X427456Y2932722D01*
G01X433456Y2940722D02*
Y2932722D01*
X437456D01*
G01X445456D02*
X441456D01*
Y2940722D01*
X445456D01*
G01X443856Y2936855D02*
X441456D01*
G01X449356Y2933788D02*
X450156Y2933122D01*
X451056Y2932722D01*
X451856D01*
X452656Y2933122D01*
X453256Y2933788D01*
X453556Y2934722D01*
X453356Y2935655D01*
X452856Y2936455D01*
X451956Y2936989D01*
X450756Y2937255D01*
X450056Y2937789D01*
X449756Y2938722D01*
X449956Y2939655D01*
X450456Y2940322D01*
X451156Y2940722D01*
X451856D01*
X452556Y2940455D01*
X453156Y2939789D01*
G01X464456Y2940722D02*
X465856Y2932722D01*
X467456Y2940722D01*
X469056Y2932722D01*
X470456Y2940722D01*
G01X473356Y2932722D02*
Y2940722D01*
G01X477556D02*
Y2932722D01*
G01Y2936722D02*
X473356D01*
G01X482256Y2940722D02*
X484656D01*
G01X483456D02*
Y2932722D01*
G01X482256D02*
X484656D01*
G01X493656Y2940055D02*
X493056Y2940455D01*
X492356Y2940722D01*
X491556D01*
X490656Y2940322D01*
X489956Y2939655D01*
X489456Y2938855D01*
X489056Y2937522D01*
X488956Y2936322D01*
X489156Y2935122D01*
X489456Y2934322D01*
X490056Y2933522D01*
X490756Y2932989D01*
X491456Y2932722D01*
X492156D01*
X492856Y2932989D01*
X493456Y2933389D01*
X493956Y2933922D01*
G01X497356Y2932722D02*
Y2940722D01*
G01X501556D02*
Y2932722D01*
G01Y2936722D02*
X497356D01*
G01X513356Y2933788D02*
X514156Y2933122D01*
X515056Y2932722D01*
X515856D01*
X516656Y2933122D01*
X517256Y2933788D01*
X517556Y2934722D01*
X517356Y2935655D01*
X516856Y2936455D01*
X515956Y2936989D01*
X514756Y2937255D01*
X514056Y2937789D01*
X513756Y2938722D01*
X513956Y2939655D01*
X514456Y2940322D01*
X515156Y2940722D01*
X515856D01*
X516556Y2940455D01*
X517156Y2939789D01*
G01X522256Y2940722D02*
X524656D01*
G01X523456D02*
Y2932722D01*
G01X522256D02*
X524656D01*
G01X529556Y2940722D02*
X533356D01*
X529556Y2932722D01*
X533356D01*
G01X541456D02*
X537456D01*
Y2940722D01*
X541456D01*
G01X539856Y2936855D02*
X537456D01*
G01X554256Y2940722D02*
X556656D01*
G01X555456D02*
Y2932722D01*
G01X554256D02*
X556656D01*
G01X561356Y2933788D02*
X562156Y2933122D01*
X563056Y2932722D01*
X563856D01*
X564656Y2933122D01*
X565256Y2933788D01*
X565556Y2934722D01*
X565356Y2935655D01*
X564856Y2936455D01*
X563956Y2936989D01*
X562756Y2937255D01*
X562056Y2937789D01*
X561756Y2938722D01*
X561956Y2939655D01*
X562456Y2940322D01*
X563156Y2940722D01*
X563856D01*
X564556Y2940455D01*
X565156Y2939789D01*
G01X581456Y2932722D02*
X577456D01*
Y2940722D01*
X581456D01*
G01X579856Y2936855D02*
X577456D01*
G01X587456Y2932722D02*
X586656Y2932855D01*
X585956Y2933389D01*
X585356Y2934189D01*
X584956Y2935122D01*
X584756Y2936189D01*
Y2937255D01*
X584956Y2938322D01*
X585356Y2939255D01*
X585956Y2940055D01*
X586656Y2940589D01*
X587456Y2940722D01*
X588256Y2940589D01*
X588956Y2940055D01*
X589556Y2939255D01*
X589956Y2938322D01*
X590156Y2937255D01*
Y2936189D01*
X589956Y2935122D01*
X589556Y2934189D01*
X588956Y2933389D01*
X588256Y2932855D01*
X587456Y2932722D01*
G01X588256Y2934855D02*
X589456Y2932722D01*
G01X593256Y2940722D02*
Y2934989D01*
X593656Y2933788D01*
X594456Y2932989D01*
X595456Y2932722D01*
X596456Y2932989D01*
X597256Y2933788D01*
X597656Y2934989D01*
Y2940722D01*
G01X600956Y2932722D02*
X603456Y2940722D01*
X605956Y2932722D01*
G01X605056Y2935522D02*
X601856D01*
G01X609456Y2940722D02*
Y2932722D01*
X613456D01*
G01X627456Y2940722D02*
Y2932722D01*
G01X625156Y2940722D02*
X629756D01*
G01X635456Y2932722D02*
X634656Y2932855D01*
X633956Y2933389D01*
X633356Y2934189D01*
X632956Y2935122D01*
X632756Y2936189D01*
Y2937255D01*
X632956Y2938322D01*
X633356Y2939255D01*
X633956Y2940055D01*
X634656Y2940589D01*
X635456Y2940722D01*
X636256Y2940589D01*
X636956Y2940055D01*
X637556Y2939255D01*
X637956Y2938322D01*
X638156Y2937255D01*
Y2936189D01*
X637956Y2935122D01*
X637556Y2934189D01*
X636956Y2933389D01*
X636256Y2932855D01*
X635456Y2932722D01*
G01X651456D02*
X650656Y2932855D01*
X649956Y2933389D01*
X649356Y2934189D01*
X648956Y2935122D01*
X648756Y2936189D01*
Y2937255D01*
X648956Y2938322D01*
X649356Y2939255D01*
X649956Y2940055D01*
X650656Y2940589D01*
X651456Y2940722D01*
X652256Y2940589D01*
X652956Y2940055D01*
X653556Y2939255D01*
X653956Y2938322D01*
X654156Y2937255D01*
Y2936189D01*
X653956Y2935122D01*
X653556Y2934189D01*
X652956Y2933389D01*
X652256Y2932855D01*
X651456Y2932722D01*
G01X657456D02*
Y2940722D01*
X659956D01*
X660756Y2940322D01*
X661256Y2939789D01*
X661456Y2938722D01*
X661256Y2937655D01*
X660656Y2936989D01*
X659956Y2936589D01*
X657456D01*
G01X659956D02*
X661456Y2932722D01*
G01X672856D02*
Y2940722D01*
X675456Y2934055D01*
X678056Y2940722D01*
Y2932722D01*
G01X683456D02*
X682656Y2932855D01*
X681956Y2933389D01*
X681356Y2934189D01*
X680956Y2935122D01*
X680756Y2936189D01*
Y2937255D01*
X680956Y2938322D01*
X681356Y2939255D01*
X681956Y2940055D01*
X682656Y2940589D01*
X683456Y2940722D01*
X684256Y2940589D01*
X684956Y2940055D01*
X685556Y2939255D01*
X685956Y2938322D01*
X686156Y2937255D01*
Y2936189D01*
X685956Y2935122D01*
X685556Y2934189D01*
X684956Y2933389D01*
X684256Y2932855D01*
X683456Y2932722D01*
G01X689456D02*
Y2940722D01*
X691956D01*
X692756Y2940322D01*
X693256Y2939789D01*
X693456Y2938722D01*
X693256Y2937655D01*
X692656Y2936989D01*
X691956Y2936589D01*
X689456D01*
G01X691956D02*
X693456Y2932722D01*
G01X701456D02*
X697456D01*
Y2940722D01*
X701456D01*
G01X699856Y2936855D02*
X697456D01*
G01X715456Y2940722D02*
Y2932722D01*
G01X713156Y2940722D02*
X717756D01*
G01X721356Y2932722D02*
Y2940722D01*
G01X725556D02*
Y2932722D01*
G01Y2936722D02*
X721356D01*
G01X728956Y2932722D02*
X731456Y2940722D01*
X733956Y2932722D01*
G01X733056Y2935522D02*
X729856D01*
G01X737156Y2932722D02*
Y2940722D01*
X741756Y2932722D01*
Y2940722D01*
G01X755256Y2932722D02*
X755456Y2934455D01*
X755756Y2935922D01*
X756156Y2937255D01*
X756656Y2938722D01*
X757456Y2940722D01*
X753456D01*
G01X763456D02*
X762656Y2940455D01*
X762056Y2939789D01*
X761656Y2938989D01*
X761356Y2937922D01*
X761256Y2936722D01*
X761356Y2935522D01*
X761656Y2934455D01*
X762056Y2933655D01*
X762656Y2932989D01*
X763456Y2932722D01*
X764256Y2932989D01*
X764856Y2933655D01*
X765256Y2934455D01*
X765556Y2935522D01*
X765656Y2936722D01*
X765556Y2937922D01*
X765256Y2938989D01*
X764856Y2939789D01*
X764256Y2940455D01*
X763456Y2940722D01*
G01X776856Y2932722D02*
Y2940722D01*
X779456Y2934055D01*
X782056Y2940722D01*
Y2932722D01*
G01X786256Y2940722D02*
X788656D01*
G01X787456D02*
Y2932722D01*
G01X786256D02*
X788656D01*
G01X793456Y2940722D02*
Y2932722D01*
X797456D01*
G01X803456Y2932455D02*
X803256Y2932589D01*
Y2932855D01*
X803456Y2932989D01*
X803656Y2932855D01*
Y2932589D01*
X803456Y2932455D01*
G01X825156Y2932722D02*
Y2940722D01*
X829756Y2932722D01*
Y2940722D01*
G01X835456Y2932722D02*
X834656Y2932855D01*
X833956Y2933389D01*
X833356Y2934189D01*
X832956Y2935122D01*
X832756Y2936189D01*
Y2937255D01*
X832956Y2938322D01*
X833356Y2939255D01*
X833956Y2940055D01*
X834656Y2940589D01*
X835456Y2940722D01*
X836256Y2940589D01*
X836956Y2940055D01*
X837556Y2939255D01*
X837956Y2938322D01*
X838156Y2937255D01*
Y2936189D01*
X837956Y2935122D01*
X837556Y2934189D01*
X836956Y2933389D01*
X836256Y2932855D01*
X835456Y2932722D01*
G01X841156D02*
Y2940722D01*
X845756Y2932722D01*
Y2940722D01*
G01X850156Y2935389D02*
X852756D01*
G01X857556Y2932722D02*
Y2940722D01*
X861356D01*
G01X859956Y2936855D02*
X857556D01*
G01X865256Y2940722D02*
Y2934989D01*
X865656Y2933788D01*
X866456Y2932989D01*
X867456Y2932722D01*
X868456Y2932989D01*
X869256Y2933788D01*
X869656Y2934989D01*
Y2940722D01*
G01X873156Y2932722D02*
Y2940722D01*
X877756Y2932722D01*
Y2940722D01*
G01X885656Y2940055D02*
X885056Y2940455D01*
X884356Y2940722D01*
X883556D01*
X882656Y2940322D01*
X881956Y2939655D01*
X881456Y2938855D01*
X881056Y2937522D01*
X880956Y2936322D01*
X881156Y2935122D01*
X881456Y2934322D01*
X882056Y2933522D01*
X882756Y2932989D01*
X883456Y2932722D01*
X884156D01*
X884856Y2932989D01*
X885456Y2933389D01*
X885956Y2933922D01*
G01X891456Y2940722D02*
Y2932722D01*
G01X889156Y2940722D02*
X893756D01*
G01X898256D02*
X900656D01*
G01X899456D02*
Y2932722D01*
G01X898256D02*
X900656D01*
G01X907456D02*
X906656Y2932855D01*
X905956Y2933389D01*
X905356Y2934189D01*
X904956Y2935122D01*
X904756Y2936189D01*
Y2937255D01*
X904956Y2938322D01*
X905356Y2939255D01*
X905956Y2940055D01*
X906656Y2940589D01*
X907456Y2940722D01*
X908256Y2940589D01*
X908956Y2940055D01*
X909556Y2939255D01*
X909956Y2938322D01*
X910156Y2937255D01*
Y2936189D01*
X909956Y2935122D01*
X909556Y2934189D01*
X908956Y2933389D01*
X908256Y2932855D01*
X907456Y2932722D01*
G01X913156D02*
Y2940722D01*
X917756Y2932722D01*
Y2940722D01*
G01X920956Y2932722D02*
X923456Y2940722D01*
X925956Y2932722D01*
G01X925056Y2935522D02*
X921856D01*
G01X929456Y2940722D02*
Y2932722D01*
X933456D01*
G01X945456D02*
Y2940722D01*
X947856D01*
X948656Y2940322D01*
X949256Y2939389D01*
X949456Y2938322D01*
X949256Y2937255D01*
X948756Y2936455D01*
X947856Y2936055D01*
X945456D01*
G01X952956Y2932722D02*
X955456Y2940722D01*
X957956Y2932722D01*
G01X957056Y2935522D02*
X953856D01*
G01X961256Y2932722D02*
Y2940722D01*
X963256D01*
X964056Y2940322D01*
X964656Y2939789D01*
X965156Y2938989D01*
X965556Y2938055D01*
X965656Y2936722D01*
X965556Y2935389D01*
X965156Y2934455D01*
X964656Y2933655D01*
X964056Y2933122D01*
X963256Y2932722D01*
X961256D01*
G01X978256Y2940722D02*
X980656D01*
G01X979456D02*
Y2932722D01*
G01X978256D02*
X980656D01*
G01X985356Y2933788D02*
X986156Y2933122D01*
X987056Y2932722D01*
X987856D01*
X988656Y2933122D01*
X989256Y2933788D01*
X989556Y2934722D01*
X989356Y2935655D01*
X988856Y2936455D01*
X987956Y2936989D01*
X986756Y2937255D01*
X986056Y2937789D01*
X985756Y2938722D01*
X985956Y2939655D01*
X986456Y2940322D01*
X987156Y2940722D01*
X987856D01*
X988556Y2940455D01*
X989156Y2939789D01*
G01X1001456Y2932722D02*
Y2940722D01*
X1003956D01*
X1004756Y2940322D01*
X1005256Y2939789D01*
X1005456Y2938722D01*
X1005256Y2937655D01*
X1004656Y2936989D01*
X1003956Y2936589D01*
X1001456D01*
G01X1003956D02*
X1005456Y2932722D01*
G01X1013456D02*
X1009456D01*
Y2940722D01*
X1013456D01*
G01X1011856Y2936855D02*
X1009456D01*
G01X1019456Y2932722D02*
X1018656Y2932855D01*
X1017956Y2933389D01*
X1017356Y2934189D01*
X1016956Y2935122D01*
X1016756Y2936189D01*
Y2937255D01*
X1016956Y2938322D01*
X1017356Y2939255D01*
X1017956Y2940055D01*
X1018656Y2940589D01*
X1019456Y2940722D01*
X1020256Y2940589D01*
X1020956Y2940055D01*
X1021556Y2939255D01*
X1021956Y2938322D01*
X1022156Y2937255D01*
Y2936189D01*
X1021956Y2935122D01*
X1021556Y2934189D01*
X1020956Y2933389D01*
X1020256Y2932855D01*
X1019456Y2932722D01*
G01X1020256Y2934855D02*
X1021456Y2932722D01*
G01X1025256Y2940722D02*
Y2934989D01*
X1025656Y2933788D01*
X1026456Y2932989D01*
X1027456Y2932722D01*
X1028456Y2932989D01*
X1029256Y2933788D01*
X1029656Y2934989D01*
Y2940722D01*
G01X1034256D02*
X1036656D01*
G01X1035456D02*
Y2932722D01*
G01X1034256D02*
X1036656D01*
G01X1041456D02*
Y2940722D01*
X1043956D01*
X1044756Y2940322D01*
X1045256Y2939789D01*
X1045456Y2938722D01*
X1045256Y2937655D01*
X1044656Y2936989D01*
X1043956Y2936589D01*
X1041456D01*
G01X1043956D02*
X1045456Y2932722D01*
G01X1053456D02*
X1049456D01*
Y2940722D01*
X1053456D01*
G01X1051856Y2936855D02*
X1049456D01*
G01X1057256Y2932722D02*
Y2940722D01*
X1059256D01*
X1060056Y2940322D01*
X1060656Y2939789D01*
X1061156Y2938989D01*
X1061556Y2938055D01*
X1061656Y2936722D01*
X1061556Y2935389D01*
X1061156Y2934455D01*
X1060656Y2933655D01*
X1060056Y2933122D01*
X1059256Y2932722D01*
X1057256D01*
G01X1075456Y2940722D02*
Y2932722D01*
G01X1073156Y2940722D02*
X1077756D01*
G01X1083456Y2932722D02*
X1082656Y2932855D01*
X1081956Y2933389D01*
X1081356Y2934189D01*
X1080956Y2935122D01*
X1080756Y2936189D01*
Y2937255D01*
X1080956Y2938322D01*
X1081356Y2939255D01*
X1081956Y2940055D01*
X1082656Y2940589D01*
X1083456Y2940722D01*
X1084256Y2940589D01*
X1084956Y2940055D01*
X1085556Y2939255D01*
X1085956Y2938322D01*
X1086156Y2937255D01*
Y2936189D01*
X1085956Y2935122D01*
X1085556Y2934189D01*
X1084956Y2933389D01*
X1084256Y2932855D01*
X1083456Y2932722D01*
G01X1100256Y2936989D02*
X1100656Y2937389D01*
X1100956Y2938055D01*
X1101156Y2938989D01*
X1100956Y2939789D01*
X1100556Y2940322D01*
X1099856Y2940722D01*
X1097156D01*
Y2932722D01*
X1100456D01*
X1101156Y2933255D01*
X1101556Y2934055D01*
X1101756Y2934989D01*
X1101556Y2935922D01*
X1100956Y2936722D01*
X1100256Y2936989D01*
X1097156D01*
G01X1109456Y2932722D02*
X1105456D01*
Y2940722D01*
X1109456D01*
G01X1107856Y2936855D02*
X1105456D01*
G01X1120956Y2932722D02*
X1123456Y2940722D01*
X1125956Y2932722D01*
G01X1125056Y2935522D02*
X1121856D01*
G01X1129256Y2932722D02*
Y2940722D01*
X1131256D01*
X1132056Y2940322D01*
X1132656Y2939789D01*
X1133156Y2938989D01*
X1133556Y2938055D01*
X1133656Y2936722D01*
X1133556Y2935389D01*
X1133156Y2934455D01*
X1132656Y2933655D01*
X1132056Y2933122D01*
X1131256Y2932722D01*
X1129256D01*
G01X1137256D02*
Y2940722D01*
X1139256D01*
X1140056Y2940322D01*
X1140656Y2939789D01*
X1141156Y2938989D01*
X1141556Y2938055D01*
X1141656Y2936722D01*
X1141556Y2935389D01*
X1141156Y2934455D01*
X1140656Y2933655D01*
X1140056Y2933122D01*
X1139256Y2932722D01*
X1137256D01*
G01X1149456D02*
X1145456D01*
Y2940722D01*
X1149456D01*
G01X1147856Y2936855D02*
X1145456D01*
G01X1153256Y2932722D02*
Y2940722D01*
X1155256D01*
X1156056Y2940322D01*
X1156656Y2939789D01*
X1157156Y2938989D01*
X1157556Y2938055D01*
X1157656Y2936722D01*
X1157556Y2935389D01*
X1157156Y2934455D01*
X1156656Y2933655D01*
X1156056Y2933122D01*
X1155256Y2932722D01*
X1153256D01*
G01X1171456Y2940722D02*
Y2932722D01*
G01X1169156Y2940722D02*
X1173756D01*
G01X1179456Y2932722D02*
X1178656Y2932855D01*
X1177956Y2933389D01*
X1177356Y2934189D01*
X1176956Y2935122D01*
X1176756Y2936189D01*
Y2937255D01*
X1176956Y2938322D01*
X1177356Y2939255D01*
X1177956Y2940055D01*
X1178656Y2940589D01*
X1179456Y2940722D01*
X1180256Y2940589D01*
X1180956Y2940055D01*
X1181556Y2939255D01*
X1181956Y2938322D01*
X1182156Y2937255D01*
Y2936189D01*
X1181956Y2935122D01*
X1181556Y2934189D01*
X1180956Y2933389D01*
X1180256Y2932855D01*
X1179456Y2932722D01*
G01X1193456D02*
Y2940722D01*
X1195856D01*
X1196656Y2940322D01*
X1197256Y2939389D01*
X1197456Y2938322D01*
X1197256Y2937255D01*
X1196756Y2936455D01*
X1195856Y2936055D01*
X1193456D01*
G01X1201456Y2932722D02*
Y2940722D01*
X1203956D01*
X1204756Y2940322D01*
X1205256Y2939789D01*
X1205456Y2938722D01*
X1205256Y2937655D01*
X1204656Y2936989D01*
X1203956Y2936589D01*
X1201456D01*
G01X1203956D02*
X1205456Y2932722D01*
G01X1213456D02*
X1209456D01*
Y2940722D01*
X1213456D01*
G01X1211856Y2936855D02*
X1209456D01*
G01X1216956Y2940722D02*
X1219456Y2932722D01*
X1221956Y2940722D01*
G01X1229456Y2932722D02*
X1225456D01*
Y2940722D01*
X1229456D01*
G01X1227856Y2936855D02*
X1225456D01*
G01X1233156Y2932722D02*
Y2940722D01*
X1237756Y2932722D01*
Y2940722D01*
G01X1243456D02*
Y2932722D01*
G01X1241156Y2940722D02*
X1245756D01*
G01X1259456D02*
Y2932722D01*
G01X1257156Y2940722D02*
X1261756D01*
G01X1265356Y2932722D02*
Y2940722D01*
G01X1269556D02*
Y2932722D01*
G01Y2936722D02*
X1265356D01*
G01X1277456Y2932722D02*
X1273456D01*
Y2940722D01*
X1277456D01*
G01X1275856Y2936855D02*
X1273456D01*
G01X1289456Y2932722D02*
Y2940722D01*
X1291856D01*
X1292656Y2940322D01*
X1293256Y2939389D01*
X1293456Y2938322D01*
X1293256Y2937255D01*
X1292756Y2936455D01*
X1291856Y2936055D01*
X1289456D01*
G01X1299456Y2932722D02*
X1298656Y2932855D01*
X1297956Y2933389D01*
X1297356Y2934189D01*
X1296956Y2935122D01*
X1296756Y2936189D01*
Y2937255D01*
X1296956Y2938322D01*
X1297356Y2939255D01*
X1297956Y2940055D01*
X1298656Y2940589D01*
X1299456Y2940722D01*
X1300256Y2940589D01*
X1300956Y2940055D01*
X1301556Y2939255D01*
X1301956Y2938322D01*
X1302156Y2937255D01*
Y2936189D01*
X1301956Y2935122D01*
X1301556Y2934189D01*
X1300956Y2933389D01*
X1300256Y2932855D01*
X1299456Y2932722D01*
G01X1307456Y2940722D02*
Y2932722D01*
G01X1305156Y2940722D02*
X1309756D01*
G01X1317456Y2932722D02*
X1313456D01*
Y2940722D01*
X1317456D01*
G01X1315856Y2936855D02*
X1313456D01*
G01X1321156Y2932722D02*
Y2940722D01*
X1325756Y2932722D01*
Y2940722D01*
G01X1331456D02*
Y2932722D01*
G01X1329156Y2940722D02*
X1333756D01*
G01X1338256D02*
X1340656D01*
G01X1339456D02*
Y2932722D01*
G01X1338256D02*
X1340656D01*
G01X1344956D02*
X1347456Y2940722D01*
X1349956Y2932722D01*
G01X1349056Y2935522D02*
X1345856D01*
G01X1353456Y2940722D02*
Y2932722D01*
X1357456D01*
G01X1369456D02*
Y2940722D01*
X1371856D01*
X1372656Y2940322D01*
X1373256Y2939389D01*
X1373456Y2938322D01*
X1373256Y2937255D01*
X1372756Y2936455D01*
X1371856Y2936055D01*
X1369456D01*
G01X1377256Y2940722D02*
Y2934989D01*
X1377656Y2933788D01*
X1378456Y2932989D01*
X1379456Y2932722D01*
X1380456Y2932989D01*
X1381256Y2933788D01*
X1381656Y2934989D01*
Y2940722D01*
G01X1385456D02*
Y2932722D01*
X1389456D01*
G01X1393456Y2940722D02*
Y2932722D01*
X1397456D01*
G01X1408956D02*
X1411456Y2940722D01*
X1413956Y2932722D01*
G01X1413056Y2935522D02*
X1409856D01*
G01X1416456Y2940722D02*
X1417856Y2932722D01*
X1419456Y2940722D01*
X1421056Y2932722D01*
X1422456Y2940722D01*
G01X1424956Y2932722D02*
X1427456Y2940722D01*
X1429956Y2932722D01*
G01X1429056Y2935522D02*
X1425856D01*
G01X1435456Y2932722D02*
Y2936322D01*
X1433456Y2940722D01*
G01X1437456D02*
X1435456Y2936322D01*
G01X1443456Y2932455D02*
X1443256Y2932589D01*
Y2932855D01*
X1443456Y2932989D01*
X1443656Y2932855D01*
Y2932589D01*
X1443456Y2932455D01*
G01X233756Y2948655D02*
X234456Y2947989D01*
X235256Y2947722D01*
X236056Y2947989D01*
X236756Y2948788D01*
X237256Y2949989D01*
X237456Y2951189D01*
Y2952655D01*
X237256Y2953855D01*
X236756Y2954922D01*
X236156Y2955455D01*
X235456Y2955722D01*
X234656Y2955455D01*
X234056Y2954922D01*
X233656Y2954122D01*
X233456Y2953055D01*
X233656Y2952122D01*
X234156Y2951189D01*
X234756Y2950655D01*
X235456Y2950522D01*
X236256Y2950788D01*
X236856Y2951455D01*
X237456Y2952655D01*
G01X243456Y2947455D02*
X243256Y2947589D01*
Y2947855D01*
X243456Y2947989D01*
X243656Y2947855D01*
Y2947589D01*
X243456Y2947455D01*
G01X248956Y2947722D02*
X251456Y2955722D01*
X253956Y2947722D01*
G01X253056Y2950522D02*
X249856D01*
G01X257156Y2947722D02*
Y2955722D01*
X261756Y2947722D01*
Y2955722D01*
G01X267456Y2947722D02*
Y2951322D01*
X265456Y2955722D01*
G01X269456D02*
X267456Y2951322D01*
G01X281356Y2948788D02*
X282156Y2948122D01*
X283056Y2947722D01*
X283856D01*
X284656Y2948122D01*
X285256Y2948788D01*
X285556Y2949722D01*
X285356Y2950655D01*
X284856Y2951455D01*
X283956Y2951989D01*
X282756Y2952255D01*
X282056Y2952789D01*
X281756Y2953722D01*
X281956Y2954655D01*
X282456Y2955322D01*
X283156Y2955722D01*
X283856D01*
X284556Y2955455D01*
X285156Y2954789D01*
G01X289456Y2947722D02*
Y2955722D01*
X291856D01*
X292656Y2955322D01*
X293256Y2954389D01*
X293456Y2953322D01*
X293256Y2952255D01*
X292756Y2951455D01*
X291856Y2951055D01*
X289456D01*
G01X301456Y2947722D02*
X297456D01*
Y2955722D01*
X301456D01*
G01X299856Y2951855D02*
X297456D01*
G01X309656Y2955055D02*
X309056Y2955455D01*
X308356Y2955722D01*
X307556D01*
X306656Y2955322D01*
X305956Y2954655D01*
X305456Y2953855D01*
X305056Y2952522D01*
X304956Y2951322D01*
X305156Y2950122D01*
X305456Y2949322D01*
X306056Y2948522D01*
X306756Y2947989D01*
X307456Y2947722D01*
X308156D01*
X308856Y2947989D01*
X309456Y2948389D01*
X309956Y2948922D01*
G01X314256Y2955722D02*
X316656D01*
G01X315456D02*
Y2947722D01*
G01X314256D02*
X316656D01*
G01X320956D02*
X323456Y2955722D01*
X325956Y2947722D01*
G01X325056Y2950522D02*
X321856D01*
G01X329456Y2955722D02*
Y2947722D01*
X333456D01*
G01X345256D02*
Y2955722D01*
X347256D01*
X348056Y2955322D01*
X348656Y2954789D01*
X349156Y2953989D01*
X349556Y2953055D01*
X349656Y2951722D01*
X349556Y2950389D01*
X349156Y2949455D01*
X348656Y2948655D01*
X348056Y2948122D01*
X347256Y2947722D01*
X345256D01*
G01X353456D02*
Y2955722D01*
X355956D01*
X356756Y2955322D01*
X357256Y2954789D01*
X357456Y2953722D01*
X357256Y2952655D01*
X356656Y2951989D01*
X355956Y2951589D01*
X353456D01*
G01X355956D02*
X357456Y2947722D01*
G01X362256Y2955722D02*
X364656D01*
G01X363456D02*
Y2947722D01*
G01X362256D02*
X364656D01*
G01X369456Y2955722D02*
Y2947722D01*
X373456D01*
G01X377456Y2955722D02*
Y2947722D01*
X381456D01*
G01X392956D02*
X395456Y2955722D01*
X397956Y2947722D01*
G01X397056Y2950522D02*
X393856D01*
G01X401156Y2947722D02*
Y2955722D01*
X405756Y2947722D01*
Y2955722D01*
G01X409256Y2947722D02*
Y2955722D01*
X411256D01*
X412056Y2955322D01*
X412656Y2954789D01*
X413156Y2953989D01*
X413556Y2953055D01*
X413656Y2951722D01*
X413556Y2950389D01*
X413156Y2949455D01*
X412656Y2948655D01*
X412056Y2948122D01*
X411256Y2947722D01*
X409256D01*
G01X425356Y2948788D02*
X426156Y2948122D01*
X427056Y2947722D01*
X427856D01*
X428656Y2948122D01*
X429256Y2948788D01*
X429556Y2949722D01*
X429356Y2950655D01*
X428856Y2951455D01*
X427956Y2951989D01*
X426756Y2952255D01*
X426056Y2952789D01*
X425756Y2953722D01*
X425956Y2954655D01*
X426456Y2955322D01*
X427156Y2955722D01*
X427856D01*
X428556Y2955455D01*
X429156Y2954789D01*
G01X435456Y2955722D02*
Y2947722D01*
G01X433156Y2955722D02*
X437756D01*
G01X440956Y2947722D02*
X443456Y2955722D01*
X445956Y2947722D01*
G01X445056Y2950522D02*
X441856D01*
G01X453656Y2955055D02*
X453056Y2955455D01*
X452356Y2955722D01*
X451556D01*
X450656Y2955322D01*
X449956Y2954655D01*
X449456Y2953855D01*
X449056Y2952522D01*
X448956Y2951322D01*
X449156Y2950122D01*
X449456Y2949322D01*
X450056Y2948522D01*
X450756Y2947989D01*
X451456Y2947722D01*
X452156D01*
X452856Y2947989D01*
X453456Y2948389D01*
X453956Y2948922D01*
G01X457256Y2947722D02*
Y2955722D01*
G01X461056D02*
X457256Y2950788D01*
G01X461656Y2947722D02*
X458956Y2953055D01*
G01X469456Y2947722D02*
X465456D01*
Y2955722D01*
X469456D01*
G01X467856Y2951855D02*
X465456D01*
G01X473256Y2947722D02*
Y2955722D01*
X475256D01*
X476056Y2955322D01*
X476656Y2954789D01*
X477156Y2953989D01*
X477556Y2953055D01*
X477656Y2951722D01*
X477556Y2950389D01*
X477156Y2949455D01*
X476656Y2948655D01*
X476056Y2948122D01*
X475256Y2947722D01*
X473256D01*
G01X489356D02*
Y2955722D01*
G01X493556D02*
Y2947722D01*
G01Y2951722D02*
X489356D01*
G01X499456Y2947722D02*
X498656Y2947855D01*
X497956Y2948389D01*
X497356Y2949189D01*
X496956Y2950122D01*
X496756Y2951189D01*
Y2952255D01*
X496956Y2953322D01*
X497356Y2954255D01*
X497956Y2955055D01*
X498656Y2955589D01*
X499456Y2955722D01*
X500256Y2955589D01*
X500956Y2955055D01*
X501556Y2954255D01*
X501956Y2953322D01*
X502156Y2952255D01*
Y2951189D01*
X501956Y2950122D01*
X501556Y2949189D01*
X500956Y2948389D01*
X500256Y2947855D01*
X499456Y2947722D01*
G01X505456Y2955722D02*
Y2947722D01*
X509456D01*
G01X517456D02*
X513456D01*
Y2955722D01*
X517456D01*
G01X515856Y2951855D02*
X513456D01*
G01X529456Y2947722D02*
Y2955722D01*
X531856D01*
X532656Y2955322D01*
X533256Y2954389D01*
X533456Y2953322D01*
X533256Y2952255D01*
X532756Y2951455D01*
X531856Y2951055D01*
X529456D01*
G01X537456Y2955722D02*
Y2947722D01*
X541456D01*
G01X549456D02*
X545456D01*
Y2955722D01*
X549456D01*
G01X547856Y2951855D02*
X545456D01*
G01X552956Y2947722D02*
X555456Y2955722D01*
X557956Y2947722D01*
G01X557056Y2950522D02*
X553856D01*
G01X561356Y2948788D02*
X562156Y2948122D01*
X563056Y2947722D01*
X563856D01*
X564656Y2948122D01*
X565256Y2948788D01*
X565556Y2949722D01*
X565356Y2950655D01*
X564856Y2951455D01*
X563956Y2951989D01*
X562756Y2952255D01*
X562056Y2952789D01*
X561756Y2953722D01*
X561956Y2954655D01*
X562456Y2955322D01*
X563156Y2955722D01*
X563856D01*
X564556Y2955455D01*
X565156Y2954789D01*
G01X573456Y2947722D02*
X569456D01*
Y2955722D01*
X573456D01*
G01X571856Y2951855D02*
X569456D01*
G01X585556Y2947722D02*
Y2955722D01*
X589356D01*
G01X587956Y2951855D02*
X585556D01*
G01X595456Y2947722D02*
X594656Y2947855D01*
X593956Y2948389D01*
X593356Y2949189D01*
X592956Y2950122D01*
X592756Y2951189D01*
Y2952255D01*
X592956Y2953322D01*
X593356Y2954255D01*
X593956Y2955055D01*
X594656Y2955589D01*
X595456Y2955722D01*
X596256Y2955589D01*
X596956Y2955055D01*
X597556Y2954255D01*
X597956Y2953322D01*
X598156Y2952255D01*
Y2951189D01*
X597956Y2950122D01*
X597556Y2949189D01*
X596956Y2948389D01*
X596256Y2947855D01*
X595456Y2947722D01*
G01X601456Y2955722D02*
Y2947722D01*
X605456D01*
G01X609456Y2955722D02*
Y2947722D01*
X613456D01*
G01X619456D02*
X618656Y2947855D01*
X617956Y2948389D01*
X617356Y2949189D01*
X616956Y2950122D01*
X616756Y2951189D01*
Y2952255D01*
X616956Y2953322D01*
X617356Y2954255D01*
X617956Y2955055D01*
X618656Y2955589D01*
X619456Y2955722D01*
X620256Y2955589D01*
X620956Y2955055D01*
X621556Y2954255D01*
X621956Y2953322D01*
X622156Y2952255D01*
Y2951189D01*
X621956Y2950122D01*
X621556Y2949189D01*
X620956Y2948389D01*
X620256Y2947855D01*
X619456Y2947722D01*
G01X624456Y2955722D02*
X625856Y2947722D01*
X627456Y2955722D01*
X629056Y2947722D01*
X630456Y2955722D01*
G01X643456Y2947722D02*
X642656Y2947855D01*
X641956Y2948389D01*
X641356Y2949189D01*
X640956Y2950122D01*
X640756Y2951189D01*
Y2952255D01*
X640956Y2953322D01*
X641356Y2954255D01*
X641956Y2955055D01*
X642656Y2955589D01*
X643456Y2955722D01*
X644256Y2955589D01*
X644956Y2955055D01*
X645556Y2954255D01*
X645956Y2953322D01*
X646156Y2952255D01*
Y2951189D01*
X645956Y2950122D01*
X645556Y2949189D01*
X644956Y2948389D01*
X644256Y2947855D01*
X643456Y2947722D01*
G01X649256Y2955722D02*
Y2949989D01*
X649656Y2948788D01*
X650456Y2947989D01*
X651456Y2947722D01*
X652456Y2947989D01*
X653256Y2948788D01*
X653656Y2949989D01*
Y2955722D01*
G01X659456D02*
Y2947722D01*
G01X657156Y2955722D02*
X661756D01*
G01X665456D02*
Y2947722D01*
X669456D01*
G01X674256Y2955722D02*
X676656D01*
G01X675456D02*
Y2947722D01*
G01X674256D02*
X676656D01*
G01X681156D02*
Y2955722D01*
X685756Y2947722D01*
Y2955722D01*
G01X693456Y2947722D02*
X689456D01*
Y2955722D01*
X693456D01*
G01X691856Y2951855D02*
X689456D01*
G01X699456Y2947455D02*
X699256Y2947589D01*
Y2947855D01*
X699456Y2947989D01*
X699656Y2947855D01*
Y2947589D01*
X699456Y2947455D01*
G01X713456Y2947722D02*
Y2955722D01*
X715856D01*
X716656Y2955322D01*
X717256Y2954389D01*
X717456Y2953322D01*
X717256Y2952255D01*
X716756Y2951455D01*
X715856Y2951055D01*
X713456D01*
G01X723456Y2955722D02*
Y2947722D01*
G01X721156Y2955722D02*
X725756D01*
G01X729356Y2947722D02*
Y2955722D01*
G01X733556D02*
Y2947722D01*
G01Y2951722D02*
X729356D01*
G01X747456Y2955722D02*
Y2947722D01*
G01X745156Y2955722D02*
X749756D01*
G01X755456Y2947722D02*
X754656Y2947855D01*
X753956Y2948389D01*
X753356Y2949189D01*
X752956Y2950122D01*
X752756Y2951189D01*
Y2952255D01*
X752956Y2953322D01*
X753356Y2954255D01*
X753956Y2955055D01*
X754656Y2955589D01*
X755456Y2955722D01*
X756256Y2955589D01*
X756956Y2955055D01*
X757556Y2954255D01*
X757956Y2953322D01*
X758156Y2952255D01*
Y2951189D01*
X757956Y2950122D01*
X757556Y2949189D01*
X756956Y2948389D01*
X756256Y2947855D01*
X755456Y2947722D01*
G01X761456Y2955722D02*
Y2947722D01*
X765456D01*
G01X773456D02*
X769456D01*
Y2955722D01*
X773456D01*
G01X771856Y2951855D02*
X769456D01*
G01X777456Y2947722D02*
Y2955722D01*
X779956D01*
X780756Y2955322D01*
X781256Y2954789D01*
X781456Y2953722D01*
X781256Y2952655D01*
X780656Y2951989D01*
X779956Y2951589D01*
X777456D01*
G01X779956D02*
X781456Y2947722D01*
G01X784956D02*
X787456Y2955722D01*
X789956Y2947722D01*
G01X789056Y2950522D02*
X785856D01*
G01X793156Y2947722D02*
Y2955722D01*
X797756Y2947722D01*
Y2955722D01*
G01X805656Y2955055D02*
X805056Y2955455D01*
X804356Y2955722D01*
X803556D01*
X802656Y2955322D01*
X801956Y2954655D01*
X801456Y2953855D01*
X801056Y2952522D01*
X800956Y2951322D01*
X801156Y2950122D01*
X801456Y2949322D01*
X802056Y2948522D01*
X802756Y2947989D01*
X803456Y2947722D01*
X804156D01*
X804856Y2947989D01*
X805456Y2948389D01*
X805956Y2948922D01*
G01X813456Y2947722D02*
X809456D01*
Y2955722D01*
X813456D01*
G01X811856Y2951855D02*
X809456D01*
G01X827456Y2947455D02*
X827256Y2947589D01*
Y2947855D01*
X827456Y2947989D01*
X827656Y2947855D01*
Y2947589D01*
X827456Y2947455D01*
G01Y2951055D02*
X827256Y2951189D01*
Y2951455D01*
X827456Y2951589D01*
X827656Y2951455D01*
Y2951189D01*
X827456Y2951055D01*
G01X842356Y2950389D02*
X844756D01*
G01X843456Y2952122D02*
Y2948655D01*
G01X849656Y2947455D02*
X853256Y2955722D01*
G01X858156Y2950389D02*
X860756D01*
G01X865256Y2948922D02*
X865856Y2948255D01*
X866556Y2947855D01*
X867456Y2947722D01*
X868356Y2947989D01*
X869056Y2948522D01*
X869556Y2949455D01*
X869656Y2950522D01*
X869456Y2951589D01*
X868956Y2952255D01*
X868256Y2952789D01*
X867556Y2952922D01*
X866856Y2952789D01*
X865956Y2952255D01*
X866256Y2955722D01*
X868956D01*
G01X874956Y2945055D02*
X873956Y2946389D01*
X873456Y2947722D01*
Y2953055D01*
X873956Y2954389D01*
X874956Y2955722D01*
G01X880856Y2947722D02*
Y2955722D01*
X883456Y2949055D01*
X886056Y2955722D01*
Y2947722D01*
G01X890256Y2955722D02*
X892656D01*
G01X891456D02*
Y2947722D01*
G01X890256D02*
X892656D01*
G01X897456Y2955722D02*
Y2947722D01*
X901456D01*
G01X907956Y2945055D02*
X908956Y2946389D01*
X909456Y2947722D01*
Y2953055D01*
X908956Y2954389D01*
X907956Y2955722D01*
G01X915256Y2946255D02*
X915656Y2947989D01*
G01X929156Y2947722D02*
Y2955722D01*
X933756Y2947722D01*
Y2955722D01*
G01X937456Y2947722D02*
Y2955722D01*
X939856D01*
X940656Y2955322D01*
X941256Y2954389D01*
X941456Y2953322D01*
X941256Y2952255D01*
X940756Y2951455D01*
X939856Y2951055D01*
X937456D01*
G01X947456Y2955722D02*
Y2947722D01*
G01X945156Y2955722D02*
X949756D01*
G01X953356Y2947722D02*
Y2955722D01*
G01X957556D02*
Y2947722D01*
G01Y2951722D02*
X953356D01*
G01X971456Y2955722D02*
Y2947722D01*
G01X969156Y2955722D02*
X973756D01*
G01X979456Y2947722D02*
X978656Y2947855D01*
X977956Y2948389D01*
X977356Y2949189D01*
X976956Y2950122D01*
X976756Y2951189D01*
Y2952255D01*
X976956Y2953322D01*
X977356Y2954255D01*
X977956Y2955055D01*
X978656Y2955589D01*
X979456Y2955722D01*
X980256Y2955589D01*
X980956Y2955055D01*
X981556Y2954255D01*
X981956Y2953322D01*
X982156Y2952255D01*
Y2951189D01*
X981956Y2950122D01*
X981556Y2949189D01*
X980956Y2948389D01*
X980256Y2947855D01*
X979456Y2947722D01*
G01X985456Y2955722D02*
Y2947722D01*
X989456D01*
G01X997456D02*
X993456D01*
Y2955722D01*
X997456D01*
G01X995856Y2951855D02*
X993456D01*
G01X1001456Y2947722D02*
Y2955722D01*
X1003956D01*
X1004756Y2955322D01*
X1005256Y2954789D01*
X1005456Y2953722D01*
X1005256Y2952655D01*
X1004656Y2951989D01*
X1003956Y2951589D01*
X1001456D01*
G01X1003956D02*
X1005456Y2947722D01*
G01X1008956D02*
X1011456Y2955722D01*
X1013956Y2947722D01*
G01X1013056Y2950522D02*
X1009856D01*
G01X1017156Y2947722D02*
Y2955722D01*
X1021756Y2947722D01*
Y2955722D01*
G01X1029656Y2955055D02*
X1029056Y2955455D01*
X1028356Y2955722D01*
X1027556D01*
X1026656Y2955322D01*
X1025956Y2954655D01*
X1025456Y2953855D01*
X1025056Y2952522D01*
X1024956Y2951322D01*
X1025156Y2950122D01*
X1025456Y2949322D01*
X1026056Y2948522D01*
X1026756Y2947989D01*
X1027456Y2947722D01*
X1028156D01*
X1028856Y2947989D01*
X1029456Y2948389D01*
X1029956Y2948922D01*
G01X1037456Y2947722D02*
X1033456D01*
Y2955722D01*
X1037456D01*
G01X1035856Y2951855D02*
X1033456D01*
G01X1043456Y2947455D02*
X1043256Y2947589D01*
Y2947855D01*
X1043456Y2947989D01*
X1043656Y2947855D01*
Y2947589D01*
X1043456Y2947455D01*
G01Y2951055D02*
X1043256Y2951189D01*
Y2951455D01*
X1043456Y2951589D01*
X1043656Y2951455D01*
Y2951189D01*
X1043456Y2951055D01*
G01X1058356Y2950389D02*
X1060756D01*
G01X1059456Y2952122D02*
Y2948655D01*
G01X1065656Y2947455D02*
X1069256Y2955722D01*
G01X1074156Y2950389D02*
X1076756D01*
G01X1084656Y2947722D02*
Y2955722D01*
X1080956Y2949989D01*
X1085956D01*
G01X1090956Y2945055D02*
X1089956Y2946389D01*
X1089456Y2947722D01*
Y2953055D01*
X1089956Y2954389D01*
X1090956Y2955722D01*
G01X1096856Y2947722D02*
Y2955722D01*
X1099456Y2949055D01*
X1102056Y2955722D01*
Y2947722D01*
G01X1106256Y2955722D02*
X1108656D01*
G01X1107456D02*
Y2947722D01*
G01X1106256D02*
X1108656D01*
G01X1113456Y2955722D02*
Y2947722D01*
X1117456D01*
G01X1123956Y2945055D02*
X1124956Y2946389D01*
X1125456Y2947722D01*
Y2953055D01*
X1124956Y2954389D01*
X1123956Y2955722D01*
G01X1131456Y2947455D02*
X1131256Y2947589D01*
Y2947855D01*
X1131456Y2947989D01*
X1131656Y2947855D01*
Y2947589D01*
X1131456Y2947455D01*
G01X235456Y2962722D02*
X236156Y2962855D01*
X236956Y2963255D01*
X237456Y2963922D01*
X237656Y2964855D01*
X237456Y2965788D01*
X236856Y2966589D01*
X235956Y2966989D01*
X234956D01*
X234356Y2967255D01*
X233856Y2967922D01*
X233656Y2968855D01*
X233956Y2969789D01*
X234656Y2970455D01*
X235456Y2970722D01*
X236256Y2970455D01*
X236956Y2969789D01*
X237256Y2968855D01*
X237056Y2967922D01*
X236556Y2967255D01*
X235956Y2966989D01*
X234956D01*
X234056Y2966589D01*
X233456Y2965788D01*
X233256Y2964855D01*
X233456Y2963922D01*
X233956Y2963255D01*
X234756Y2962855D01*
X235456Y2962722D01*
G01X243456Y2962455D02*
X243256Y2962589D01*
Y2962855D01*
X243456Y2962989D01*
X243656Y2962855D01*
Y2962589D01*
X243456Y2962455D01*
G01X249156Y2962722D02*
Y2970722D01*
X253756Y2962722D01*
Y2970722D01*
G01X259456Y2962722D02*
X258656Y2962855D01*
X257956Y2963389D01*
X257356Y2964189D01*
X256956Y2965122D01*
X256756Y2966189D01*
Y2967255D01*
X256956Y2968322D01*
X257356Y2969255D01*
X257956Y2970055D01*
X258656Y2970589D01*
X259456Y2970722D01*
X260256Y2970589D01*
X260956Y2970055D01*
X261556Y2969255D01*
X261956Y2968322D01*
X262156Y2967255D01*
Y2966189D01*
X261956Y2965122D01*
X261556Y2964189D01*
X260956Y2963389D01*
X260256Y2962855D01*
X259456Y2962722D01*
G01X267456Y2970722D02*
Y2962722D01*
G01X265156Y2970722D02*
X269756D01*
G01X280956Y2962722D02*
X283456Y2970722D01*
X285956Y2962722D01*
G01X285056Y2965522D02*
X281856D01*
G01X289456Y2970722D02*
Y2962722D01*
X293456D01*
G01X297456Y2970722D02*
Y2962722D01*
X301456D01*
G01X307456D02*
X306656Y2962855D01*
X305956Y2963389D01*
X305356Y2964189D01*
X304956Y2965122D01*
X304756Y2966189D01*
Y2967255D01*
X304956Y2968322D01*
X305356Y2969255D01*
X305956Y2970055D01*
X306656Y2970589D01*
X307456Y2970722D01*
X308256Y2970589D01*
X308956Y2970055D01*
X309556Y2969255D01*
X309956Y2968322D01*
X310156Y2967255D01*
Y2966189D01*
X309956Y2965122D01*
X309556Y2964189D01*
X308956Y2963389D01*
X308256Y2962855D01*
X307456Y2962722D01*
G01X312456Y2970722D02*
X313856Y2962722D01*
X315456Y2970722D01*
X317056Y2962722D01*
X318456Y2970722D01*
G01X332256Y2966989D02*
X332656Y2967389D01*
X332956Y2968055D01*
X333156Y2968989D01*
X332956Y2969789D01*
X332556Y2970322D01*
X331856Y2970722D01*
X329156D01*
Y2962722D01*
X332456D01*
X333156Y2963255D01*
X333556Y2964055D01*
X333756Y2964989D01*
X333556Y2965922D01*
X332956Y2966722D01*
X332256Y2966989D01*
X329156D01*
G01X337456Y2962722D02*
Y2970722D01*
X339956D01*
X340756Y2970322D01*
X341256Y2969789D01*
X341456Y2968722D01*
X341256Y2967655D01*
X340656Y2966989D01*
X339956Y2966589D01*
X337456D01*
G01X339956D02*
X341456Y2962722D01*
G01X349456D02*
X345456D01*
Y2970722D01*
X349456D01*
G01X347856Y2966855D02*
X345456D01*
G01X352956Y2962722D02*
X355456Y2970722D01*
X357956Y2962722D01*
G01X357056Y2965522D02*
X353856D01*
G01X361256Y2962722D02*
Y2970722D01*
G01X365056D02*
X361256Y2965788D01*
G01X365656Y2962722D02*
X362956Y2968055D01*
G01X371456Y2962722D02*
X370656Y2962855D01*
X369956Y2963389D01*
X369356Y2964189D01*
X368956Y2965122D01*
X368756Y2966189D01*
Y2967255D01*
X368956Y2968322D01*
X369356Y2969255D01*
X369956Y2970055D01*
X370656Y2970589D01*
X371456Y2970722D01*
X372256Y2970589D01*
X372956Y2970055D01*
X373556Y2969255D01*
X373956Y2968322D01*
X374156Y2967255D01*
Y2966189D01*
X373956Y2965122D01*
X373556Y2964189D01*
X372956Y2963389D01*
X372256Y2962855D01*
X371456Y2962722D01*
G01X377256Y2970722D02*
Y2964989D01*
X377656Y2963788D01*
X378456Y2962989D01*
X379456Y2962722D01*
X380456Y2962989D01*
X381256Y2963788D01*
X381656Y2964989D01*
Y2970722D01*
G01X387456D02*
Y2962722D01*
G01X385156Y2970722D02*
X389756D01*
G01X401556Y2962722D02*
Y2970722D01*
X405356D01*
G01X403956Y2966855D02*
X401556D01*
G01X411456Y2962722D02*
X410656Y2962855D01*
X409956Y2963389D01*
X409356Y2964189D01*
X408956Y2965122D01*
X408756Y2966189D01*
Y2967255D01*
X408956Y2968322D01*
X409356Y2969255D01*
X409956Y2970055D01*
X410656Y2970589D01*
X411456Y2970722D01*
X412256Y2970589D01*
X412956Y2970055D01*
X413556Y2969255D01*
X413956Y2968322D01*
X414156Y2967255D01*
Y2966189D01*
X413956Y2965122D01*
X413556Y2964189D01*
X412956Y2963389D01*
X412256Y2962855D01*
X411456Y2962722D01*
G01X417456D02*
Y2970722D01*
X419956D01*
X420756Y2970322D01*
X421256Y2969789D01*
X421456Y2968722D01*
X421256Y2967655D01*
X420656Y2966989D01*
X419956Y2966589D01*
X417456D01*
G01X419956D02*
X421456Y2962722D01*
G01X433456Y2970722D02*
Y2962722D01*
X437456D01*
G01X440956D02*
X443456Y2970722D01*
X445956Y2962722D01*
G01X445056Y2965522D02*
X441856D01*
G01X449356Y2963788D02*
X450156Y2963122D01*
X451056Y2962722D01*
X451856D01*
X452656Y2963122D01*
X453256Y2963788D01*
X453556Y2964722D01*
X453356Y2965655D01*
X452856Y2966455D01*
X451956Y2966989D01*
X450756Y2967255D01*
X450056Y2967789D01*
X449756Y2968722D01*
X449956Y2969655D01*
X450456Y2970322D01*
X451156Y2970722D01*
X451856D01*
X452556Y2970455D01*
X453156Y2969789D01*
G01X461456Y2962722D02*
X457456D01*
Y2970722D01*
X461456D01*
G01X459856Y2966855D02*
X457456D01*
G01X465456Y2962722D02*
Y2970722D01*
X467956D01*
X468756Y2970322D01*
X469256Y2969789D01*
X469456Y2968722D01*
X469256Y2967655D01*
X468656Y2966989D01*
X467956Y2966589D01*
X465456D01*
G01X467956D02*
X469456Y2962722D01*
G01X480956Y2970722D02*
X483456Y2962722D01*
X485956Y2970722D01*
G01X490256D02*
X492656D01*
G01X491456D02*
Y2962722D01*
G01X490256D02*
X492656D01*
G01X496956D02*
X499456Y2970722D01*
X501956Y2962722D01*
G01X501056Y2965522D02*
X497856D01*
G01X513356Y2962722D02*
Y2970722D01*
G01X517556D02*
Y2962722D01*
G01Y2966722D02*
X513356D01*
G01X523456Y2962722D02*
X522656Y2962855D01*
X521956Y2963389D01*
X521356Y2964189D01*
X520956Y2965122D01*
X520756Y2966189D01*
Y2967255D01*
X520956Y2968322D01*
X521356Y2969255D01*
X521956Y2970055D01*
X522656Y2970589D01*
X523456Y2970722D01*
X524256Y2970589D01*
X524956Y2970055D01*
X525556Y2969255D01*
X525956Y2968322D01*
X526156Y2967255D01*
Y2966189D01*
X525956Y2965122D01*
X525556Y2964189D01*
X524956Y2963389D01*
X524256Y2962855D01*
X523456Y2962722D01*
G01X529456Y2970722D02*
Y2962722D01*
X533456D01*
G01X541456D02*
X537456D01*
Y2970722D01*
X541456D01*
G01X539856Y2966855D02*
X537456D01*
G01X547456Y2962455D02*
X547256Y2962589D01*
Y2962855D01*
X547456Y2962989D01*
X547656Y2962855D01*
Y2962589D01*
X547456Y2962455D01*
G01X235256Y2977722D02*
X235456Y2979455D01*
X235756Y2980922D01*
X236156Y2982255D01*
X236656Y2983722D01*
X237456Y2985722D01*
X233456D01*
G01X243456Y2977455D02*
X243256Y2977589D01*
Y2977855D01*
X243456Y2977989D01*
X243656Y2977855D01*
Y2977589D01*
X243456Y2977455D01*
G01X249556Y2977722D02*
Y2985722D01*
X253356D01*
G01X251956Y2981855D02*
X249556D01*
G01X259456Y2977722D02*
X258656Y2977855D01*
X257956Y2978389D01*
X257356Y2979189D01*
X256956Y2980122D01*
X256756Y2981189D01*
Y2982255D01*
X256956Y2983322D01*
X257356Y2984255D01*
X257956Y2985055D01*
X258656Y2985589D01*
X259456Y2985722D01*
X260256Y2985589D01*
X260956Y2985055D01*
X261556Y2984255D01*
X261956Y2983322D01*
X262156Y2982255D01*
Y2981189D01*
X261956Y2980122D01*
X261556Y2979189D01*
X260956Y2978389D01*
X260256Y2977855D01*
X259456Y2977722D01*
G01X265456D02*
Y2985722D01*
X267956D01*
X268756Y2985322D01*
X269256Y2984789D01*
X269456Y2983722D01*
X269256Y2982655D01*
X268656Y2981989D01*
X267956Y2981589D01*
X265456D01*
G01X267956D02*
X269456Y2977722D01*
G01X283456D02*
Y2985722D01*
X282256Y2984122D01*
G01Y2977722D02*
X284656D01*
G01X291456Y2985722D02*
X290656Y2985455D01*
X290056Y2984789D01*
X289656Y2983989D01*
X289356Y2982922D01*
X289256Y2981722D01*
X289356Y2980522D01*
X289656Y2979455D01*
X290056Y2978655D01*
X290656Y2977989D01*
X291456Y2977722D01*
X292256Y2977989D01*
X292856Y2978655D01*
X293256Y2979455D01*
X293556Y2980522D01*
X293656Y2981722D01*
X293556Y2982922D01*
X293256Y2983989D01*
X292856Y2984789D01*
X292256Y2985455D01*
X291456Y2985722D01*
G01X296856Y2977722D02*
Y2985722D01*
X299456Y2979055D01*
X302056Y2985722D01*
Y2977722D01*
G01X306256Y2985722D02*
X308656D01*
G01X307456D02*
Y2977722D01*
G01X306256D02*
X308656D01*
G01X313456Y2985722D02*
Y2977722D01*
X317456D01*
G01X321356Y2978788D02*
X322156Y2978122D01*
X323056Y2977722D01*
X323856D01*
X324656Y2978122D01*
X325256Y2978788D01*
X325556Y2979722D01*
X325356Y2980655D01*
X324856Y2981455D01*
X323956Y2981989D01*
X322756Y2982255D01*
X322056Y2982789D01*
X321756Y2983722D01*
X321956Y2984655D01*
X322456Y2985322D01*
X323156Y2985722D01*
X323856D01*
X324556Y2985455D01*
X325156Y2984789D01*
G01X336956Y2985722D02*
X339456Y2977722D01*
X341956Y2985722D01*
G01X346256D02*
X348656D01*
G01X347456D02*
Y2977722D01*
G01X346256D02*
X348656D01*
G01X352956D02*
X355456Y2985722D01*
X357956Y2977722D01*
G01X357056Y2980522D02*
X353856D01*
G01X361356Y2978788D02*
X362156Y2978122D01*
X363056Y2977722D01*
X363856D01*
X364656Y2978122D01*
X365256Y2978788D01*
X365556Y2979722D01*
X365356Y2980655D01*
X364856Y2981455D01*
X363956Y2981989D01*
X362756Y2982255D01*
X362056Y2982789D01*
X361756Y2983722D01*
X361956Y2984655D01*
X362456Y2985322D01*
X363156Y2985722D01*
X363856D01*
X364556Y2985455D01*
X365156Y2984789D01*
G01X377256Y2985722D02*
Y2979989D01*
X377656Y2978788D01*
X378456Y2977989D01*
X379456Y2977722D01*
X380456Y2977989D01*
X381256Y2978788D01*
X381656Y2979989D01*
Y2985722D01*
G01X385356Y2978788D02*
X386156Y2978122D01*
X387056Y2977722D01*
X387856D01*
X388656Y2978122D01*
X389256Y2978788D01*
X389556Y2979722D01*
X389356Y2980655D01*
X388856Y2981455D01*
X387956Y2981989D01*
X386756Y2982255D01*
X386056Y2982789D01*
X385756Y2983722D01*
X385956Y2984655D01*
X386456Y2985322D01*
X387156Y2985722D01*
X387856D01*
X388556Y2985455D01*
X389156Y2984789D01*
G01X397456Y2977722D02*
X393456D01*
Y2985722D01*
X397456D01*
G01X395856Y2981855D02*
X393456D01*
G01X409756Y2978655D02*
X410456Y2977989D01*
X411256Y2977722D01*
X412056Y2977989D01*
X412756Y2978788D01*
X413256Y2979989D01*
X413456Y2981189D01*
Y2982655D01*
X413256Y2983855D01*
X412756Y2984922D01*
X412156Y2985455D01*
X411456Y2985722D01*
X410656Y2985455D01*
X410056Y2984922D01*
X409656Y2984122D01*
X409456Y2983055D01*
X409656Y2982122D01*
X410156Y2981189D01*
X410756Y2980655D01*
X411456Y2980522D01*
X412256Y2980788D01*
X412856Y2981455D01*
X413456Y2982655D01*
G01X419456Y2977455D02*
X419256Y2977589D01*
Y2977855D01*
X419456Y2977989D01*
X419656Y2977855D01*
Y2977589D01*
X419456Y2977455D01*
G01X427456Y2977722D02*
X428156Y2977855D01*
X428956Y2978255D01*
X429456Y2978922D01*
X429656Y2979855D01*
X429456Y2980788D01*
X428856Y2981589D01*
X427956Y2981989D01*
X426956D01*
X426356Y2982255D01*
X425856Y2982922D01*
X425656Y2983855D01*
X425956Y2984789D01*
X426656Y2985455D01*
X427456Y2985722D01*
X428256Y2985455D01*
X428956Y2984789D01*
X429256Y2983855D01*
X429056Y2982922D01*
X428556Y2982255D01*
X427956Y2981989D01*
X426956D01*
X426056Y2981589D01*
X425456Y2980788D01*
X425256Y2979855D01*
X425456Y2978922D01*
X425956Y2978255D01*
X426756Y2977855D01*
X427456Y2977722D01*
G01X432856D02*
Y2985722D01*
X435456Y2979055D01*
X438056Y2985722D01*
Y2977722D01*
G01X442256Y2985722D02*
X444656D01*
G01X443456D02*
Y2977722D01*
G01X442256D02*
X444656D01*
G01X449456Y2985722D02*
Y2977722D01*
X453456D01*
G01X457356Y2978788D02*
X458156Y2978122D01*
X459056Y2977722D01*
X459856D01*
X460656Y2978122D01*
X461256Y2978788D01*
X461556Y2979722D01*
X461356Y2980655D01*
X460856Y2981455D01*
X459956Y2981989D01*
X458756Y2982255D01*
X458056Y2982789D01*
X457756Y2983722D01*
X457956Y2984655D01*
X458456Y2985322D01*
X459156Y2985722D01*
X459856D01*
X460556Y2985455D01*
X461156Y2984789D01*
G01X473256Y2977722D02*
Y2985722D01*
X475256D01*
X476056Y2985322D01*
X476656Y2984789D01*
X477156Y2983989D01*
X477556Y2983055D01*
X477656Y2981722D01*
X477556Y2980389D01*
X477156Y2979455D01*
X476656Y2978655D01*
X476056Y2978122D01*
X475256Y2977722D01*
X473256D01*
G01X481456D02*
Y2985722D01*
X483956D01*
X484756Y2985322D01*
X485256Y2984789D01*
X485456Y2983722D01*
X485256Y2982655D01*
X484656Y2981989D01*
X483956Y2981589D01*
X481456D01*
G01X483956D02*
X485456Y2977722D01*
G01X490256Y2985722D02*
X492656D01*
G01X491456D02*
Y2977722D01*
G01X490256D02*
X492656D01*
G01X497456Y2985722D02*
Y2977722D01*
X501456D01*
G01X505456Y2985722D02*
Y2977722D01*
X509456D01*
G01X524256Y2981989D02*
X524656Y2982389D01*
X524956Y2983055D01*
X525156Y2983989D01*
X524956Y2984789D01*
X524556Y2985322D01*
X523856Y2985722D01*
X521156D01*
Y2977722D01*
X524456D01*
X525156Y2978255D01*
X525556Y2979055D01*
X525756Y2979989D01*
X525556Y2980922D01*
X524956Y2981722D01*
X524256Y2981989D01*
X521156D01*
G01X530256Y2985722D02*
X532656D01*
G01X531456D02*
Y2977722D01*
G01X530256D02*
X532656D01*
G01X539456Y2985722D02*
Y2977722D01*
G01X537156Y2985722D02*
X541756D01*
G01X547456Y2977455D02*
X547256Y2977589D01*
Y2977855D01*
X547456Y2977989D01*
X547656Y2977855D01*
Y2977589D01*
X547456Y2977455D01*
G01X561556Y2977722D02*
Y2985722D01*
X565356D01*
G01X563956Y2981855D02*
X561556D01*
G01X571456Y2977722D02*
X570656Y2977855D01*
X569956Y2978389D01*
X569356Y2979189D01*
X568956Y2980122D01*
X568756Y2981189D01*
Y2982255D01*
X568956Y2983322D01*
X569356Y2984255D01*
X569956Y2985055D01*
X570656Y2985589D01*
X571456Y2985722D01*
X572256Y2985589D01*
X572956Y2985055D01*
X573556Y2984255D01*
X573956Y2983322D01*
X574156Y2982255D01*
Y2981189D01*
X573956Y2980122D01*
X573556Y2979189D01*
X572956Y2978389D01*
X572256Y2977855D01*
X571456Y2977722D01*
G01X577456D02*
Y2985722D01*
X579956D01*
X580756Y2985322D01*
X581256Y2984789D01*
X581456Y2983722D01*
X581256Y2982655D01*
X580656Y2981989D01*
X579956Y2981589D01*
X577456D01*
G01X579956D02*
X581456Y2977722D01*
G01X595456D02*
X596156Y2977855D01*
X596956Y2978255D01*
X597456Y2978922D01*
X597656Y2979855D01*
X597456Y2980788D01*
X596856Y2981589D01*
X595956Y2981989D01*
X594956D01*
X594356Y2982255D01*
X593856Y2982922D01*
X593656Y2983855D01*
X593956Y2984789D01*
X594656Y2985455D01*
X595456Y2985722D01*
X596256Y2985455D01*
X596956Y2984789D01*
X597256Y2983855D01*
X597056Y2982922D01*
X596556Y2982255D01*
X595956Y2981989D01*
X594956D01*
X594056Y2981589D01*
X593456Y2980788D01*
X593256Y2979855D01*
X593456Y2978922D01*
X593956Y2978255D01*
X594756Y2977855D01*
X595456Y2977722D01*
G01X600856D02*
Y2985722D01*
X603456Y2979055D01*
X606056Y2985722D01*
Y2977722D01*
G01X610256Y2985722D02*
X612656D01*
G01X611456D02*
Y2977722D01*
G01X610256D02*
X612656D01*
G01X617456Y2985722D02*
Y2977722D01*
X621456D01*
G01X625356Y2978788D02*
X626156Y2978122D01*
X627056Y2977722D01*
X627856D01*
X628656Y2978122D01*
X629256Y2978788D01*
X629556Y2979722D01*
X629356Y2980655D01*
X628856Y2981455D01*
X627956Y2981989D01*
X626756Y2982255D01*
X626056Y2982789D01*
X625756Y2983722D01*
X625956Y2984655D01*
X626456Y2985322D01*
X627156Y2985722D01*
X627856D01*
X628556Y2985455D01*
X629156Y2984789D01*
G01X640956Y2985722D02*
X643456Y2977722D01*
X645956Y2985722D01*
G01X650256D02*
X652656D01*
G01X651456D02*
Y2977722D01*
G01X650256D02*
X652656D01*
G01X656956D02*
X659456Y2985722D01*
X661956Y2977722D01*
G01X661056Y2980522D02*
X657856D01*
G01X665356Y2978788D02*
X666156Y2978122D01*
X667056Y2977722D01*
X667856D01*
X668656Y2978122D01*
X669256Y2978788D01*
X669556Y2979722D01*
X669356Y2980655D01*
X668856Y2981455D01*
X667956Y2981989D01*
X666756Y2982255D01*
X666056Y2982789D01*
X665756Y2983722D01*
X665956Y2984655D01*
X666456Y2985322D01*
X667156Y2985722D01*
X667856D01*
X668556Y2985455D01*
X669156Y2984789D01*
G01X681256Y2985722D02*
Y2979989D01*
X681656Y2978788D01*
X682456Y2977989D01*
X683456Y2977722D01*
X684456Y2977989D01*
X685256Y2978788D01*
X685656Y2979989D01*
Y2985722D01*
G01X689356Y2978788D02*
X690156Y2978122D01*
X691056Y2977722D01*
X691856D01*
X692656Y2978122D01*
X693256Y2978788D01*
X693556Y2979722D01*
X693356Y2980655D01*
X692856Y2981455D01*
X691956Y2981989D01*
X690756Y2982255D01*
X690056Y2982789D01*
X689756Y2983722D01*
X689956Y2984655D01*
X690456Y2985322D01*
X691156Y2985722D01*
X691856D01*
X692556Y2985455D01*
X693156Y2984789D01*
G01X701456Y2977722D02*
X697456D01*
Y2985722D01*
X701456D01*
G01X699856Y2981855D02*
X697456D01*
G01X715256Y2977722D02*
X715456Y2979455D01*
X715756Y2980922D01*
X716156Y2982255D01*
X716656Y2983722D01*
X717456Y2985722D01*
X713456D01*
G01X723456Y2977455D02*
X723256Y2977589D01*
Y2977855D01*
X723456Y2977989D01*
X723656Y2977855D01*
Y2977589D01*
X723456Y2977455D01*
G01X729756Y2978655D02*
X730456Y2977989D01*
X731256Y2977722D01*
X732056Y2977989D01*
X732756Y2978788D01*
X733256Y2979989D01*
X733456Y2981189D01*
Y2982655D01*
X733256Y2983855D01*
X732756Y2984922D01*
X732156Y2985455D01*
X731456Y2985722D01*
X730656Y2985455D01*
X730056Y2984922D01*
X729656Y2984122D01*
X729456Y2983055D01*
X729656Y2982122D01*
X730156Y2981189D01*
X730756Y2980655D01*
X731456Y2980522D01*
X732256Y2980788D01*
X732856Y2981455D01*
X733456Y2982655D01*
G01X736856Y2977722D02*
Y2985722D01*
X739456Y2979055D01*
X742056Y2985722D01*
Y2977722D01*
G01X746256Y2985722D02*
X748656D01*
G01X747456D02*
Y2977722D01*
G01X746256D02*
X748656D01*
G01X753456Y2985722D02*
Y2977722D01*
X757456D01*
G01X761356Y2978788D02*
X762156Y2978122D01*
X763056Y2977722D01*
X763856D01*
X764656Y2978122D01*
X765256Y2978788D01*
X765556Y2979722D01*
X765356Y2980655D01*
X764856Y2981455D01*
X763956Y2981989D01*
X762756Y2982255D01*
X762056Y2982789D01*
X761756Y2983722D01*
X761956Y2984655D01*
X762456Y2985322D01*
X763156Y2985722D01*
X763856D01*
X764556Y2985455D01*
X765156Y2984789D01*
G01X777256Y2977722D02*
Y2985722D01*
X779256D01*
X780056Y2985322D01*
X780656Y2984789D01*
X781156Y2983989D01*
X781556Y2983055D01*
X781656Y2981722D01*
X781556Y2980389D01*
X781156Y2979455D01*
X780656Y2978655D01*
X780056Y2978122D01*
X779256Y2977722D01*
X777256D01*
G01X785456D02*
Y2985722D01*
X787956D01*
X788756Y2985322D01*
X789256Y2984789D01*
X789456Y2983722D01*
X789256Y2982655D01*
X788656Y2981989D01*
X787956Y2981589D01*
X785456D01*
G01X787956D02*
X789456Y2977722D01*
G01X794256Y2985722D02*
X796656D01*
G01X795456D02*
Y2977722D01*
G01X794256D02*
X796656D01*
G01X801456Y2985722D02*
Y2977722D01*
X805456D01*
G01X809456Y2985722D02*
Y2977722D01*
X813456D01*
G01X828256Y2981989D02*
X828656Y2982389D01*
X828956Y2983055D01*
X829156Y2983989D01*
X828956Y2984789D01*
X828556Y2985322D01*
X827856Y2985722D01*
X825156D01*
Y2977722D01*
X828456D01*
X829156Y2978255D01*
X829556Y2979055D01*
X829756Y2979989D01*
X829556Y2980922D01*
X828956Y2981722D01*
X828256Y2981989D01*
X825156D01*
G01X834256Y2985722D02*
X836656D01*
G01X835456D02*
Y2977722D01*
G01X834256D02*
X836656D01*
G01X843456Y2985722D02*
Y2977722D01*
G01X841156Y2985722D02*
X845756D01*
G01X851456Y2977455D02*
X851256Y2977589D01*
Y2977855D01*
X851456Y2977989D01*
X851656Y2977855D01*
Y2977589D01*
X851456Y2977455D01*
G01X857556Y2977722D02*
Y2985722D01*
X861356D01*
G01X859956Y2981855D02*
X857556D01*
G01X867456Y2977722D02*
X866656Y2977855D01*
X865956Y2978389D01*
X865356Y2979189D01*
X864956Y2980122D01*
X864756Y2981189D01*
Y2982255D01*
X864956Y2983322D01*
X865356Y2984255D01*
X865956Y2985055D01*
X866656Y2985589D01*
X867456Y2985722D01*
X868256Y2985589D01*
X868956Y2985055D01*
X869556Y2984255D01*
X869956Y2983322D01*
X870156Y2982255D01*
Y2981189D01*
X869956Y2980122D01*
X869556Y2979189D01*
X868956Y2978389D01*
X868256Y2977855D01*
X867456Y2977722D01*
G01X873456D02*
Y2985722D01*
X875956D01*
X876756Y2985322D01*
X877256Y2984789D01*
X877456Y2983722D01*
X877256Y2982655D01*
X876656Y2981989D01*
X875956Y2981589D01*
X873456D01*
G01X875956D02*
X877456Y2977722D01*
G01X889556Y2984389D02*
X890156Y2985189D01*
X890856Y2985589D01*
X891656Y2985722D01*
X892656Y2985455D01*
X893356Y2984789D01*
X893556Y2983989D01*
X893456Y2983188D01*
X893056Y2982522D01*
X891056Y2981189D01*
X890156Y2980255D01*
X889556Y2978922D01*
X889356Y2977722D01*
X893556D01*
G01X899456Y2985722D02*
X898656Y2985455D01*
X898056Y2984789D01*
X897656Y2983989D01*
X897356Y2982922D01*
X897256Y2981722D01*
X897356Y2980522D01*
X897656Y2979455D01*
X898056Y2978655D01*
X898656Y2977989D01*
X899456Y2977722D01*
X900256Y2977989D01*
X900856Y2978655D01*
X901256Y2979455D01*
X901556Y2980522D01*
X901656Y2981722D01*
X901556Y2982922D01*
X901256Y2983989D01*
X900856Y2984789D01*
X900256Y2985455D01*
X899456Y2985722D01*
G01X904856Y2977722D02*
Y2985722D01*
X907456Y2979055D01*
X910056Y2985722D01*
Y2977722D01*
G01X914256Y2985722D02*
X916656D01*
G01X915456D02*
Y2977722D01*
G01X914256D02*
X916656D01*
G01X921456Y2985722D02*
Y2977722D01*
X925456D01*
G01X929356Y2978788D02*
X930156Y2978122D01*
X931056Y2977722D01*
X931856D01*
X932656Y2978122D01*
X933256Y2978788D01*
X933556Y2979722D01*
X933356Y2980655D01*
X932856Y2981455D01*
X931956Y2981989D01*
X930756Y2982255D01*
X930056Y2982789D01*
X929756Y2983722D01*
X929956Y2984655D01*
X930456Y2985322D01*
X931156Y2985722D01*
X931856D01*
X932556Y2985455D01*
X933156Y2984789D01*
G01X944956Y2985722D02*
X947456Y2977722D01*
X949956Y2985722D01*
G01X954256D02*
X956656D01*
G01X955456D02*
Y2977722D01*
G01X954256D02*
X956656D01*
G01X960956D02*
X963456Y2985722D01*
X965956Y2977722D01*
G01X965056Y2980522D02*
X961856D01*
G01X969356Y2978788D02*
X970156Y2978122D01*
X971056Y2977722D01*
X971856D01*
X972656Y2978122D01*
X973256Y2978788D01*
X973556Y2979722D01*
X973356Y2980655D01*
X972856Y2981455D01*
X971956Y2981989D01*
X970756Y2982255D01*
X970056Y2982789D01*
X969756Y2983722D01*
X969956Y2984655D01*
X970456Y2985322D01*
X971156Y2985722D01*
X971856D01*
X972556Y2985455D01*
X973156Y2984789D01*
G01X985256Y2985722D02*
Y2979989D01*
X985656Y2978788D01*
X986456Y2977989D01*
X987456Y2977722D01*
X988456Y2977989D01*
X989256Y2978788D01*
X989656Y2979989D01*
Y2985722D01*
G01X993356Y2978788D02*
X994156Y2978122D01*
X995056Y2977722D01*
X995856D01*
X996656Y2978122D01*
X997256Y2978788D01*
X997556Y2979722D01*
X997356Y2980655D01*
X996856Y2981455D01*
X995956Y2981989D01*
X994756Y2982255D01*
X994056Y2982789D01*
X993756Y2983722D01*
X993956Y2984655D01*
X994456Y2985322D01*
X995156Y2985722D01*
X995856D01*
X996556Y2985455D01*
X997156Y2984789D01*
G01X1005456Y2977722D02*
X1001456D01*
Y2985722D01*
X1005456D01*
G01X1003856Y2981855D02*
X1001456D01*
G01X1019456Y2977722D02*
Y2985722D01*
X1018256Y2984122D01*
G01Y2977722D02*
X1020656D01*
G01X1025756Y2978655D02*
X1026456Y2977989D01*
X1027256Y2977722D01*
X1028056Y2977989D01*
X1028756Y2978788D01*
X1029256Y2979989D01*
X1029456Y2981189D01*
Y2982655D01*
X1029256Y2983855D01*
X1028756Y2984922D01*
X1028156Y2985455D01*
X1027456Y2985722D01*
X1026656Y2985455D01*
X1026056Y2984922D01*
X1025656Y2984122D01*
X1025456Y2983055D01*
X1025656Y2982122D01*
X1026156Y2981189D01*
X1026756Y2980655D01*
X1027456Y2980522D01*
X1028256Y2980788D01*
X1028856Y2981455D01*
X1029456Y2982655D01*
G01X1035456Y2977455D02*
X1035256Y2977589D01*
Y2977855D01*
X1035456Y2977989D01*
X1035656Y2977855D01*
Y2977589D01*
X1035456Y2977455D01*
G01X1043256Y2977722D02*
X1043456Y2979455D01*
X1043756Y2980922D01*
X1044156Y2982255D01*
X1044656Y2983722D01*
X1045456Y2985722D01*
X1041456D01*
G01X1048856Y2977722D02*
Y2985722D01*
X1051456Y2979055D01*
X1054056Y2985722D01*
Y2977722D01*
G01X1058256Y2985722D02*
X1060656D01*
G01X1059456D02*
Y2977722D01*
G01X1058256D02*
X1060656D01*
G01X1065456Y2985722D02*
Y2977722D01*
X1069456D01*
G01X1073356Y2978788D02*
X1074156Y2978122D01*
X1075056Y2977722D01*
X1075856D01*
X1076656Y2978122D01*
X1077256Y2978788D01*
X1077556Y2979722D01*
X1077356Y2980655D01*
X1076856Y2981455D01*
X1075956Y2981989D01*
X1074756Y2982255D01*
X1074056Y2982789D01*
X1073756Y2983722D01*
X1073956Y2984655D01*
X1074456Y2985322D01*
X1075156Y2985722D01*
X1075856D01*
X1076556Y2985455D01*
X1077156Y2984789D01*
G01X1089256Y2977722D02*
Y2985722D01*
X1091256D01*
X1092056Y2985322D01*
X1092656Y2984789D01*
X1093156Y2983989D01*
X1093556Y2983055D01*
X1093656Y2981722D01*
X1093556Y2980389D01*
X1093156Y2979455D01*
X1092656Y2978655D01*
X1092056Y2978122D01*
X1091256Y2977722D01*
X1089256D01*
G01X1097456D02*
Y2985722D01*
X1099956D01*
X1100756Y2985322D01*
X1101256Y2984789D01*
X1101456Y2983722D01*
X1101256Y2982655D01*
X1100656Y2981989D01*
X1099956Y2981589D01*
X1097456D01*
G01X1099956D02*
X1101456Y2977722D01*
G01X1106256Y2985722D02*
X1108656D01*
G01X1107456D02*
Y2977722D01*
G01X1106256D02*
X1108656D01*
G01X1113456Y2985722D02*
Y2977722D01*
X1117456D01*
G01X1121456Y2985722D02*
Y2977722D01*
X1125456D01*
G01X1140256Y2981989D02*
X1140656Y2982389D01*
X1140956Y2983055D01*
X1141156Y2983989D01*
X1140956Y2984789D01*
X1140556Y2985322D01*
X1139856Y2985722D01*
X1137156D01*
Y2977722D01*
X1140456D01*
X1141156Y2978255D01*
X1141556Y2979055D01*
X1141756Y2979989D01*
X1141556Y2980922D01*
X1140956Y2981722D01*
X1140256Y2981989D01*
X1137156D01*
G01X1146256Y2985722D02*
X1148656D01*
G01X1147456D02*
Y2977722D01*
G01X1146256D02*
X1148656D01*
G01X1155456Y2985722D02*
Y2977722D01*
G01X1153156Y2985722D02*
X1157756D01*
G01X1163456Y2977455D02*
X1163256Y2977589D01*
Y2977855D01*
X1163456Y2977989D01*
X1163656Y2977855D01*
Y2977589D01*
X1163456Y2977455D01*
G01X233556Y2996055D02*
X234256Y2996989D01*
X234856Y2997522D01*
X235656Y2997789D01*
X236356Y2997522D01*
X236856Y2996989D01*
X237256Y2996189D01*
X237356Y2995255D01*
X237256Y2994455D01*
X236856Y2993655D01*
X236256Y2992989D01*
X235556Y2992722D01*
X234756Y2992989D01*
X234056Y2993788D01*
X233656Y2994989D01*
X233556Y2996322D01*
X233756Y2998055D01*
X234056Y2998989D01*
X234556Y2999922D01*
X235256Y3000589D01*
X235956Y3000722D01*
X236656Y3000455D01*
X237156Y2999789D01*
G01X243456Y2992455D02*
X243256Y2992589D01*
Y2992855D01*
X243456Y2992989D01*
X243656Y2992855D01*
Y2992589D01*
X243456Y2992455D01*
G01X249556Y2999389D02*
X250156Y3000189D01*
X250856Y3000589D01*
X251656Y3000722D01*
X252656Y3000455D01*
X253356Y2999789D01*
X253556Y2998989D01*
X253456Y2998188D01*
X253056Y2997522D01*
X251056Y2996189D01*
X250156Y2995255D01*
X249556Y2993922D01*
X249356Y2992722D01*
X253556D01*
G01X267456D02*
X266656Y2992855D01*
X265956Y2993389D01*
X265356Y2994189D01*
X264956Y2995122D01*
X264756Y2996189D01*
Y2997255D01*
X264956Y2998322D01*
X265356Y2999255D01*
X265956Y3000055D01*
X266656Y3000589D01*
X267456Y3000722D01*
X268256Y3000589D01*
X268956Y3000055D01*
X269556Y2999255D01*
X269956Y2998322D01*
X270156Y2997255D01*
Y2996189D01*
X269956Y2995122D01*
X269556Y2994189D01*
X268956Y2993389D01*
X268256Y2992855D01*
X267456Y2992722D01*
G01X273256Y3000722D02*
Y2994989D01*
X273656Y2993788D01*
X274456Y2992989D01*
X275456Y2992722D01*
X276456Y2992989D01*
X277256Y2993788D01*
X277656Y2994989D01*
Y3000722D01*
G01X283456D02*
Y2992722D01*
G01X281156Y3000722D02*
X285756D01*
G01X289356Y2993788D02*
X290156Y2993122D01*
X291056Y2992722D01*
X291856D01*
X292656Y2993122D01*
X293256Y2993788D01*
X293556Y2994722D01*
X293356Y2995655D01*
X292856Y2996455D01*
X291956Y2996989D01*
X290756Y2997255D01*
X290056Y2997789D01*
X289756Y2998722D01*
X289956Y2999655D01*
X290456Y3000322D01*
X291156Y3000722D01*
X291856D01*
X292556Y3000455D01*
X293156Y2999789D01*
G01X298256Y3000722D02*
X300656D01*
G01X299456D02*
Y2992722D01*
G01X298256D02*
X300656D01*
G01X305256D02*
Y3000722D01*
X307256D01*
X308056Y3000322D01*
X308656Y2999789D01*
X309156Y2998989D01*
X309556Y2998055D01*
X309656Y2996722D01*
X309556Y2995389D01*
X309156Y2994455D01*
X308656Y2993655D01*
X308056Y2993122D01*
X307256Y2992722D01*
X305256D01*
G01X317456D02*
X313456D01*
Y3000722D01*
X317456D01*
G01X315856Y2996855D02*
X313456D01*
G01X332256Y2996989D02*
X332656Y2997389D01*
X332956Y2998055D01*
X333156Y2998989D01*
X332956Y2999789D01*
X332556Y3000322D01*
X331856Y3000722D01*
X329156D01*
Y2992722D01*
X332456D01*
X333156Y2993255D01*
X333556Y2994055D01*
X333756Y2994989D01*
X333556Y2995922D01*
X332956Y2996722D01*
X332256Y2996989D01*
X329156D01*
G01X339456Y2992722D02*
X338656Y2992855D01*
X337956Y2993389D01*
X337356Y2994189D01*
X336956Y2995122D01*
X336756Y2996189D01*
Y2997255D01*
X336956Y2998322D01*
X337356Y2999255D01*
X337956Y3000055D01*
X338656Y3000589D01*
X339456Y3000722D01*
X340256Y3000589D01*
X340956Y3000055D01*
X341556Y2999255D01*
X341956Y2998322D01*
X342156Y2997255D01*
Y2996189D01*
X341956Y2995122D01*
X341556Y2994189D01*
X340956Y2993389D01*
X340256Y2992855D01*
X339456Y2992722D01*
G01X344956D02*
X347456Y3000722D01*
X349956Y2992722D01*
G01X349056Y2995522D02*
X345856D01*
G01X353456Y2992722D02*
Y3000722D01*
X355956D01*
X356756Y3000322D01*
X357256Y2999789D01*
X357456Y2998722D01*
X357256Y2997655D01*
X356656Y2996989D01*
X355956Y2996589D01*
X353456D01*
G01X355956D02*
X357456Y2992722D01*
G01X361256D02*
Y3000722D01*
X363256D01*
X364056Y3000322D01*
X364656Y2999789D01*
X365156Y2998989D01*
X365556Y2998055D01*
X365656Y2996722D01*
X365556Y2995389D01*
X365156Y2994455D01*
X364656Y2993655D01*
X364056Y2993122D01*
X363256Y2992722D01*
X361256D01*
G01X379456D02*
X378656Y2992855D01*
X377956Y2993389D01*
X377356Y2994189D01*
X376956Y2995122D01*
X376756Y2996189D01*
Y2997255D01*
X376956Y2998322D01*
X377356Y2999255D01*
X377956Y3000055D01*
X378656Y3000589D01*
X379456Y3000722D01*
X380256Y3000589D01*
X380956Y3000055D01*
X381556Y2999255D01*
X381956Y2998322D01*
X382156Y2997255D01*
Y2996189D01*
X381956Y2995122D01*
X381556Y2994189D01*
X380956Y2993389D01*
X380256Y2992855D01*
X379456Y2992722D01*
G01X385256Y3000722D02*
Y2994989D01*
X385656Y2993788D01*
X386456Y2992989D01*
X387456Y2992722D01*
X388456Y2992989D01*
X389256Y2993788D01*
X389656Y2994989D01*
Y3000722D01*
G01X395456D02*
Y2992722D01*
G01X393156Y3000722D02*
X397756D01*
G01X401456D02*
Y2992722D01*
X405456D01*
G01X410256Y3000722D02*
X412656D01*
G01X411456D02*
Y2992722D01*
G01X410256D02*
X412656D01*
G01X417156D02*
Y3000722D01*
X421756Y2992722D01*
Y3000722D01*
G01X429456Y2992722D02*
X425456D01*
Y3000722D01*
X429456D01*
G01X427856Y2996855D02*
X425456D01*
G01X441556Y2992722D02*
Y3000722D01*
X445356D01*
G01X443956Y2996855D02*
X441556D01*
G01X451456Y2992722D02*
X450656Y2992855D01*
X449956Y2993389D01*
X449356Y2994189D01*
X448956Y2995122D01*
X448756Y2996189D01*
Y2997255D01*
X448956Y2998322D01*
X449356Y2999255D01*
X449956Y3000055D01*
X450656Y3000589D01*
X451456Y3000722D01*
X452256Y3000589D01*
X452956Y3000055D01*
X453556Y2999255D01*
X453956Y2998322D01*
X454156Y2997255D01*
Y2996189D01*
X453956Y2995122D01*
X453556Y2994189D01*
X452956Y2993389D01*
X452256Y2992855D01*
X451456Y2992722D01*
G01X457456Y3000722D02*
Y2992722D01*
X461456D01*
G01X465456Y3000722D02*
Y2992722D01*
X469456D01*
G01X475456D02*
X474656Y2992855D01*
X473956Y2993389D01*
X473356Y2994189D01*
X472956Y2995122D01*
X472756Y2996189D01*
Y2997255D01*
X472956Y2998322D01*
X473356Y2999255D01*
X473956Y3000055D01*
X474656Y3000589D01*
X475456Y3000722D01*
X476256Y3000589D01*
X476956Y3000055D01*
X477556Y2999255D01*
X477956Y2998322D01*
X478156Y2997255D01*
Y2996189D01*
X477956Y2995122D01*
X477556Y2994189D01*
X476956Y2993389D01*
X476256Y2992855D01*
X475456Y2992722D01*
G01X480456Y3000722D02*
X481856Y2992722D01*
X483456Y3000722D01*
X485056Y2992722D01*
X486456Y3000722D01*
G01X497456Y2992722D02*
Y3000722D01*
X499856D01*
X500656Y3000322D01*
X501256Y2999389D01*
X501456Y2998322D01*
X501256Y2997255D01*
X500756Y2996455D01*
X499856Y2996055D01*
X497456D01*
G01X509656Y3000055D02*
X509056Y3000455D01*
X508356Y3000722D01*
X507556D01*
X506656Y3000322D01*
X505956Y2999655D01*
X505456Y2998855D01*
X505056Y2997522D01*
X504956Y2996322D01*
X505156Y2995122D01*
X505456Y2994322D01*
X506056Y2993522D01*
X506756Y2992989D01*
X507456Y2992722D01*
X508156D01*
X508856Y2992989D01*
X509456Y2993389D01*
X509956Y2993922D01*
G01X516256Y2996989D02*
X516656Y2997389D01*
X516956Y2998055D01*
X517156Y2998989D01*
X516956Y2999789D01*
X516556Y3000322D01*
X515856Y3000722D01*
X513156D01*
Y2992722D01*
X516456D01*
X517156Y2993255D01*
X517556Y2994055D01*
X517756Y2994989D01*
X517556Y2995922D01*
X516956Y2996722D01*
X516256Y2996989D01*
X513156D01*
G01X529356Y2993788D02*
X530156Y2993122D01*
X531056Y2992722D01*
X531856D01*
X532656Y2993122D01*
X533256Y2993788D01*
X533556Y2994722D01*
X533356Y2995655D01*
X532856Y2996455D01*
X531956Y2996989D01*
X530756Y2997255D01*
X530056Y2997789D01*
X529756Y2998722D01*
X529956Y2999655D01*
X530456Y3000322D01*
X531156Y3000722D01*
X531856D01*
X532556Y3000455D01*
X533156Y2999789D01*
G01X537356Y2992722D02*
Y3000722D01*
G01X541556D02*
Y2992722D01*
G01Y2996722D02*
X537356D01*
G01X547456Y2992722D02*
X546656Y2992855D01*
X545956Y2993389D01*
X545356Y2994189D01*
X544956Y2995122D01*
X544756Y2996189D01*
Y2997255D01*
X544956Y2998322D01*
X545356Y2999255D01*
X545956Y3000055D01*
X546656Y3000589D01*
X547456Y3000722D01*
X548256Y3000589D01*
X548956Y3000055D01*
X549556Y2999255D01*
X549956Y2998322D01*
X550156Y2997255D01*
Y2996189D01*
X549956Y2995122D01*
X549556Y2994189D01*
X548956Y2993389D01*
X548256Y2992855D01*
X547456Y2992722D01*
G01X553456D02*
Y3000722D01*
X555856D01*
X556656Y3000322D01*
X557256Y2999389D01*
X557456Y2998322D01*
X557256Y2997255D01*
X556756Y2996455D01*
X555856Y2996055D01*
X553456D01*
G01X569456Y2992722D02*
Y3000722D01*
X571856D01*
X572656Y3000322D01*
X573256Y2999389D01*
X573456Y2998322D01*
X573256Y2997255D01*
X572756Y2996455D01*
X571856Y2996055D01*
X569456D01*
G01X577456Y2992722D02*
Y3000722D01*
X579956D01*
X580756Y3000322D01*
X581256Y2999789D01*
X581456Y2998722D01*
X581256Y2997655D01*
X580656Y2996989D01*
X579956Y2996589D01*
X577456D01*
G01X579956D02*
X581456Y2992722D01*
G01X589456D02*
X585456D01*
Y3000722D01*
X589456D01*
G01X587856Y2996855D02*
X585456D01*
G01X593556Y2992722D02*
Y3000722D01*
X597356D01*
G01X595956Y2996855D02*
X593556D01*
G01X605456Y2992722D02*
X601456D01*
Y3000722D01*
X605456D01*
G01X603856Y2996855D02*
X601456D01*
G01X609456Y2992722D02*
Y3000722D01*
X611956D01*
X612756Y3000322D01*
X613256Y2999789D01*
X613456Y2998722D01*
X613256Y2997655D01*
X612656Y2996989D01*
X611956Y2996589D01*
X609456D01*
G01X611956D02*
X613456Y2992722D01*
G01X621456D02*
X617456D01*
Y3000722D01*
X621456D01*
G01X619856Y2996855D02*
X617456D01*
G01X625156Y2992722D02*
Y3000722D01*
X629756Y2992722D01*
Y3000722D01*
G01X637656Y3000055D02*
X637056Y3000455D01*
X636356Y3000722D01*
X635556D01*
X634656Y3000322D01*
X633956Y2999655D01*
X633456Y2998855D01*
X633056Y2997522D01*
X632956Y2996322D01*
X633156Y2995122D01*
X633456Y2994322D01*
X634056Y2993522D01*
X634756Y2992989D01*
X635456Y2992722D01*
X636156D01*
X636856Y2992989D01*
X637456Y2993389D01*
X637956Y2993922D01*
G01X645456Y2992722D02*
X641456D01*
Y3000722D01*
X645456D01*
G01X643856Y2996855D02*
X641456D01*
G01X660256Y2996989D02*
X660656Y2997389D01*
X660956Y2998055D01*
X661156Y2998989D01*
X660956Y2999789D01*
X660556Y3000322D01*
X659856Y3000722D01*
X657156D01*
Y2992722D01*
X660456D01*
X661156Y2993255D01*
X661556Y2994055D01*
X661756Y2994989D01*
X661556Y2995922D01*
X660956Y2996722D01*
X660256Y2996989D01*
X657156D01*
G01X665256Y3000722D02*
Y2994989D01*
X665656Y2993788D01*
X666456Y2992989D01*
X667456Y2992722D01*
X668456Y2992989D01*
X669256Y2993788D01*
X669656Y2994989D01*
Y3000722D01*
G01X675456D02*
Y2992722D01*
G01X673156Y3000722D02*
X677756D01*
G01X693656Y3000055D02*
X693056Y3000455D01*
X692356Y3000722D01*
X691556D01*
X690656Y3000322D01*
X689956Y2999655D01*
X689456Y2998855D01*
X689056Y2997522D01*
X688956Y2996322D01*
X689156Y2995122D01*
X689456Y2994322D01*
X690056Y2993522D01*
X690756Y2992989D01*
X691456Y2992722D01*
X692156D01*
X692856Y2992989D01*
X693456Y2993389D01*
X693956Y2993922D01*
G01X699456Y2992722D02*
X698656Y2992855D01*
X697956Y2993389D01*
X697356Y2994189D01*
X696956Y2995122D01*
X696756Y2996189D01*
Y2997255D01*
X696956Y2998322D01*
X697356Y2999255D01*
X697956Y3000055D01*
X698656Y3000589D01*
X699456Y3000722D01*
X700256Y3000589D01*
X700956Y3000055D01*
X701556Y2999255D01*
X701956Y2998322D01*
X702156Y2997255D01*
Y2996189D01*
X701956Y2995122D01*
X701556Y2994189D01*
X700956Y2993389D01*
X700256Y2992855D01*
X699456Y2992722D01*
G01X705256Y3000722D02*
Y2994989D01*
X705656Y2993788D01*
X706456Y2992989D01*
X707456Y2992722D01*
X708456Y2992989D01*
X709256Y2993788D01*
X709656Y2994989D01*
Y3000722D01*
G01X713456Y2992722D02*
Y3000722D01*
X715856D01*
X716656Y3000322D01*
X717256Y2999389D01*
X717456Y2998322D01*
X717256Y2997255D01*
X716756Y2996455D01*
X715856Y2996055D01*
X713456D01*
G01X723456Y2992722D02*
X722656Y2992855D01*
X721956Y2993389D01*
X721356Y2994189D01*
X720956Y2995122D01*
X720756Y2996189D01*
Y2997255D01*
X720956Y2998322D01*
X721356Y2999255D01*
X721956Y3000055D01*
X722656Y3000589D01*
X723456Y3000722D01*
X724256Y3000589D01*
X724956Y3000055D01*
X725556Y2999255D01*
X725956Y2998322D01*
X726156Y2997255D01*
Y2996189D01*
X725956Y2995122D01*
X725556Y2994189D01*
X724956Y2993389D01*
X724256Y2992855D01*
X723456Y2992722D01*
G01X729156D02*
Y3000722D01*
X733756Y2992722D01*
Y3000722D01*
G01X737656Y2992455D02*
X741256Y3000722D01*
G01X745556Y2992722D02*
Y3000722D01*
X749356D01*
G01X747956Y2996855D02*
X745556D01*
G01X754256Y3000722D02*
X756656D01*
G01X755456D02*
Y2992722D01*
G01X754256D02*
X756656D01*
G01X761256D02*
Y3000722D01*
X763256D01*
X764056Y3000322D01*
X764656Y2999789D01*
X765156Y2998989D01*
X765556Y2998055D01*
X765656Y2996722D01*
X765556Y2995389D01*
X765156Y2994455D01*
X764656Y2993655D01*
X764056Y2993122D01*
X763256Y2992722D01*
X761256D01*
G01X769256Y3000722D02*
Y2994989D01*
X769656Y2993788D01*
X770456Y2992989D01*
X771456Y2992722D01*
X772456Y2992989D01*
X773256Y2993788D01*
X773656Y2994989D01*
Y3000722D01*
G01X781656Y3000055D02*
X781056Y3000455D01*
X780356Y3000722D01*
X779556D01*
X778656Y3000322D01*
X777956Y2999655D01*
X777456Y2998855D01*
X777056Y2997522D01*
X776956Y2996322D01*
X777156Y2995122D01*
X777456Y2994322D01*
X778056Y2993522D01*
X778756Y2992989D01*
X779456Y2992722D01*
X780156D01*
X780856Y2992989D01*
X781456Y2993389D01*
X781956Y2993922D01*
G01X786256Y3000722D02*
X788656D01*
G01X787456D02*
Y2992722D01*
G01X786256D02*
X788656D01*
G01X792956D02*
X795456Y3000722D01*
X797956Y2992722D01*
G01X797056Y2995522D02*
X793856D01*
G01X801456Y3000722D02*
Y2992722D01*
X805456D01*
G01X816856D02*
Y3000722D01*
X819456Y2994055D01*
X822056Y3000722D01*
Y2992722D01*
G01X824956D02*
X827456Y3000722D01*
X829956Y2992722D01*
G01X829056Y2995522D02*
X825856D01*
G01X833456Y2992722D02*
Y3000722D01*
X835956D01*
X836756Y3000322D01*
X837256Y2999789D01*
X837456Y2998722D01*
X837256Y2997655D01*
X836656Y2996989D01*
X835956Y2996589D01*
X833456D01*
G01X835956D02*
X837456Y2992722D01*
G01X841256D02*
Y3000722D01*
G01X845056D02*
X841256Y2995788D01*
G01X845656Y2992722D02*
X842956Y2998055D01*
G01X849656Y2992455D02*
X853256Y3000722D01*
G01X859456D02*
Y2992722D01*
G01X857156Y3000722D02*
X861756D01*
G01X867456Y2992722D02*
X866656Y2992855D01*
X865956Y2993389D01*
X865356Y2994189D01*
X864956Y2995122D01*
X864756Y2996189D01*
Y2997255D01*
X864956Y2998322D01*
X865356Y2999255D01*
X865956Y3000055D01*
X866656Y3000589D01*
X867456Y3000722D01*
X868256Y3000589D01*
X868956Y3000055D01*
X869556Y2999255D01*
X869956Y2998322D01*
X870156Y2997255D01*
Y2996189D01*
X869956Y2995122D01*
X869556Y2994189D01*
X868956Y2993389D01*
X868256Y2992855D01*
X867456Y2992722D01*
G01X875456D02*
X874656Y2992855D01*
X873956Y2993389D01*
X873356Y2994189D01*
X872956Y2995122D01*
X872756Y2996189D01*
Y2997255D01*
X872956Y2998322D01*
X873356Y2999255D01*
X873956Y3000055D01*
X874656Y3000589D01*
X875456Y3000722D01*
X876256Y3000589D01*
X876956Y3000055D01*
X877556Y2999255D01*
X877956Y2998322D01*
X878156Y2997255D01*
Y2996189D01*
X877956Y2995122D01*
X877556Y2994189D01*
X876956Y2993389D01*
X876256Y2992855D01*
X875456Y2992722D01*
G01X881456Y3000722D02*
Y2992722D01*
X885456D01*
G01X890256Y3000722D02*
X892656D01*
G01X891456D02*
Y2992722D01*
G01X890256D02*
X892656D01*
G01X897156D02*
Y3000722D01*
X901756Y2992722D01*
Y3000722D01*
G01X908056Y2996722D02*
X910056D01*
Y2994322D01*
X909456Y2993522D01*
X908756Y2992989D01*
X907756Y2992722D01*
X906756Y2992989D01*
X906056Y2993522D01*
X905456Y2994322D01*
X905056Y2995255D01*
X904856Y2996322D01*
Y2997255D01*
X905056Y2998055D01*
X905456Y2998989D01*
X906056Y2999789D01*
X906656Y3000322D01*
X907456Y3000722D01*
X908156D01*
X908956Y3000455D01*
X909556Y2999922D01*
G01X921356Y2992722D02*
Y3000722D01*
G01X925556D02*
Y2992722D01*
G01Y2996722D02*
X921356D01*
G01X931456Y2992722D02*
X930656Y2992855D01*
X929956Y2993389D01*
X929356Y2994189D01*
X928956Y2995122D01*
X928756Y2996189D01*
Y2997255D01*
X928956Y2998322D01*
X929356Y2999255D01*
X929956Y3000055D01*
X930656Y3000589D01*
X931456Y3000722D01*
X932256Y3000589D01*
X932956Y3000055D01*
X933556Y2999255D01*
X933956Y2998322D01*
X934156Y2997255D01*
Y2996189D01*
X933956Y2995122D01*
X933556Y2994189D01*
X932956Y2993389D01*
X932256Y2992855D01*
X931456Y2992722D01*
G01X937456Y3000722D02*
Y2992722D01*
X941456D01*
G01X949456D02*
X945456D01*
Y3000722D01*
X949456D01*
G01X947856Y2996855D02*
X945456D01*
G01X961356Y2993788D02*
X962156Y2993122D01*
X963056Y2992722D01*
X963856D01*
X964656Y2993122D01*
X965256Y2993788D01*
X965556Y2994722D01*
X965356Y2995655D01*
X964856Y2996455D01*
X963956Y2996989D01*
X962756Y2997255D01*
X962056Y2997789D01*
X961756Y2998722D01*
X961956Y2999655D01*
X962456Y3000322D01*
X963156Y3000722D01*
X963856D01*
X964556Y3000455D01*
X965156Y2999789D01*
G01X969456Y2992722D02*
Y3000722D01*
X971856D01*
X972656Y3000322D01*
X973256Y2999389D01*
X973456Y2998322D01*
X973256Y2997255D01*
X972756Y2996455D01*
X971856Y2996055D01*
X969456D01*
G01X976956Y2992722D02*
X979456Y3000722D01*
X981956Y2992722D01*
G01X981056Y2995522D02*
X977856D01*
G01X989656Y3000055D02*
X989056Y3000455D01*
X988356Y3000722D01*
X987556D01*
X986656Y3000322D01*
X985956Y2999655D01*
X985456Y2998855D01*
X985056Y2997522D01*
X984956Y2996322D01*
X985156Y2995122D01*
X985456Y2994322D01*
X986056Y2993522D01*
X986756Y2992989D01*
X987456Y2992722D01*
X988156D01*
X988856Y2992989D01*
X989456Y2993389D01*
X989956Y2993922D01*
G01X994256Y3000722D02*
X996656D01*
G01X995456D02*
Y2992722D01*
G01X994256D02*
X996656D01*
G01X1001156D02*
Y3000722D01*
X1005756Y2992722D01*
Y3000722D01*
G01X1012056Y2996722D02*
X1014056D01*
Y2994322D01*
X1013456Y2993522D01*
X1012756Y2992989D01*
X1011756Y2992722D01*
X1010756Y2992989D01*
X1010056Y2993522D01*
X1009456Y2994322D01*
X1009056Y2995255D01*
X1008856Y2996322D01*
Y2997255D01*
X1009056Y2998055D01*
X1009456Y2998989D01*
X1010056Y2999789D01*
X1010656Y3000322D01*
X1011456Y3000722D01*
X1012156D01*
X1012956Y3000455D01*
X1013556Y2999922D01*
G01X1024956Y2992722D02*
X1027456Y3000722D01*
X1029956Y2992722D01*
G01X1029056Y2995522D02*
X1025856D01*
G01X1033456Y3000722D02*
Y2992722D01*
X1037456D01*
G01X1041456Y3000722D02*
Y2992722D01*
X1045456D01*
G01X1057256Y3000722D02*
Y2994989D01*
X1057656Y2993788D01*
X1058456Y2992989D01*
X1059456Y2992722D01*
X1060456Y2992989D01*
X1061256Y2993788D01*
X1061656Y2994989D01*
Y3000722D01*
G01X1065356Y2993788D02*
X1066156Y2993122D01*
X1067056Y2992722D01*
X1067856D01*
X1068656Y2993122D01*
X1069256Y2993788D01*
X1069556Y2994722D01*
X1069356Y2995655D01*
X1068856Y2996455D01*
X1067956Y2996989D01*
X1066756Y2997255D01*
X1066056Y2997789D01*
X1065756Y2998722D01*
X1065956Y2999655D01*
X1066456Y3000322D01*
X1067156Y3000722D01*
X1067856D01*
X1068556Y3000455D01*
X1069156Y2999789D01*
G01X1074256Y3000722D02*
X1076656D01*
G01X1075456D02*
Y2992722D01*
G01X1074256D02*
X1076656D01*
G01X1081156D02*
Y3000722D01*
X1085756Y2992722D01*
Y3000722D01*
G01X1092056Y2996722D02*
X1094056D01*
Y2994322D01*
X1093456Y2993522D01*
X1092756Y2992989D01*
X1091756Y2992722D01*
X1090756Y2992989D01*
X1090056Y2993522D01*
X1089456Y2994322D01*
X1089056Y2995255D01*
X1088856Y2996322D01*
Y2997255D01*
X1089056Y2998055D01*
X1089456Y2998989D01*
X1090056Y2999789D01*
X1090656Y3000322D01*
X1091456Y3000722D01*
X1092156D01*
X1092956Y3000455D01*
X1093556Y2999922D01*
G01X1105256Y2993922D02*
X1105856Y2993255D01*
X1106556Y2992855D01*
X1107456Y2992722D01*
X1108356Y2992989D01*
X1109056Y2993522D01*
X1109556Y2994455D01*
X1109656Y2995522D01*
X1109456Y2996589D01*
X1108956Y2997255D01*
X1108256Y2997789D01*
X1107556Y2997922D01*
X1106856Y2997789D01*
X1105956Y2997255D01*
X1106256Y3000722D01*
X1108956D01*
G01X1115456D02*
X1114656Y3000455D01*
X1114056Y2999789D01*
X1113656Y2998989D01*
X1113356Y2997922D01*
X1113256Y2996722D01*
X1113356Y2995522D01*
X1113656Y2994455D01*
X1114056Y2993655D01*
X1114656Y2992989D01*
X1115456Y2992722D01*
X1116256Y2992989D01*
X1116856Y2993655D01*
X1117256Y2994455D01*
X1117556Y2995522D01*
X1117656Y2996722D01*
X1117556Y2997922D01*
X1117256Y2998989D01*
X1116856Y2999789D01*
X1116256Y3000455D01*
X1115456Y3000722D01*
G01X1120856Y2992722D02*
Y3000722D01*
X1123456Y2994055D01*
X1126056Y3000722D01*
Y2992722D01*
G01X1130256Y3000722D02*
X1132656D01*
G01X1131456D02*
Y2992722D01*
G01X1130256D02*
X1132656D01*
G01X1137456Y3000722D02*
Y2992722D01*
X1141456D01*
G01X1145356Y2993788D02*
X1146156Y2993122D01*
X1147056Y2992722D01*
X1147856D01*
X1148656Y2993122D01*
X1149256Y2993788D01*
X1149556Y2994722D01*
X1149356Y2995655D01*
X1148856Y2996455D01*
X1147956Y2996989D01*
X1146756Y2997255D01*
X1146056Y2997789D01*
X1145756Y2998722D01*
X1145956Y2999655D01*
X1146456Y3000322D01*
X1147156Y3000722D01*
X1147856D01*
X1148556Y3000455D01*
X1149156Y2999789D01*
G01X1155456Y2992455D02*
X1155256Y2992589D01*
Y2992855D01*
X1155456Y2992989D01*
X1155656Y2992855D01*
Y2992589D01*
X1155456Y2992455D01*
G01X233556Y3011055D02*
X234256Y3011989D01*
X234856Y3012522D01*
X235656Y3012789D01*
X236356Y3012522D01*
X236856Y3011989D01*
X237256Y3011189D01*
X237356Y3010255D01*
X237256Y3009455D01*
X236856Y3008655D01*
X236256Y3007989D01*
X235556Y3007722D01*
X234756Y3007989D01*
X234056Y3008788D01*
X233656Y3009989D01*
X233556Y3011322D01*
X233756Y3013055D01*
X234056Y3013989D01*
X234556Y3014922D01*
X235256Y3015589D01*
X235956Y3015722D01*
X236656Y3015455D01*
X237156Y3014789D01*
G01X243456Y3007455D02*
X243256Y3007589D01*
Y3007855D01*
X243456Y3007989D01*
X243656Y3007855D01*
Y3007589D01*
X243456Y3007455D01*
G01X251456Y3007722D02*
Y3015722D01*
X250256Y3014122D01*
G01Y3007722D02*
X252656D01*
G01X266256Y3015722D02*
X268656D01*
G01X267456D02*
Y3007722D01*
G01X266256D02*
X268656D01*
G01X273156D02*
Y3015722D01*
X277756Y3007722D01*
Y3015722D01*
G01X281356Y3008788D02*
X282156Y3008122D01*
X283056Y3007722D01*
X283856D01*
X284656Y3008122D01*
X285256Y3008788D01*
X285556Y3009722D01*
X285356Y3010655D01*
X284856Y3011455D01*
X283956Y3011989D01*
X282756Y3012255D01*
X282056Y3012789D01*
X281756Y3013722D01*
X281956Y3014655D01*
X282456Y3015322D01*
X283156Y3015722D01*
X283856D01*
X284556Y3015455D01*
X285156Y3014789D01*
G01X290256Y3015722D02*
X292656D01*
G01X291456D02*
Y3007722D01*
G01X290256D02*
X292656D01*
G01X297256D02*
Y3015722D01*
X299256D01*
X300056Y3015322D01*
X300656Y3014789D01*
X301156Y3013989D01*
X301556Y3013055D01*
X301656Y3011722D01*
X301556Y3010389D01*
X301156Y3009455D01*
X300656Y3008655D01*
X300056Y3008122D01*
X299256Y3007722D01*
X297256D01*
G01X309456D02*
X305456D01*
Y3015722D01*
X309456D01*
G01X307856Y3011855D02*
X305456D01*
G01X324256Y3011989D02*
X324656Y3012389D01*
X324956Y3013055D01*
X325156Y3013989D01*
X324956Y3014789D01*
X324556Y3015322D01*
X323856Y3015722D01*
X321156D01*
Y3007722D01*
X324456D01*
X325156Y3008255D01*
X325556Y3009055D01*
X325756Y3009989D01*
X325556Y3010922D01*
X324956Y3011722D01*
X324256Y3011989D01*
X321156D01*
G01X331456Y3007722D02*
X330656Y3007855D01*
X329956Y3008389D01*
X329356Y3009189D01*
X328956Y3010122D01*
X328756Y3011189D01*
Y3012255D01*
X328956Y3013322D01*
X329356Y3014255D01*
X329956Y3015055D01*
X330656Y3015589D01*
X331456Y3015722D01*
X332256Y3015589D01*
X332956Y3015055D01*
X333556Y3014255D01*
X333956Y3013322D01*
X334156Y3012255D01*
Y3011189D01*
X333956Y3010122D01*
X333556Y3009189D01*
X332956Y3008389D01*
X332256Y3007855D01*
X331456Y3007722D01*
G01X336956D02*
X339456Y3015722D01*
X341956Y3007722D01*
G01X341056Y3010522D02*
X337856D01*
G01X345456Y3007722D02*
Y3015722D01*
X347956D01*
X348756Y3015322D01*
X349256Y3014789D01*
X349456Y3013722D01*
X349256Y3012655D01*
X348656Y3011989D01*
X347956Y3011589D01*
X345456D01*
G01X347956D02*
X349456Y3007722D01*
G01X353256D02*
Y3015722D01*
X355256D01*
X356056Y3015322D01*
X356656Y3014789D01*
X357156Y3013989D01*
X357556Y3013055D01*
X357656Y3011722D01*
X357556Y3010389D01*
X357156Y3009455D01*
X356656Y3008655D01*
X356056Y3008122D01*
X355256Y3007722D01*
X353256D01*
G01X371456D02*
X370656Y3007855D01*
X369956Y3008389D01*
X369356Y3009189D01*
X368956Y3010122D01*
X368756Y3011189D01*
Y3012255D01*
X368956Y3013322D01*
X369356Y3014255D01*
X369956Y3015055D01*
X370656Y3015589D01*
X371456Y3015722D01*
X372256Y3015589D01*
X372956Y3015055D01*
X373556Y3014255D01*
X373956Y3013322D01*
X374156Y3012255D01*
Y3011189D01*
X373956Y3010122D01*
X373556Y3009189D01*
X372956Y3008389D01*
X372256Y3007855D01*
X371456Y3007722D01*
G01X377256Y3015722D02*
Y3009989D01*
X377656Y3008788D01*
X378456Y3007989D01*
X379456Y3007722D01*
X380456Y3007989D01*
X381256Y3008788D01*
X381656Y3009989D01*
Y3015722D01*
G01X387456D02*
Y3007722D01*
G01X385156Y3015722D02*
X389756D01*
G01X393456D02*
Y3007722D01*
X397456D01*
G01X402256Y3015722D02*
X404656D01*
G01X403456D02*
Y3007722D01*
G01X402256D02*
X404656D01*
G01X409156D02*
Y3015722D01*
X413756Y3007722D01*
Y3015722D01*
G01X421456Y3007722D02*
X417456D01*
Y3015722D01*
X421456D01*
G01X419856Y3011855D02*
X417456D01*
G01X433256Y3007722D02*
Y3015722D01*
X435256D01*
X436056Y3015322D01*
X436656Y3014789D01*
X437156Y3013989D01*
X437556Y3013055D01*
X437656Y3011722D01*
X437556Y3010389D01*
X437156Y3009455D01*
X436656Y3008655D01*
X436056Y3008122D01*
X435256Y3007722D01*
X433256D01*
G01X441256Y3015722D02*
Y3009989D01*
X441656Y3008788D01*
X442456Y3007989D01*
X443456Y3007722D01*
X444456Y3007989D01*
X445256Y3008788D01*
X445656Y3009989D01*
Y3015722D01*
G01X448856Y3007722D02*
Y3015722D01*
X451456Y3009055D01*
X454056Y3015722D01*
Y3007722D01*
G01X456856D02*
Y3015722D01*
X459456Y3009055D01*
X462056Y3015722D01*
Y3007722D01*
G01X467456D02*
Y3011322D01*
X465456Y3015722D01*
G01X469456D02*
X467456Y3011322D01*
G01X481456Y3007722D02*
Y3015722D01*
X483856D01*
X484656Y3015322D01*
X485256Y3014389D01*
X485456Y3013322D01*
X485256Y3012255D01*
X484756Y3011455D01*
X483856Y3011055D01*
X481456D01*
G01X488956Y3007722D02*
X491456Y3015722D01*
X493956Y3007722D01*
G01X493056Y3010522D02*
X489856D01*
G01X497256Y3007722D02*
Y3015722D01*
X499256D01*
X500056Y3015322D01*
X500656Y3014789D01*
X501156Y3013989D01*
X501556Y3013055D01*
X501656Y3011722D01*
X501556Y3010389D01*
X501156Y3009455D01*
X500656Y3008655D01*
X500056Y3008122D01*
X499256Y3007722D01*
X497256D01*
G01X513256D02*
Y3015722D01*
X515256D01*
X516056Y3015322D01*
X516656Y3014789D01*
X517156Y3013989D01*
X517556Y3013055D01*
X517656Y3011722D01*
X517556Y3010389D01*
X517156Y3009455D01*
X516656Y3008655D01*
X516056Y3008122D01*
X515256Y3007722D01*
X513256D01*
G01X525456D02*
X521456D01*
Y3015722D01*
X525456D01*
G01X523856Y3011855D02*
X521456D01*
G01X529356Y3008788D02*
X530156Y3008122D01*
X531056Y3007722D01*
X531856D01*
X532656Y3008122D01*
X533256Y3008788D01*
X533556Y3009722D01*
X533356Y3010655D01*
X532856Y3011455D01*
X531956Y3011989D01*
X530756Y3012255D01*
X530056Y3012789D01*
X529756Y3013722D01*
X529956Y3014655D01*
X530456Y3015322D01*
X531156Y3015722D01*
X531856D01*
X532556Y3015455D01*
X533156Y3014789D01*
G01X538256Y3015722D02*
X540656D01*
G01X539456D02*
Y3007722D01*
G01X538256D02*
X540656D01*
G01X548056Y3011722D02*
X550056D01*
Y3009322D01*
X549456Y3008522D01*
X548756Y3007989D01*
X547756Y3007722D01*
X546756Y3007989D01*
X546056Y3008522D01*
X545456Y3009322D01*
X545056Y3010255D01*
X544856Y3011322D01*
Y3012255D01*
X545056Y3013055D01*
X545456Y3013989D01*
X546056Y3014789D01*
X546656Y3015322D01*
X547456Y3015722D01*
X548156D01*
X548956Y3015455D01*
X549556Y3014922D01*
G01X553156Y3007722D02*
Y3015722D01*
X557756Y3007722D01*
Y3015722D01*
G01X570256D02*
X572656D01*
G01X571456D02*
Y3007722D01*
G01X570256D02*
X572656D01*
G01X577156D02*
Y3015722D01*
X581756Y3007722D01*
Y3015722D01*
G01X593356Y3008788D02*
X594156Y3008122D01*
X595056Y3007722D01*
X595856D01*
X596656Y3008122D01*
X597256Y3008788D01*
X597556Y3009722D01*
X597356Y3010655D01*
X596856Y3011455D01*
X595956Y3011989D01*
X594756Y3012255D01*
X594056Y3012789D01*
X593756Y3013722D01*
X593956Y3014655D01*
X594456Y3015322D01*
X595156Y3015722D01*
X595856D01*
X596556Y3015455D01*
X597156Y3014789D01*
G01X603456Y3007722D02*
X602656Y3007855D01*
X601956Y3008389D01*
X601356Y3009189D01*
X600956Y3010122D01*
X600756Y3011189D01*
Y3012255D01*
X600956Y3013322D01*
X601356Y3014255D01*
X601956Y3015055D01*
X602656Y3015589D01*
X603456Y3015722D01*
X604256Y3015589D01*
X604956Y3015055D01*
X605556Y3014255D01*
X605956Y3013322D01*
X606156Y3012255D01*
Y3011189D01*
X605956Y3010122D01*
X605556Y3009189D01*
X604956Y3008389D01*
X604256Y3007855D01*
X603456Y3007722D01*
G01X604256Y3009855D02*
X605456Y3007722D01*
G01X609256Y3015722D02*
Y3009989D01*
X609656Y3008788D01*
X610456Y3007989D01*
X611456Y3007722D01*
X612456Y3007989D01*
X613256Y3008788D01*
X613656Y3009989D01*
Y3015722D01*
G01X616956Y3007722D02*
X619456Y3015722D01*
X621956Y3007722D01*
G01X621056Y3010522D02*
X617856D01*
G01X625456Y3007722D02*
Y3015722D01*
X627956D01*
X628756Y3015322D01*
X629256Y3014789D01*
X629456Y3013722D01*
X629256Y3012655D01*
X628656Y3011989D01*
X627956Y3011589D01*
X625456D01*
G01X627956D02*
X629456Y3007722D01*
G01X637456D02*
X633456D01*
Y3015722D01*
X637456D01*
G01X635856Y3011855D02*
X633456D01*
G01X649356Y3008788D02*
X650156Y3008122D01*
X651056Y3007722D01*
X651856D01*
X652656Y3008122D01*
X653256Y3008788D01*
X653556Y3009722D01*
X653356Y3010655D01*
X652856Y3011455D01*
X651956Y3011989D01*
X650756Y3012255D01*
X650056Y3012789D01*
X649756Y3013722D01*
X649956Y3014655D01*
X650456Y3015322D01*
X651156Y3015722D01*
X651856D01*
X652556Y3015455D01*
X653156Y3014789D01*
G01X657356Y3007722D02*
Y3015722D01*
G01X661556D02*
Y3007722D01*
G01Y3011722D02*
X657356D01*
G01X664956Y3007722D02*
X667456Y3015722D01*
X669956Y3007722D01*
G01X669056Y3010522D02*
X665856D01*
G01X673456Y3007722D02*
Y3015722D01*
X675856D01*
X676656Y3015322D01*
X677256Y3014389D01*
X677456Y3013322D01*
X677256Y3012255D01*
X676756Y3011455D01*
X675856Y3011055D01*
X673456D01*
G01X685456Y3007722D02*
X681456D01*
Y3015722D01*
X685456D01*
G01X683856Y3011855D02*
X681456D01*
G01X690156Y3010389D02*
X692756D01*
G01X705356Y3008788D02*
X706156Y3008122D01*
X707056Y3007722D01*
X707856D01*
X708656Y3008122D01*
X709256Y3008788D01*
X709556Y3009722D01*
X709356Y3010655D01*
X708856Y3011455D01*
X707956Y3011989D01*
X706756Y3012255D01*
X706056Y3012789D01*
X705756Y3013722D01*
X705956Y3014655D01*
X706456Y3015322D01*
X707156Y3015722D01*
X707856D01*
X708556Y3015455D01*
X709156Y3014789D01*
G01X713356Y3007722D02*
Y3015722D01*
G01X717556D02*
Y3007722D01*
G01Y3011722D02*
X713356D01*
G01X720956Y3007722D02*
X723456Y3015722D01*
X725956Y3007722D01*
G01X725056Y3010522D02*
X721856D01*
G01X729456Y3007722D02*
Y3015722D01*
X731856D01*
X732656Y3015322D01*
X733256Y3014389D01*
X733456Y3013322D01*
X733256Y3012255D01*
X732756Y3011455D01*
X731856Y3011055D01*
X729456D01*
G01X741456Y3007722D02*
X737456D01*
Y3015722D01*
X741456D01*
G01X739856Y3011855D02*
X737456D01*
G01X753356Y3008788D02*
X754156Y3008122D01*
X755056Y3007722D01*
X755856D01*
X756656Y3008122D01*
X757256Y3008788D01*
X757556Y3009722D01*
X757356Y3010655D01*
X756856Y3011455D01*
X755956Y3011989D01*
X754756Y3012255D01*
X754056Y3012789D01*
X753756Y3013722D01*
X753956Y3014655D01*
X754456Y3015322D01*
X755156Y3015722D01*
X755856D01*
X756556Y3015455D01*
X757156Y3014789D01*
G01X762256Y3015722D02*
X764656D01*
G01X763456D02*
Y3007722D01*
G01X762256D02*
X764656D01*
G01X769556Y3015722D02*
X773356D01*
X769556Y3007722D01*
X773356D01*
G01X781456D02*
X777456D01*
Y3015722D01*
X781456D01*
G01X779856Y3011855D02*
X777456D01*
G01X793256Y3008922D02*
X793856Y3008255D01*
X794556Y3007855D01*
X795456Y3007722D01*
X796356Y3007989D01*
X797056Y3008522D01*
X797556Y3009455D01*
X797656Y3010522D01*
X797456Y3011589D01*
X796956Y3012255D01*
X796256Y3012789D01*
X795556Y3012922D01*
X794856Y3012789D01*
X793956Y3012255D01*
X794256Y3015722D01*
X796956D01*
G01X803456D02*
X802656Y3015455D01*
X802056Y3014789D01*
X801656Y3013989D01*
X801356Y3012922D01*
X801256Y3011722D01*
X801356Y3010522D01*
X801656Y3009455D01*
X802056Y3008655D01*
X802656Y3007989D01*
X803456Y3007722D01*
X804256Y3007989D01*
X804856Y3008655D01*
X805256Y3009455D01*
X805556Y3010522D01*
X805656Y3011722D01*
X805556Y3012922D01*
X805256Y3013989D01*
X804856Y3014789D01*
X804256Y3015455D01*
X803456Y3015722D01*
G01X808856Y3007722D02*
Y3015722D01*
X811456Y3009055D01*
X814056Y3015722D01*
Y3007722D01*
G01X818256Y3015722D02*
X820656D01*
G01X819456D02*
Y3007722D01*
G01X818256D02*
X820656D01*
G01X825456Y3015722D02*
Y3007722D01*
X829456D01*
G01X833356Y3008788D02*
X834156Y3008122D01*
X835056Y3007722D01*
X835856D01*
X836656Y3008122D01*
X837256Y3008788D01*
X837556Y3009722D01*
X837356Y3010655D01*
X836856Y3011455D01*
X835956Y3011989D01*
X834756Y3012255D01*
X834056Y3012789D01*
X833756Y3013722D01*
X833956Y3014655D01*
X834456Y3015322D01*
X835156Y3015722D01*
X835856D01*
X836556Y3015455D01*
X837156Y3014789D01*
G01X843256Y3006255D02*
X843656Y3007989D01*
G01X857456Y3007722D02*
Y3015722D01*
X859856D01*
X860656Y3015322D01*
X861256Y3014389D01*
X861456Y3013322D01*
X861256Y3012255D01*
X860756Y3011455D01*
X859856Y3011055D01*
X857456D01*
G01X866256Y3015722D02*
X868656D01*
G01X867456D02*
Y3007722D01*
G01X866256D02*
X868656D01*
G01X875456Y3015722D02*
Y3007722D01*
G01X873156Y3015722D02*
X877756D01*
G01X885656Y3015055D02*
X885056Y3015455D01*
X884356Y3015722D01*
X883556D01*
X882656Y3015322D01*
X881956Y3014655D01*
X881456Y3013855D01*
X881056Y3012522D01*
X880956Y3011322D01*
X881156Y3010122D01*
X881456Y3009322D01*
X882056Y3008522D01*
X882756Y3007989D01*
X883456Y3007722D01*
X884156D01*
X884856Y3007989D01*
X885456Y3008389D01*
X885956Y3008922D01*
G01X889356Y3007722D02*
Y3015722D01*
G01X893556D02*
Y3007722D01*
G01Y3011722D02*
X889356D01*
G01X906956Y3005055D02*
X905956Y3006389D01*
X905456Y3007722D01*
Y3013055D01*
X905956Y3014389D01*
X906956Y3015722D01*
G01X913356Y3008788D02*
X914156Y3008122D01*
X915056Y3007722D01*
X915856D01*
X916656Y3008122D01*
X917256Y3008788D01*
X917556Y3009722D01*
X917356Y3010655D01*
X916856Y3011455D01*
X915956Y3011989D01*
X914756Y3012255D01*
X914056Y3012789D01*
X913756Y3013722D01*
X913956Y3014655D01*
X914456Y3015322D01*
X915156Y3015722D01*
X915856D01*
X916556Y3015455D01*
X917156Y3014789D01*
G01X921356Y3007722D02*
Y3015722D01*
G01X925556D02*
Y3007722D01*
G01Y3011722D02*
X921356D01*
G01X928956Y3007722D02*
X931456Y3015722D01*
X933956Y3007722D01*
G01X933056Y3010522D02*
X929856D01*
G01X937456Y3007722D02*
Y3015722D01*
X939856D01*
X940656Y3015322D01*
X941256Y3014389D01*
X941456Y3013322D01*
X941256Y3012255D01*
X940756Y3011455D01*
X939856Y3011055D01*
X937456D01*
G01X949456Y3007722D02*
X945456D01*
Y3015722D01*
X949456D01*
G01X947856Y3011855D02*
X945456D01*
G01X965656Y3015055D02*
X965056Y3015455D01*
X964356Y3015722D01*
X963556D01*
X962656Y3015322D01*
X961956Y3014655D01*
X961456Y3013855D01*
X961056Y3012522D01*
X960956Y3011322D01*
X961156Y3010122D01*
X961456Y3009322D01*
X962056Y3008522D01*
X962756Y3007989D01*
X963456Y3007722D01*
X964156D01*
X964856Y3007989D01*
X965456Y3008389D01*
X965956Y3008922D01*
G01X973456Y3007722D02*
X969456D01*
Y3015722D01*
X973456D01*
G01X971856Y3011855D02*
X969456D01*
G01X977156Y3007722D02*
Y3015722D01*
X981756Y3007722D01*
Y3015722D01*
G01X987456D02*
Y3007722D01*
G01X985156Y3015722D02*
X989756D01*
G01X997456Y3007722D02*
X993456D01*
Y3015722D01*
X997456D01*
G01X995856Y3011855D02*
X993456D01*
G01X1001456Y3007722D02*
Y3015722D01*
X1003956D01*
X1004756Y3015322D01*
X1005256Y3014789D01*
X1005456Y3013722D01*
X1005256Y3012655D01*
X1004656Y3011989D01*
X1003956Y3011589D01*
X1001456D01*
G01X1003956D02*
X1005456Y3007722D01*
G01X1019456Y3015722D02*
Y3007722D01*
G01X1017156Y3015722D02*
X1021756D01*
G01X1027456Y3007722D02*
X1026656Y3007855D01*
X1025956Y3008389D01*
X1025356Y3009189D01*
X1024956Y3010122D01*
X1024756Y3011189D01*
Y3012255D01*
X1024956Y3013322D01*
X1025356Y3014255D01*
X1025956Y3015055D01*
X1026656Y3015589D01*
X1027456Y3015722D01*
X1028256Y3015589D01*
X1028956Y3015055D01*
X1029556Y3014255D01*
X1029956Y3013322D01*
X1030156Y3012255D01*
Y3011189D01*
X1029956Y3010122D01*
X1029556Y3009189D01*
X1028956Y3008389D01*
X1028256Y3007855D01*
X1027456Y3007722D01*
G01X1045656Y3015055D02*
X1045056Y3015455D01*
X1044356Y3015722D01*
X1043556D01*
X1042656Y3015322D01*
X1041956Y3014655D01*
X1041456Y3013855D01*
X1041056Y3012522D01*
X1040956Y3011322D01*
X1041156Y3010122D01*
X1041456Y3009322D01*
X1042056Y3008522D01*
X1042756Y3007989D01*
X1043456Y3007722D01*
X1044156D01*
X1044856Y3007989D01*
X1045456Y3008389D01*
X1045956Y3008922D01*
G01X1053456Y3007722D02*
X1049456D01*
Y3015722D01*
X1053456D01*
G01X1051856Y3011855D02*
X1049456D01*
G01X1057156Y3007722D02*
Y3015722D01*
X1061756Y3007722D01*
Y3015722D01*
G01X1067456D02*
Y3007722D01*
G01X1065156Y3015722D02*
X1069756D01*
G01X1077456Y3007722D02*
X1073456D01*
Y3015722D01*
X1077456D01*
G01X1075856Y3011855D02*
X1073456D01*
G01X1081456Y3007722D02*
Y3015722D01*
X1083956D01*
X1084756Y3015322D01*
X1085256Y3014789D01*
X1085456Y3013722D01*
X1085256Y3012655D01*
X1084656Y3011989D01*
X1083956Y3011589D01*
X1081456D01*
G01X1083956D02*
X1085456Y3007722D01*
G01X1091956Y3005055D02*
X1092956Y3006389D01*
X1093456Y3007722D01*
Y3013055D01*
X1092956Y3014389D01*
X1091956Y3015722D01*
G01X1099456Y3007455D02*
X1099256Y3007589D01*
Y3007855D01*
X1099456Y3007989D01*
X1099656Y3007855D01*
Y3007589D01*
X1099456Y3007455D01*
G01Y3011055D02*
X1099256Y3011189D01*
Y3011455D01*
X1099456Y3011589D01*
X1099656Y3011455D01*
Y3011189D01*
X1099456Y3011055D01*
G01X1115456Y3007722D02*
Y3015722D01*
X1114256Y3014122D01*
G01Y3007722D02*
X1116656D01*
G01X1123456Y3015722D02*
X1122656Y3015455D01*
X1122056Y3014789D01*
X1121656Y3013989D01*
X1121356Y3012922D01*
X1121256Y3011722D01*
X1121356Y3010522D01*
X1121656Y3009455D01*
X1122056Y3008655D01*
X1122656Y3007989D01*
X1123456Y3007722D01*
X1124256Y3007989D01*
X1124856Y3008655D01*
X1125256Y3009455D01*
X1125556Y3010522D01*
X1125656Y3011722D01*
X1125556Y3012922D01*
X1125256Y3013989D01*
X1124856Y3014789D01*
X1124256Y3015455D01*
X1123456Y3015722D01*
G01X1131456D02*
X1130656Y3015455D01*
X1130056Y3014789D01*
X1129656Y3013989D01*
X1129356Y3012922D01*
X1129256Y3011722D01*
X1129356Y3010522D01*
X1129656Y3009455D01*
X1130056Y3008655D01*
X1130656Y3007989D01*
X1131456Y3007722D01*
X1132256Y3007989D01*
X1132856Y3008655D01*
X1133256Y3009455D01*
X1133556Y3010522D01*
X1133656Y3011722D01*
X1133556Y3012922D01*
X1133256Y3013989D01*
X1132856Y3014789D01*
X1132256Y3015455D01*
X1131456Y3015722D01*
G01X1136856Y3007722D02*
Y3015722D01*
X1139456Y3009055D01*
X1142056Y3015722D01*
Y3007722D01*
G01X1146256Y3015722D02*
X1148656D01*
G01X1147456D02*
Y3007722D01*
G01X1146256D02*
X1148656D01*
G01X1153456Y3015722D02*
Y3007722D01*
X1157456D01*
G01X1161356Y3008788D02*
X1162156Y3008122D01*
X1163056Y3007722D01*
X1163856D01*
X1164656Y3008122D01*
X1165256Y3008788D01*
X1165556Y3009722D01*
X1165356Y3010655D01*
X1164856Y3011455D01*
X1163956Y3011989D01*
X1162756Y3012255D01*
X1162056Y3012789D01*
X1161756Y3013722D01*
X1161956Y3014655D01*
X1162456Y3015322D01*
X1163156Y3015722D01*
X1163856D01*
X1164556Y3015455D01*
X1165156Y3014789D01*
G01X1171456Y3007455D02*
X1171256Y3007589D01*
Y3007855D01*
X1171456Y3007989D01*
X1171656Y3007855D01*
Y3007589D01*
X1171456Y3007455D01*
G01X1185256Y3007722D02*
Y3015722D01*
X1187256D01*
X1188056Y3015322D01*
X1188656Y3014789D01*
X1189156Y3013989D01*
X1189556Y3013055D01*
X1189656Y3011722D01*
X1189556Y3010389D01*
X1189156Y3009455D01*
X1188656Y3008655D01*
X1188056Y3008122D01*
X1187256Y3007722D01*
X1185256D01*
G01X1193456D02*
Y3015722D01*
X1195956D01*
X1196756Y3015322D01*
X1197256Y3014789D01*
X1197456Y3013722D01*
X1197256Y3012655D01*
X1196656Y3011989D01*
X1195956Y3011589D01*
X1193456D01*
G01X1195956D02*
X1197456Y3007722D01*
G01X1202256Y3015722D02*
X1204656D01*
G01X1203456D02*
Y3007722D01*
G01X1202256D02*
X1204656D01*
G01X1209456Y3015722D02*
Y3007722D01*
X1213456D01*
G01X1217456Y3015722D02*
Y3007722D01*
X1221456D01*
G01X1225656Y3007455D02*
X1229256Y3015722D01*
G01X1233556Y3007722D02*
Y3015722D01*
X1237356D01*
G01X1235956Y3011855D02*
X1233556D01*
G01X1245456Y3007722D02*
X1241456D01*
Y3015722D01*
X1245456D01*
G01X1243856Y3011855D02*
X1241456D01*
G01X1248956Y3007722D02*
X1251456Y3015722D01*
X1253956Y3007722D01*
G01X1253056Y3010522D02*
X1249856D01*
G01X1259456Y3015722D02*
Y3007722D01*
G01X1257156Y3015722D02*
X1261756D01*
G01X1265256D02*
Y3009989D01*
X1265656Y3008788D01*
X1266456Y3007989D01*
X1267456Y3007722D01*
X1268456Y3007989D01*
X1269256Y3008788D01*
X1269656Y3009989D01*
Y3015722D01*
G01X1273456Y3007722D02*
Y3015722D01*
X1275956D01*
X1276756Y3015322D01*
X1277256Y3014789D01*
X1277456Y3013722D01*
X1277256Y3012655D01*
X1276656Y3011989D01*
X1275956Y3011589D01*
X1273456D01*
G01X1275956D02*
X1277456Y3007722D01*
G01X1285456D02*
X1281456D01*
Y3015722D01*
X1285456D01*
G01X1283856Y3011855D02*
X1281456D01*
G01X1289656Y3007455D02*
X1293256Y3015722D01*
G01X1297456Y3007722D02*
Y3015722D01*
X1299956D01*
X1300756Y3015322D01*
X1301256Y3014789D01*
X1301456Y3013722D01*
X1301256Y3012655D01*
X1300656Y3011989D01*
X1299956Y3011589D01*
X1297456D01*
G01X1299956D02*
X1301456Y3007722D01*
G01X1307456D02*
X1306656Y3007855D01*
X1305956Y3008389D01*
X1305356Y3009189D01*
X1304956Y3010122D01*
X1304756Y3011189D01*
Y3012255D01*
X1304956Y3013322D01*
X1305356Y3014255D01*
X1305956Y3015055D01*
X1306656Y3015589D01*
X1307456Y3015722D01*
X1308256Y3015589D01*
X1308956Y3015055D01*
X1309556Y3014255D01*
X1309956Y3013322D01*
X1310156Y3012255D01*
Y3011189D01*
X1309956Y3010122D01*
X1309556Y3009189D01*
X1308956Y3008389D01*
X1308256Y3007855D01*
X1307456Y3007722D01*
G01X1313256Y3015722D02*
Y3009989D01*
X1313656Y3008788D01*
X1314456Y3007989D01*
X1315456Y3007722D01*
X1316456Y3007989D01*
X1317256Y3008788D01*
X1317656Y3009989D01*
Y3015722D01*
G01X1323456D02*
Y3007722D01*
G01X1321156Y3015722D02*
X1325756D01*
G01X1333456Y3007722D02*
X1329456D01*
Y3015722D01*
X1333456D01*
G01X1331856Y3011855D02*
X1329456D01*
G01X1337656Y3007455D02*
X1341256Y3015722D01*
G01X1345456Y3007722D02*
Y3015722D01*
X1347856D01*
X1348656Y3015322D01*
X1349256Y3014389D01*
X1349456Y3013322D01*
X1349256Y3012255D01*
X1348756Y3011455D01*
X1347856Y3011055D01*
X1345456D01*
G01X1353456Y3007722D02*
Y3015722D01*
X1355956D01*
X1356756Y3015322D01*
X1357256Y3014789D01*
X1357456Y3013722D01*
X1357256Y3012655D01*
X1356656Y3011989D01*
X1355956Y3011589D01*
X1353456D01*
G01X1355956D02*
X1357456Y3007722D01*
G01X1363456D02*
X1362656Y3007855D01*
X1361956Y3008389D01*
X1361356Y3009189D01*
X1360956Y3010122D01*
X1360756Y3011189D01*
Y3012255D01*
X1360956Y3013322D01*
X1361356Y3014255D01*
X1361956Y3015055D01*
X1362656Y3015589D01*
X1363456Y3015722D01*
X1364256Y3015589D01*
X1364956Y3015055D01*
X1365556Y3014255D01*
X1365956Y3013322D01*
X1366156Y3012255D01*
Y3011189D01*
X1365956Y3010122D01*
X1365556Y3009189D01*
X1364956Y3008389D01*
X1364256Y3007855D01*
X1363456Y3007722D01*
G01X1369556D02*
Y3015722D01*
X1373356D01*
G01X1371956Y3011855D02*
X1369556D01*
G01X1378256Y3015722D02*
X1380656D01*
G01X1379456D02*
Y3007722D01*
G01X1378256D02*
X1380656D01*
G01X1385456Y3015722D02*
Y3007722D01*
X1389456D01*
G01X1397456D02*
X1393456D01*
Y3015722D01*
X1397456D01*
G01X1395856Y3011855D02*
X1393456D01*
G01X1409356Y3008788D02*
X1410156Y3008122D01*
X1411056Y3007722D01*
X1411856D01*
X1412656Y3008122D01*
X1413256Y3008788D01*
X1413556Y3009722D01*
X1413356Y3010655D01*
X1412856Y3011455D01*
X1411956Y3011989D01*
X1410756Y3012255D01*
X1410056Y3012789D01*
X1409756Y3013722D01*
X1409956Y3014655D01*
X1410456Y3015322D01*
X1411156Y3015722D01*
X1411856D01*
X1412556Y3015455D01*
X1413156Y3014789D01*
G01X1417456Y3007722D02*
Y3015722D01*
X1419856D01*
X1420656Y3015322D01*
X1421256Y3014389D01*
X1421456Y3013322D01*
X1421256Y3012255D01*
X1420756Y3011455D01*
X1419856Y3011055D01*
X1417456D01*
G01X1424956Y3007722D02*
X1427456Y3015722D01*
X1429956Y3007722D01*
G01X1429056Y3010522D02*
X1425856D01*
G01X1437656Y3015055D02*
X1437056Y3015455D01*
X1436356Y3015722D01*
X1435556D01*
X1434656Y3015322D01*
X1433956Y3014655D01*
X1433456Y3013855D01*
X1433056Y3012522D01*
X1432956Y3011322D01*
X1433156Y3010122D01*
X1433456Y3009322D01*
X1434056Y3008522D01*
X1434756Y3007989D01*
X1435456Y3007722D01*
X1436156D01*
X1436856Y3007989D01*
X1437456Y3008389D01*
X1437956Y3008922D01*
G01X1442256Y3015722D02*
X1444656D01*
G01X1443456D02*
Y3007722D01*
G01X1442256D02*
X1444656D01*
G01X1449156D02*
Y3015722D01*
X1453756Y3007722D01*
Y3015722D01*
G01X1460056Y3011722D02*
X1462056D01*
Y3009322D01*
X1461456Y3008522D01*
X1460756Y3007989D01*
X1459756Y3007722D01*
X1458756Y3007989D01*
X1458056Y3008522D01*
X1457456Y3009322D01*
X1457056Y3010255D01*
X1456856Y3011322D01*
Y3012255D01*
X1457056Y3013055D01*
X1457456Y3013989D01*
X1458056Y3014789D01*
X1458656Y3015322D01*
X1459456Y3015722D01*
X1460156D01*
X1460956Y3015455D01*
X1461556Y3014922D01*
G01X1472956Y3007722D02*
X1475456Y3015722D01*
X1477956Y3007722D01*
G01X1477056Y3010522D02*
X1473856D01*
G01X1481456Y3015722D02*
Y3007722D01*
X1485456D01*
G01X1489456Y3015722D02*
Y3007722D01*
X1493456D01*
G01X1505256Y3015722D02*
Y3009989D01*
X1505656Y3008788D01*
X1506456Y3007989D01*
X1507456Y3007722D01*
X1508456Y3007989D01*
X1509256Y3008788D01*
X1509656Y3009989D01*
Y3015722D01*
G01X1513356Y3008788D02*
X1514156Y3008122D01*
X1515056Y3007722D01*
X1515856D01*
X1516656Y3008122D01*
X1517256Y3008788D01*
X1517556Y3009722D01*
X1517356Y3010655D01*
X1516856Y3011455D01*
X1515956Y3011989D01*
X1514756Y3012255D01*
X1514056Y3012789D01*
X1513756Y3013722D01*
X1513956Y3014655D01*
X1514456Y3015322D01*
X1515156Y3015722D01*
X1515856D01*
X1516556Y3015455D01*
X1517156Y3014789D01*
G01X1522256Y3015722D02*
X1524656D01*
G01X1523456D02*
Y3007722D01*
G01X1522256D02*
X1524656D01*
G01X1529156D02*
Y3015722D01*
X1533756Y3007722D01*
Y3015722D01*
G01X1540056Y3011722D02*
X1542056D01*
Y3009322D01*
X1541456Y3008522D01*
X1540756Y3007989D01*
X1539756Y3007722D01*
X1538756Y3007989D01*
X1538056Y3008522D01*
X1537456Y3009322D01*
X1537056Y3010255D01*
X1536856Y3011322D01*
Y3012255D01*
X1537056Y3013055D01*
X1537456Y3013989D01*
X1538056Y3014789D01*
X1538656Y3015322D01*
X1539456Y3015722D01*
X1540156D01*
X1540956Y3015455D01*
X1541556Y3014922D01*
G01X1555456Y3007722D02*
Y3015722D01*
X1554256Y3014122D01*
G01Y3007722D02*
X1556656D01*
G01X1563456Y3015722D02*
X1562656Y3015455D01*
X1562056Y3014789D01*
X1561656Y3013989D01*
X1561356Y3012922D01*
X1561256Y3011722D01*
X1561356Y3010522D01*
X1561656Y3009455D01*
X1562056Y3008655D01*
X1562656Y3007989D01*
X1563456Y3007722D01*
X1564256Y3007989D01*
X1564856Y3008655D01*
X1565256Y3009455D01*
X1565556Y3010522D01*
X1565656Y3011722D01*
X1565556Y3012922D01*
X1565256Y3013989D01*
X1564856Y3014789D01*
X1564256Y3015455D01*
X1563456Y3015722D01*
G01X1571456D02*
X1570656Y3015455D01*
X1570056Y3014789D01*
X1569656Y3013989D01*
X1569356Y3012922D01*
X1569256Y3011722D01*
X1569356Y3010522D01*
X1569656Y3009455D01*
X1570056Y3008655D01*
X1570656Y3007989D01*
X1571456Y3007722D01*
X1572256Y3007989D01*
X1572856Y3008655D01*
X1573256Y3009455D01*
X1573556Y3010522D01*
X1573656Y3011722D01*
X1573556Y3012922D01*
X1573256Y3013989D01*
X1572856Y3014789D01*
X1572256Y3015455D01*
X1571456Y3015722D01*
G01X1576856Y3007722D02*
Y3015722D01*
X1579456Y3009055D01*
X1582056Y3015722D01*
Y3007722D01*
G01X1586256Y3015722D02*
X1588656D01*
G01X1587456D02*
Y3007722D01*
G01X1586256D02*
X1588656D01*
G01X1593456Y3015722D02*
Y3007722D01*
X1597456D01*
G01X1601356Y3008788D02*
X1602156Y3008122D01*
X1603056Y3007722D01*
X1603856D01*
X1604656Y3008122D01*
X1605256Y3008788D01*
X1605556Y3009722D01*
X1605356Y3010655D01*
X1604856Y3011455D01*
X1603956Y3011989D01*
X1602756Y3012255D01*
X1602056Y3012789D01*
X1601756Y3013722D01*
X1601956Y3014655D01*
X1602456Y3015322D01*
X1603156Y3015722D01*
X1603856D01*
X1604556Y3015455D01*
X1605156Y3014789D01*
G01X1611456Y3007455D02*
X1611256Y3007589D01*
Y3007855D01*
X1611456Y3007989D01*
X1611656Y3007855D01*
Y3007589D01*
X1611456Y3007455D01*
G01X1633456Y3015722D02*
Y3007722D01*
X1637456D01*
G01X1640956D02*
X1643456Y3015722D01*
X1645956Y3007722D01*
G01X1645056Y3010522D02*
X1641856D01*
G01X1652256Y3011989D02*
X1652656Y3012389D01*
X1652956Y3013055D01*
X1653156Y3013989D01*
X1652956Y3014789D01*
X1652556Y3015322D01*
X1651856Y3015722D01*
X1649156D01*
Y3007722D01*
X1652456D01*
X1653156Y3008255D01*
X1653556Y3009055D01*
X1653756Y3009989D01*
X1653556Y3010922D01*
X1652956Y3011722D01*
X1652256Y3011989D01*
X1649156D01*
G01X1661456Y3007722D02*
X1657456D01*
Y3015722D01*
X1661456D01*
G01X1659856Y3011855D02*
X1657456D01*
G01X1665456Y3015722D02*
Y3007722D01*
X1669456D01*
G01X1680956D02*
X1683456Y3015722D01*
X1685956Y3007722D01*
G01X1685056Y3010522D02*
X1681856D01*
G01X1689456Y3007722D02*
Y3015722D01*
X1691956D01*
X1692756Y3015322D01*
X1693256Y3014789D01*
X1693456Y3013722D01*
X1693256Y3012655D01*
X1692656Y3011989D01*
X1691956Y3011589D01*
X1689456D01*
G01X1691956D02*
X1693456Y3007722D01*
G01X1701456D02*
X1697456D01*
Y3015722D01*
X1701456D01*
G01X1699856Y3011855D02*
X1697456D01*
G01X1704956Y3007722D02*
X1707456Y3015722D01*
X1709956Y3007722D01*
G01X1709056Y3010522D02*
X1705856D01*
G01X1721156Y3007722D02*
Y3015722D01*
X1725756Y3007722D01*
Y3015722D01*
G01X1731456Y3007722D02*
X1730656Y3007855D01*
X1729956Y3008389D01*
X1729356Y3009189D01*
X1728956Y3010122D01*
X1728756Y3011189D01*
Y3012255D01*
X1728956Y3013322D01*
X1729356Y3014255D01*
X1729956Y3015055D01*
X1730656Y3015589D01*
X1731456Y3015722D01*
X1732256Y3015589D01*
X1732956Y3015055D01*
X1733556Y3014255D01*
X1733956Y3013322D01*
X1734156Y3012255D01*
Y3011189D01*
X1733956Y3010122D01*
X1733556Y3009189D01*
X1732956Y3008389D01*
X1732256Y3007855D01*
X1731456Y3007722D01*
G01X1744956D02*
X1747456Y3015722D01*
X1749956Y3007722D01*
G01X1749056Y3010522D02*
X1745856D01*
G01X1753256Y3007722D02*
Y3015722D01*
X1755256D01*
X1756056Y3015322D01*
X1756656Y3014789D01*
X1757156Y3013989D01*
X1757556Y3013055D01*
X1757656Y3011722D01*
X1757556Y3010389D01*
X1757156Y3009455D01*
X1756656Y3008655D01*
X1756056Y3008122D01*
X1755256Y3007722D01*
X1753256D01*
G01X1761256D02*
Y3015722D01*
X1763256D01*
X1764056Y3015322D01*
X1764656Y3014789D01*
X1765156Y3013989D01*
X1765556Y3013055D01*
X1765656Y3011722D01*
X1765556Y3010389D01*
X1765156Y3009455D01*
X1764656Y3008655D01*
X1764056Y3008122D01*
X1763256Y3007722D01*
X1761256D01*
G01X1777256D02*
Y3015722D01*
X1779256D01*
X1780056Y3015322D01*
X1780656Y3014789D01*
X1781156Y3013989D01*
X1781556Y3013055D01*
X1781656Y3011722D01*
X1781556Y3010389D01*
X1781156Y3009455D01*
X1780656Y3008655D01*
X1780056Y3008122D01*
X1779256Y3007722D01*
X1777256D01*
G01X1785256Y3015722D02*
Y3009989D01*
X1785656Y3008788D01*
X1786456Y3007989D01*
X1787456Y3007722D01*
X1788456Y3007989D01*
X1789256Y3008788D01*
X1789656Y3009989D01*
Y3015722D01*
G01X1792856Y3007722D02*
Y3015722D01*
X1795456Y3009055D01*
X1798056Y3015722D01*
Y3007722D01*
G01X1800856D02*
Y3015722D01*
X1803456Y3009055D01*
X1806056Y3015722D01*
Y3007722D01*
G01X1811456D02*
Y3011322D01*
X1809456Y3015722D01*
G01X1813456D02*
X1811456Y3011322D01*
G01X1825456Y3007722D02*
Y3015722D01*
X1827856D01*
X1828656Y3015322D01*
X1829256Y3014389D01*
X1829456Y3013322D01*
X1829256Y3012255D01*
X1828756Y3011455D01*
X1827856Y3011055D01*
X1825456D01*
G01X1832956Y3007722D02*
X1835456Y3015722D01*
X1837956Y3007722D01*
G01X1837056Y3010522D02*
X1833856D01*
G01X1841256Y3007722D02*
Y3015722D01*
X1843256D01*
X1844056Y3015322D01*
X1844656Y3014789D01*
X1845156Y3013989D01*
X1845556Y3013055D01*
X1845656Y3011722D01*
X1845556Y3010389D01*
X1845156Y3009455D01*
X1844656Y3008655D01*
X1844056Y3008122D01*
X1843256Y3007722D01*
X1841256D01*
G01X1851456Y3007455D02*
X1851256Y3007589D01*
Y3007855D01*
X1851456Y3007989D01*
X1851656Y3007855D01*
Y3007589D01*
X1851456Y3007455D01*
G01X233256Y3068922D02*
X233856Y3068255D01*
X234556Y3067855D01*
X235456Y3067722D01*
X236356Y3067989D01*
X237056Y3068522D01*
X237556Y3069455D01*
X237656Y3070522D01*
X237456Y3071589D01*
X236956Y3072255D01*
X236256Y3072789D01*
X235556Y3072922D01*
X234856Y3072789D01*
X233956Y3072255D01*
X234256Y3075722D01*
X236956D01*
G01X243456Y3067455D02*
X243256Y3067589D01*
Y3067855D01*
X243456Y3067989D01*
X243656Y3067855D01*
Y3067589D01*
X243456Y3067455D01*
G01X249456Y3067722D02*
Y3075722D01*
X251856D01*
X252656Y3075322D01*
X253256Y3074389D01*
X253456Y3073322D01*
X253256Y3072255D01*
X252756Y3071455D01*
X251856Y3071055D01*
X249456D01*
G01X261456Y3067722D02*
X257456D01*
Y3075722D01*
X261456D01*
G01X259856Y3071855D02*
X257456D01*
G01X269456Y3067722D02*
X265456D01*
Y3075722D01*
X269456D01*
G01X267856Y3071855D02*
X265456D01*
G01X273456Y3075722D02*
Y3067722D01*
X277456D01*
G01X282256Y3075722D02*
X284656D01*
G01X283456D02*
Y3067722D01*
G01X282256D02*
X284656D01*
G01X289156D02*
Y3075722D01*
X293756Y3067722D01*
Y3075722D01*
G01X300056Y3071722D02*
X302056D01*
Y3069322D01*
X301456Y3068522D01*
X300756Y3067989D01*
X299756Y3067722D01*
X298756Y3067989D01*
X298056Y3068522D01*
X297456Y3069322D01*
X297056Y3070255D01*
X296856Y3071322D01*
Y3072255D01*
X297056Y3073055D01*
X297456Y3073989D01*
X298056Y3074789D01*
X298656Y3075322D01*
X299456Y3075722D01*
X300156D01*
X300956Y3075455D01*
X301556Y3074922D01*
G01X313356Y3068788D02*
X314156Y3068122D01*
X315056Y3067722D01*
X315856D01*
X316656Y3068122D01*
X317256Y3068788D01*
X317556Y3069722D01*
X317356Y3070655D01*
X316856Y3071455D01*
X315956Y3071989D01*
X314756Y3072255D01*
X314056Y3072789D01*
X313756Y3073722D01*
X313956Y3074655D01*
X314456Y3075322D01*
X315156Y3075722D01*
X315856D01*
X316556Y3075455D01*
X317156Y3074789D01*
G01X323456Y3075722D02*
Y3067722D01*
G01X321156Y3075722D02*
X325756D01*
G01X329456Y3067722D02*
Y3075722D01*
X331956D01*
X332756Y3075322D01*
X333256Y3074789D01*
X333456Y3073722D01*
X333256Y3072655D01*
X332656Y3071989D01*
X331956Y3071589D01*
X329456D01*
G01X331956D02*
X333456Y3067722D01*
G01X341456D02*
X337456D01*
Y3075722D01*
X341456D01*
G01X339856Y3071855D02*
X337456D01*
G01X345156Y3067722D02*
Y3075722D01*
X349756Y3067722D01*
Y3075722D01*
G01X356056Y3071722D02*
X358056D01*
Y3069322D01*
X357456Y3068522D01*
X356756Y3067989D01*
X355756Y3067722D01*
X354756Y3067989D01*
X354056Y3068522D01*
X353456Y3069322D01*
X353056Y3070255D01*
X352856Y3071322D01*
Y3072255D01*
X353056Y3073055D01*
X353456Y3073989D01*
X354056Y3074789D01*
X354656Y3075322D01*
X355456Y3075722D01*
X356156D01*
X356956Y3075455D01*
X357556Y3074922D01*
G01X363456Y3075722D02*
Y3067722D01*
G01X361156Y3075722D02*
X365756D01*
G01X369356Y3067722D02*
Y3075722D01*
G01X373556D02*
Y3067722D01*
G01Y3071722D02*
X369356D01*
G01X384956Y3067722D02*
X387456Y3075722D01*
X389956Y3067722D01*
G01X389056Y3070522D02*
X385856D01*
G01X393156Y3067722D02*
Y3075722D01*
X397756Y3067722D01*
Y3075722D01*
G01X401256Y3067722D02*
Y3075722D01*
X403256D01*
X404056Y3075322D01*
X404656Y3074789D01*
X405156Y3073989D01*
X405556Y3073055D01*
X405656Y3071722D01*
X405556Y3070389D01*
X405156Y3069455D01*
X404656Y3068655D01*
X404056Y3068122D01*
X403256Y3067722D01*
X401256D01*
G01X420256Y3071989D02*
X420656Y3072389D01*
X420956Y3073055D01*
X421156Y3073989D01*
X420956Y3074789D01*
X420556Y3075322D01*
X419856Y3075722D01*
X417156D01*
Y3067722D01*
X420456D01*
X421156Y3068255D01*
X421556Y3069055D01*
X421756Y3069989D01*
X421556Y3070922D01*
X420956Y3071722D01*
X420256Y3071989D01*
X417156D01*
G01X428056Y3071722D02*
X430056D01*
Y3069322D01*
X429456Y3068522D01*
X428756Y3067989D01*
X427756Y3067722D01*
X426756Y3067989D01*
X426056Y3068522D01*
X425456Y3069322D01*
X425056Y3070255D01*
X424856Y3071322D01*
Y3072255D01*
X425056Y3073055D01*
X425456Y3073989D01*
X426056Y3074789D01*
X426656Y3075322D01*
X427456Y3075722D01*
X428156D01*
X428956Y3075455D01*
X429556Y3074922D01*
G01X432956Y3067722D02*
X435456Y3075722D01*
X437956Y3067722D01*
G01X437056Y3070522D02*
X433856D01*
G01X449456Y3067722D02*
Y3075722D01*
X451856D01*
X452656Y3075322D01*
X453256Y3074389D01*
X453456Y3073322D01*
X453256Y3072255D01*
X452756Y3071455D01*
X451856Y3071055D01*
X449456D01*
G01X456956Y3067722D02*
X459456Y3075722D01*
X461956Y3067722D01*
G01X461056Y3070522D02*
X457856D01*
G01X465256Y3067722D02*
Y3075722D01*
X467256D01*
X468056Y3075322D01*
X468656Y3074789D01*
X469156Y3073989D01*
X469556Y3073055D01*
X469656Y3071722D01*
X469556Y3070389D01*
X469156Y3069455D01*
X468656Y3068655D01*
X468056Y3068122D01*
X467256Y3067722D01*
X465256D01*
G01X473356Y3068788D02*
X474156Y3068122D01*
X475056Y3067722D01*
X475856D01*
X476656Y3068122D01*
X477256Y3068788D01*
X477556Y3069722D01*
X477356Y3070655D01*
X476856Y3071455D01*
X475956Y3071989D01*
X474756Y3072255D01*
X474056Y3072789D01*
X473756Y3073722D01*
X473956Y3074655D01*
X474456Y3075322D01*
X475156Y3075722D01*
X475856D01*
X476556Y3075455D01*
X477156Y3074789D01*
G01X488956Y3067722D02*
X491456Y3075722D01*
X493956Y3067722D01*
G01X493056Y3070522D02*
X489856D01*
G01X497256Y3067722D02*
Y3075722D01*
X499256D01*
X500056Y3075322D01*
X500656Y3074789D01*
X501156Y3073989D01*
X501556Y3073055D01*
X501656Y3071722D01*
X501556Y3070389D01*
X501156Y3069455D01*
X500656Y3068655D01*
X500056Y3068122D01*
X499256Y3067722D01*
X497256D01*
G01X505356D02*
Y3075722D01*
G01X509556D02*
Y3067722D01*
G01Y3071722D02*
X505356D01*
G01X517456Y3067722D02*
X513456D01*
Y3075722D01*
X517456D01*
G01X515856Y3071855D02*
X513456D01*
G01X521356Y3068788D02*
X522156Y3068122D01*
X523056Y3067722D01*
X523856D01*
X524656Y3068122D01*
X525256Y3068788D01*
X525556Y3069722D01*
X525356Y3070655D01*
X524856Y3071455D01*
X523956Y3071989D01*
X522756Y3072255D01*
X522056Y3072789D01*
X521756Y3073722D01*
X521956Y3074655D01*
X522456Y3075322D01*
X523156Y3075722D01*
X523856D01*
X524556Y3075455D01*
X525156Y3074789D01*
G01X530256Y3075722D02*
X532656D01*
G01X531456D02*
Y3067722D01*
G01X530256D02*
X532656D01*
G01X539456D02*
X538656Y3067855D01*
X537956Y3068389D01*
X537356Y3069189D01*
X536956Y3070122D01*
X536756Y3071189D01*
Y3072255D01*
X536956Y3073322D01*
X537356Y3074255D01*
X537956Y3075055D01*
X538656Y3075589D01*
X539456Y3075722D01*
X540256Y3075589D01*
X540956Y3075055D01*
X541556Y3074255D01*
X541956Y3073322D01*
X542156Y3072255D01*
Y3071189D01*
X541956Y3070122D01*
X541556Y3069189D01*
X540956Y3068389D01*
X540256Y3067855D01*
X539456Y3067722D01*
G01X545156D02*
Y3075722D01*
X549756Y3067722D01*
Y3075722D01*
G01X563456D02*
Y3067722D01*
G01X561156Y3075722D02*
X565756D01*
G01X573456Y3067722D02*
X569456D01*
Y3075722D01*
X573456D01*
G01X571856Y3071855D02*
X569456D01*
G01X577356Y3068788D02*
X578156Y3068122D01*
X579056Y3067722D01*
X579856D01*
X580656Y3068122D01*
X581256Y3068788D01*
X581556Y3069722D01*
X581356Y3070655D01*
X580856Y3071455D01*
X579956Y3071989D01*
X578756Y3072255D01*
X578056Y3072789D01*
X577756Y3073722D01*
X577956Y3074655D01*
X578456Y3075322D01*
X579156Y3075722D01*
X579856D01*
X580556Y3075455D01*
X581156Y3074789D01*
G01X587456Y3075722D02*
Y3067722D01*
G01X585156Y3075722D02*
X589756D01*
G01X601456Y3067722D02*
Y3075722D01*
X603856D01*
X604656Y3075322D01*
X605256Y3074389D01*
X605456Y3073322D01*
X605256Y3072255D01*
X604756Y3071455D01*
X603856Y3071055D01*
X601456D01*
G01X608956Y3067722D02*
X611456Y3075722D01*
X613956Y3067722D01*
G01X613056Y3070522D02*
X609856D01*
G01X619456Y3075722D02*
Y3067722D01*
G01X617156Y3075722D02*
X621756D01*
G01X627456D02*
Y3067722D01*
G01X625156Y3075722D02*
X629756D01*
G01X637456Y3067722D02*
X633456D01*
Y3075722D01*
X637456D01*
G01X635856Y3071855D02*
X633456D01*
G01X641456Y3067722D02*
Y3075722D01*
X643956D01*
X644756Y3075322D01*
X645256Y3074789D01*
X645456Y3073722D01*
X645256Y3072655D01*
X644656Y3071989D01*
X643956Y3071589D01*
X641456D01*
G01X643956D02*
X645456Y3067722D01*
G01X649156D02*
Y3075722D01*
X653756Y3067722D01*
Y3075722D01*
G01X657356Y3068788D02*
X658156Y3068122D01*
X659056Y3067722D01*
X659856D01*
X660656Y3068122D01*
X661256Y3068788D01*
X661556Y3069722D01*
X661356Y3070655D01*
X660856Y3071455D01*
X659956Y3071989D01*
X658756Y3072255D01*
X658056Y3072789D01*
X657756Y3073722D01*
X657956Y3074655D01*
X658456Y3075322D01*
X659156Y3075722D01*
X659856D01*
X660556Y3075455D01*
X661156Y3074789D01*
G01X667456Y3067455D02*
X667256Y3067589D01*
Y3067855D01*
X667456Y3067989D01*
X667656Y3067855D01*
Y3067589D01*
X667456Y3067455D01*
G01X236656Y3142722D02*
Y3150722D01*
X232956Y3144989D01*
X237956D01*
G01X243456Y3142455D02*
X243256Y3142589D01*
Y3142855D01*
X243456Y3142989D01*
X243656Y3142855D01*
Y3142589D01*
X243456Y3142455D01*
G01X253656Y3150055D02*
X253056Y3150455D01*
X252356Y3150722D01*
X251556D01*
X250656Y3150322D01*
X249956Y3149655D01*
X249456Y3148855D01*
X249056Y3147522D01*
X248956Y3146322D01*
X249156Y3145122D01*
X249456Y3144322D01*
X250056Y3143522D01*
X250756Y3142989D01*
X251456Y3142722D01*
X252156D01*
X252856Y3142989D01*
X253456Y3143389D01*
X253956Y3143922D01*
G01X259456Y3142722D02*
X258656Y3142855D01*
X257956Y3143389D01*
X257356Y3144189D01*
X256956Y3145122D01*
X256756Y3146189D01*
Y3147255D01*
X256956Y3148322D01*
X257356Y3149255D01*
X257956Y3150055D01*
X258656Y3150589D01*
X259456Y3150722D01*
X260256Y3150589D01*
X260956Y3150055D01*
X261556Y3149255D01*
X261956Y3148322D01*
X262156Y3147255D01*
Y3146189D01*
X261956Y3145122D01*
X261556Y3144189D01*
X260956Y3143389D01*
X260256Y3142855D01*
X259456Y3142722D01*
G01X265156D02*
Y3150722D01*
X269756Y3142722D01*
Y3150722D01*
G01X275456D02*
Y3142722D01*
G01X273156Y3150722D02*
X277756D01*
G01X281456Y3142722D02*
Y3150722D01*
X283956D01*
X284756Y3150322D01*
X285256Y3149789D01*
X285456Y3148722D01*
X285256Y3147655D01*
X284656Y3146989D01*
X283956Y3146589D01*
X281456D01*
G01X283956D02*
X285456Y3142722D01*
G01X291456D02*
X290656Y3142855D01*
X289956Y3143389D01*
X289356Y3144189D01*
X288956Y3145122D01*
X288756Y3146189D01*
Y3147255D01*
X288956Y3148322D01*
X289356Y3149255D01*
X289956Y3150055D01*
X290656Y3150589D01*
X291456Y3150722D01*
X292256Y3150589D01*
X292956Y3150055D01*
X293556Y3149255D01*
X293956Y3148322D01*
X294156Y3147255D01*
Y3146189D01*
X293956Y3145122D01*
X293556Y3144189D01*
X292956Y3143389D01*
X292256Y3142855D01*
X291456Y3142722D01*
G01X297456Y3150722D02*
Y3142722D01*
X301456D01*
G01X305456Y3150722D02*
Y3142722D01*
X309456D01*
G01X317456D02*
X313456D01*
Y3150722D01*
X317456D01*
G01X315856Y3146855D02*
X313456D01*
G01X321256Y3142722D02*
Y3150722D01*
X323256D01*
X324056Y3150322D01*
X324656Y3149789D01*
X325156Y3148989D01*
X325556Y3148055D01*
X325656Y3146722D01*
X325556Y3145389D01*
X325156Y3144455D01*
X324656Y3143655D01*
X324056Y3143122D01*
X323256Y3142722D01*
X321256D01*
G01X338256Y3150722D02*
X340656D01*
G01X339456D02*
Y3142722D01*
G01X338256D02*
X340656D01*
G01X344856D02*
Y3150722D01*
X347456Y3144055D01*
X350056Y3150722D01*
Y3142722D01*
G01X353456D02*
Y3150722D01*
X355856D01*
X356656Y3150322D01*
X357256Y3149389D01*
X357456Y3148322D01*
X357256Y3147255D01*
X356756Y3146455D01*
X355856Y3146055D01*
X353456D01*
G01X365456Y3142722D02*
X361456D01*
Y3150722D01*
X365456D01*
G01X363856Y3146855D02*
X361456D01*
G01X369256Y3142722D02*
Y3150722D01*
X371256D01*
X372056Y3150322D01*
X372656Y3149789D01*
X373156Y3148989D01*
X373556Y3148055D01*
X373656Y3146722D01*
X373556Y3145389D01*
X373156Y3144455D01*
X372656Y3143655D01*
X372056Y3143122D01*
X371256Y3142722D01*
X369256D01*
G01X376956D02*
X379456Y3150722D01*
X381956Y3142722D01*
G01X381056Y3145522D02*
X377856D01*
G01X385156Y3142722D02*
Y3150722D01*
X389756Y3142722D01*
Y3150722D01*
G01X397656Y3150055D02*
X397056Y3150455D01*
X396356Y3150722D01*
X395556D01*
X394656Y3150322D01*
X393956Y3149655D01*
X393456Y3148855D01*
X393056Y3147522D01*
X392956Y3146322D01*
X393156Y3145122D01*
X393456Y3144322D01*
X394056Y3143522D01*
X394756Y3142989D01*
X395456Y3142722D01*
X396156D01*
X396856Y3142989D01*
X397456Y3143389D01*
X397956Y3143922D01*
G01X405456Y3142722D02*
X401456D01*
Y3150722D01*
X405456D01*
G01X403856Y3146855D02*
X401456D01*
G01X420256Y3146989D02*
X420656Y3147389D01*
X420956Y3148055D01*
X421156Y3148989D01*
X420956Y3149789D01*
X420556Y3150322D01*
X419856Y3150722D01*
X417156D01*
Y3142722D01*
X420456D01*
X421156Y3143255D01*
X421556Y3144055D01*
X421756Y3144989D01*
X421556Y3145922D01*
X420956Y3146722D01*
X420256Y3146989D01*
X417156D01*
G01X427456Y3142722D02*
X426656Y3142855D01*
X425956Y3143389D01*
X425356Y3144189D01*
X424956Y3145122D01*
X424756Y3146189D01*
Y3147255D01*
X424956Y3148322D01*
X425356Y3149255D01*
X425956Y3150055D01*
X426656Y3150589D01*
X427456Y3150722D01*
X428256Y3150589D01*
X428956Y3150055D01*
X429556Y3149255D01*
X429956Y3148322D01*
X430156Y3147255D01*
Y3146189D01*
X429956Y3145122D01*
X429556Y3144189D01*
X428956Y3143389D01*
X428256Y3142855D01*
X427456Y3142722D01*
G01X432956D02*
X435456Y3150722D01*
X437956Y3142722D01*
G01X437056Y3145522D02*
X433856D01*
G01X441456Y3142722D02*
Y3150722D01*
X443956D01*
X444756Y3150322D01*
X445256Y3149789D01*
X445456Y3148722D01*
X445256Y3147655D01*
X444656Y3146989D01*
X443956Y3146589D01*
X441456D01*
G01X443956D02*
X445456Y3142722D01*
G01X449256D02*
Y3150722D01*
X451256D01*
X452056Y3150322D01*
X452656Y3149789D01*
X453156Y3148989D01*
X453556Y3148055D01*
X453656Y3146722D01*
X453556Y3145389D01*
X453156Y3144455D01*
X452656Y3143655D01*
X452056Y3143122D01*
X451256Y3142722D01*
X449256D01*
G01X459456Y3142455D02*
X459256Y3142589D01*
Y3142855D01*
X459456Y3142989D01*
X459656Y3142855D01*
Y3142589D01*
X459456Y3142455D01*
G01X473356Y3143788D02*
X474156Y3143122D01*
X475056Y3142722D01*
X475856D01*
X476656Y3143122D01*
X477256Y3143788D01*
X477556Y3144722D01*
X477356Y3145655D01*
X476856Y3146455D01*
X475956Y3146989D01*
X474756Y3147255D01*
X474056Y3147789D01*
X473756Y3148722D01*
X473956Y3149655D01*
X474456Y3150322D01*
X475156Y3150722D01*
X475856D01*
X476556Y3150455D01*
X477156Y3149789D01*
G01X485456Y3142722D02*
X481456D01*
Y3150722D01*
X485456D01*
G01X483856Y3146855D02*
X481456D01*
G01X493456Y3142722D02*
X489456D01*
Y3150722D01*
X493456D01*
G01X491856Y3146855D02*
X489456D01*
G01X505456Y3150722D02*
Y3142722D01*
X509456D01*
G01X512956D02*
X515456Y3150722D01*
X517956Y3142722D01*
G01X517056Y3145522D02*
X513856D01*
G01X523456Y3142722D02*
Y3146322D01*
X521456Y3150722D01*
G01X525456D02*
X523456Y3146322D01*
G01X533456Y3142722D02*
X529456D01*
Y3150722D01*
X533456D01*
G01X531856Y3146855D02*
X529456D01*
G01X537456Y3142722D02*
Y3150722D01*
X539956D01*
X540756Y3150322D01*
X541256Y3149789D01*
X541456Y3148722D01*
X541256Y3147655D01*
X540656Y3146989D01*
X539956Y3146589D01*
X537456D01*
G01X539956D02*
X541456Y3142722D01*
G01X553356Y3143788D02*
X554156Y3143122D01*
X555056Y3142722D01*
X555856D01*
X556656Y3143122D01*
X557256Y3143788D01*
X557556Y3144722D01*
X557356Y3145655D01*
X556856Y3146455D01*
X555956Y3146989D01*
X554756Y3147255D01*
X554056Y3147789D01*
X553756Y3148722D01*
X553956Y3149655D01*
X554456Y3150322D01*
X555156Y3150722D01*
X555856D01*
X556556Y3150455D01*
X557156Y3149789D01*
G01X563456Y3150722D02*
Y3142722D01*
G01X561156Y3150722D02*
X565756D01*
G01X568956Y3142722D02*
X571456Y3150722D01*
X573956Y3142722D01*
G01X573056Y3145522D02*
X569856D01*
G01X581656Y3150055D02*
X581056Y3150455D01*
X580356Y3150722D01*
X579556D01*
X578656Y3150322D01*
X577956Y3149655D01*
X577456Y3148855D01*
X577056Y3147522D01*
X576956Y3146322D01*
X577156Y3145122D01*
X577456Y3144322D01*
X578056Y3143522D01*
X578756Y3142989D01*
X579456Y3142722D01*
X580156D01*
X580856Y3142989D01*
X581456Y3143389D01*
X581956Y3143922D01*
G01X585256Y3142722D02*
Y3150722D01*
G01X589056D02*
X585256Y3145788D01*
G01X589656Y3142722D02*
X586956Y3148055D01*
G01X593256Y3150722D02*
Y3144989D01*
X593656Y3143788D01*
X594456Y3142989D01*
X595456Y3142722D01*
X596456Y3142989D01*
X597256Y3143788D01*
X597656Y3144989D01*
Y3150722D01*
G01X601456Y3142722D02*
Y3150722D01*
X603856D01*
X604656Y3150322D01*
X605256Y3149389D01*
X605456Y3148322D01*
X605256Y3147255D01*
X604756Y3146455D01*
X603856Y3146055D01*
X601456D01*
G01X616956Y3142722D02*
X619456Y3150722D01*
X621956Y3142722D01*
G01X621056Y3145522D02*
X617856D01*
G01X625156Y3142722D02*
Y3150722D01*
X629756Y3142722D01*
Y3150722D01*
G01X633256Y3142722D02*
Y3150722D01*
X635256D01*
X636056Y3150322D01*
X636656Y3149789D01*
X637156Y3148989D01*
X637556Y3148055D01*
X637656Y3146722D01*
X637556Y3145389D01*
X637156Y3144455D01*
X636656Y3143655D01*
X636056Y3143122D01*
X635256Y3142722D01*
X633256D01*
G01X650256Y3150722D02*
X652656D01*
G01X651456D02*
Y3142722D01*
G01X650256D02*
X652656D01*
G01X656856D02*
Y3150722D01*
X659456Y3144055D01*
X662056Y3150722D01*
Y3142722D01*
G01X665456D02*
Y3150722D01*
X667856D01*
X668656Y3150322D01*
X669256Y3149389D01*
X669456Y3148322D01*
X669256Y3147255D01*
X668756Y3146455D01*
X667856Y3146055D01*
X665456D01*
G01X677456Y3142722D02*
X673456D01*
Y3150722D01*
X677456D01*
G01X675856Y3146855D02*
X673456D01*
G01X681256Y3142722D02*
Y3150722D01*
X683256D01*
X684056Y3150322D01*
X684656Y3149789D01*
X685156Y3148989D01*
X685556Y3148055D01*
X685656Y3146722D01*
X685556Y3145389D01*
X685156Y3144455D01*
X684656Y3143655D01*
X684056Y3143122D01*
X683256Y3142722D01*
X681256D01*
G01X688956D02*
X691456Y3150722D01*
X693956Y3142722D01*
G01X693056Y3145522D02*
X689856D01*
G01X697156Y3142722D02*
Y3150722D01*
X701756Y3142722D01*
Y3150722D01*
G01X709656Y3150055D02*
X709056Y3150455D01*
X708356Y3150722D01*
X707556D01*
X706656Y3150322D01*
X705956Y3149655D01*
X705456Y3148855D01*
X705056Y3147522D01*
X704956Y3146322D01*
X705156Y3145122D01*
X705456Y3144322D01*
X706056Y3143522D01*
X706756Y3142989D01*
X707456Y3142722D01*
X708156D01*
X708856Y3142989D01*
X709456Y3143389D01*
X709956Y3143922D01*
G01X717456Y3142722D02*
X713456D01*
Y3150722D01*
X717456D01*
G01X715856Y3146855D02*
X713456D01*
G01X251556Y3172722D02*
Y3180722D01*
X255356D01*
G01X253956Y3176855D02*
X251556D01*
G01X261456Y3172455D02*
X261256Y3172589D01*
Y3172855D01*
X261456Y3172989D01*
X261656Y3172855D01*
Y3172589D01*
X261456Y3172455D01*
G01X267156Y3172722D02*
Y3180722D01*
X271756Y3172722D01*
Y3180722D01*
G01X279456Y3172722D02*
X275456D01*
Y3180722D01*
X279456D01*
G01X277856Y3176855D02*
X275456D01*
G01X287456Y3172722D02*
X283456D01*
Y3180722D01*
X287456D01*
G01X285856Y3176855D02*
X283456D01*
G01X291256Y3172722D02*
Y3180722D01*
X293256D01*
X294056Y3180322D01*
X294656Y3179789D01*
X295156Y3178989D01*
X295556Y3178055D01*
X295656Y3176722D01*
X295556Y3175389D01*
X295156Y3174455D01*
X294656Y3173655D01*
X294056Y3173122D01*
X293256Y3172722D01*
X291256D01*
G01X307456D02*
Y3180722D01*
X309856D01*
X310656Y3180322D01*
X311256Y3179389D01*
X311456Y3178322D01*
X311256Y3177255D01*
X310756Y3176455D01*
X309856Y3176055D01*
X307456D01*
G01X319656Y3180055D02*
X319056Y3180455D01*
X318356Y3180722D01*
X317556D01*
X316656Y3180322D01*
X315956Y3179655D01*
X315456Y3178855D01*
X315056Y3177522D01*
X314956Y3176322D01*
X315156Y3175122D01*
X315456Y3174322D01*
X316056Y3173522D01*
X316756Y3172989D01*
X317456Y3172722D01*
X318156D01*
X318856Y3172989D01*
X319456Y3173389D01*
X319956Y3173922D01*
G01X326256Y3176989D02*
X326656Y3177389D01*
X326956Y3178055D01*
X327156Y3178989D01*
X326956Y3179789D01*
X326556Y3180322D01*
X325856Y3180722D01*
X323156D01*
Y3172722D01*
X326456D01*
X327156Y3173255D01*
X327556Y3174055D01*
X327756Y3174989D01*
X327556Y3175922D01*
X326956Y3176722D01*
X326256Y3176989D01*
X323156D01*
G01X338856Y3172722D02*
Y3180722D01*
X341456Y3174055D01*
X344056Y3180722D01*
Y3172722D01*
G01X346956D02*
X349456Y3180722D01*
X351956Y3172722D01*
G01X351056Y3175522D02*
X347856D01*
G01X355256Y3172722D02*
Y3180722D01*
G01X359056D02*
X355256Y3175788D01*
G01X359656Y3172722D02*
X356956Y3178055D01*
G01X367456Y3172722D02*
X363456D01*
Y3180722D01*
X367456D01*
G01X365856Y3176855D02*
X363456D01*
G01X371456Y3172722D02*
Y3180722D01*
X373956D01*
X374756Y3180322D01*
X375256Y3179789D01*
X375456Y3178722D01*
X375256Y3177655D01*
X374656Y3176989D01*
X373956Y3176589D01*
X371456D01*
G01X373956D02*
X375456Y3172722D01*
G01X387456Y3180722D02*
Y3172722D01*
X391456D01*
G01X397456D02*
X396656Y3172855D01*
X395956Y3173389D01*
X395356Y3174189D01*
X394956Y3175122D01*
X394756Y3176189D01*
Y3177255D01*
X394956Y3178322D01*
X395356Y3179255D01*
X395956Y3180055D01*
X396656Y3180589D01*
X397456Y3180722D01*
X398256Y3180589D01*
X398956Y3180055D01*
X399556Y3179255D01*
X399956Y3178322D01*
X400156Y3177255D01*
Y3176189D01*
X399956Y3175122D01*
X399556Y3174189D01*
X398956Y3173389D01*
X398256Y3172855D01*
X397456Y3172722D01*
G01X406056Y3176722D02*
X408056D01*
Y3174322D01*
X407456Y3173522D01*
X406756Y3172989D01*
X405756Y3172722D01*
X404756Y3172989D01*
X404056Y3173522D01*
X403456Y3174322D01*
X403056Y3175255D01*
X402856Y3176322D01*
Y3177255D01*
X403056Y3178055D01*
X403456Y3178989D01*
X404056Y3179789D01*
X404656Y3180322D01*
X405456Y3180722D01*
X406156D01*
X406956Y3180455D01*
X407556Y3179922D01*
G01X413456Y3172722D02*
X412656Y3172855D01*
X411956Y3173389D01*
X411356Y3174189D01*
X410956Y3175122D01*
X410756Y3176189D01*
Y3177255D01*
X410956Y3178322D01*
X411356Y3179255D01*
X411956Y3180055D01*
X412656Y3180589D01*
X413456Y3180722D01*
X414256Y3180589D01*
X414956Y3180055D01*
X415556Y3179255D01*
X415956Y3178322D01*
X416156Y3177255D01*
Y3176189D01*
X415956Y3175122D01*
X415556Y3174189D01*
X414956Y3173389D01*
X414256Y3172855D01*
X413456Y3172722D01*
G01X426956D02*
X429456Y3180722D01*
X431956Y3172722D01*
G01X431056Y3175522D02*
X427856D01*
G01X435156Y3172722D02*
Y3180722D01*
X439756Y3172722D01*
Y3180722D01*
G01X443256Y3172722D02*
Y3180722D01*
X445256D01*
X446056Y3180322D01*
X446656Y3179789D01*
X447156Y3178989D01*
X447556Y3178055D01*
X447656Y3176722D01*
X447556Y3175389D01*
X447156Y3174455D01*
X446656Y3173655D01*
X446056Y3173122D01*
X445256Y3172722D01*
X443256D01*
G01X459256D02*
Y3180722D01*
X461256D01*
X462056Y3180322D01*
X462656Y3179789D01*
X463156Y3178989D01*
X463556Y3178055D01*
X463656Y3176722D01*
X463556Y3175389D01*
X463156Y3174455D01*
X462656Y3173655D01*
X462056Y3173122D01*
X461256Y3172722D01*
X459256D01*
G01X466956D02*
X469456Y3180722D01*
X471956Y3172722D01*
G01X471056Y3175522D02*
X467856D01*
G01X477456Y3180722D02*
Y3172722D01*
G01X475156Y3180722D02*
X479756D01*
G01X487456Y3172722D02*
X483456D01*
Y3180722D01*
X487456D01*
G01X485856Y3176855D02*
X483456D01*
G01X503656Y3180055D02*
X503056Y3180455D01*
X502356Y3180722D01*
X501556D01*
X500656Y3180322D01*
X499956Y3179655D01*
X499456Y3178855D01*
X499056Y3177522D01*
X498956Y3176322D01*
X499156Y3175122D01*
X499456Y3174322D01*
X500056Y3173522D01*
X500756Y3172989D01*
X501456Y3172722D01*
X502156D01*
X502856Y3172989D01*
X503456Y3173389D01*
X503956Y3173922D01*
G01X509456Y3172722D02*
X508656Y3172855D01*
X507956Y3173389D01*
X507356Y3174189D01*
X506956Y3175122D01*
X506756Y3176189D01*
Y3177255D01*
X506956Y3178322D01*
X507356Y3179255D01*
X507956Y3180055D01*
X508656Y3180589D01*
X509456Y3180722D01*
X510256Y3180589D01*
X510956Y3180055D01*
X511556Y3179255D01*
X511956Y3178322D01*
X512156Y3177255D01*
Y3176189D01*
X511956Y3175122D01*
X511556Y3174189D01*
X510956Y3173389D01*
X510256Y3172855D01*
X509456Y3172722D01*
G01X515256D02*
Y3180722D01*
X517256D01*
X518056Y3180322D01*
X518656Y3179789D01*
X519156Y3178989D01*
X519556Y3178055D01*
X519656Y3176722D01*
X519556Y3175389D01*
X519156Y3174455D01*
X518656Y3173655D01*
X518056Y3173122D01*
X517256Y3172722D01*
X515256D01*
G01X527456D02*
X523456D01*
Y3180722D01*
X527456D01*
G01X525856Y3176855D02*
X523456D01*
G01X540956Y3170055D02*
X539956Y3171389D01*
X539456Y3172722D01*
Y3178055D01*
X539956Y3179389D01*
X540956Y3180722D01*
G01X546456D02*
X547856Y3172722D01*
X549456Y3180722D01*
X551056Y3172722D01*
X552456Y3180722D01*
G01X554456D02*
X555856Y3172722D01*
X557456Y3180722D01*
X559056Y3172722D01*
X560456Y3180722D01*
G01X565456Y3172722D02*
Y3176322D01*
X563456Y3180722D01*
G01X567456D02*
X565456Y3176322D01*
G01X573456Y3172722D02*
Y3176322D01*
X571456Y3180722D01*
G01X575456D02*
X573456Y3176322D01*
G01X581956Y3170055D02*
X582956Y3171389D01*
X583456Y3172722D01*
Y3178055D01*
X582956Y3179389D01*
X581956Y3180722D01*
G01X597456Y3172722D02*
X596856Y3172855D01*
X596256Y3173389D01*
X595856Y3174322D01*
X595656Y3175389D01*
X595856Y3176455D01*
X596256Y3177389D01*
X596856Y3177922D01*
X597456Y3178055D01*
X598056Y3177922D01*
X598656Y3177389D01*
X599056Y3176455D01*
X599156Y3175389D01*
X599056Y3174322D01*
X598656Y3173389D01*
X598056Y3172855D01*
X597456Y3172722D01*
G01X603756D02*
Y3178055D01*
G01Y3176722D02*
X604156Y3177389D01*
X604756Y3177922D01*
X605556Y3178055D01*
X606256Y3177922D01*
X606856Y3177389D01*
X607156Y3176455D01*
Y3172722D01*
G01X619356Y3173788D02*
X620156Y3173122D01*
X621056Y3172722D01*
X621856D01*
X622656Y3173122D01*
X623256Y3173788D01*
X623556Y3174722D01*
X623356Y3175655D01*
X622856Y3176455D01*
X621956Y3176989D01*
X620756Y3177255D01*
X620056Y3177789D01*
X619756Y3178722D01*
X619956Y3179655D01*
X620456Y3180322D01*
X621156Y3180722D01*
X621856D01*
X622556Y3180455D01*
X623156Y3179789D01*
G01X628256Y3180722D02*
X630656D01*
G01X629456D02*
Y3172722D01*
G01X628256D02*
X630656D01*
G01X635456Y3180722D02*
Y3172722D01*
X639456D01*
G01X643256D02*
Y3180722D01*
G01X647056D02*
X643256Y3175788D01*
G01X647656Y3172722D02*
X644956Y3178055D01*
G01X651356Y3173788D02*
X652156Y3173122D01*
X653056Y3172722D01*
X653856D01*
X654656Y3173122D01*
X655256Y3173788D01*
X655556Y3174722D01*
X655356Y3175655D01*
X654856Y3176455D01*
X653956Y3176989D01*
X652756Y3177255D01*
X652056Y3177789D01*
X651756Y3178722D01*
X651956Y3179655D01*
X652456Y3180322D01*
X653156Y3180722D01*
X653856D01*
X654556Y3180455D01*
X655156Y3179789D01*
G01X663656Y3180055D02*
X663056Y3180455D01*
X662356Y3180722D01*
X661556D01*
X660656Y3180322D01*
X659956Y3179655D01*
X659456Y3178855D01*
X659056Y3177522D01*
X658956Y3176322D01*
X659156Y3175122D01*
X659456Y3174322D01*
X660056Y3173522D01*
X660756Y3172989D01*
X661456Y3172722D01*
X662156D01*
X662856Y3172989D01*
X663456Y3173389D01*
X663956Y3173922D01*
G01X667456Y3172722D02*
Y3180722D01*
X669956D01*
X670756Y3180322D01*
X671256Y3179789D01*
X671456Y3178722D01*
X671256Y3177655D01*
X670656Y3176989D01*
X669956Y3176589D01*
X667456D01*
G01X669956D02*
X671456Y3172722D01*
G01X679456D02*
X675456D01*
Y3180722D01*
X679456D01*
G01X677856Y3176855D02*
X675456D01*
G01X687456Y3172722D02*
X683456D01*
Y3180722D01*
X687456D01*
G01X685856Y3176855D02*
X683456D01*
G01X691156Y3172722D02*
Y3180722D01*
X695756Y3172722D01*
Y3180722D01*
G01X709456D02*
Y3172722D01*
G01X707156Y3180722D02*
X711756D01*
G01X717456Y3172722D02*
X716656Y3172855D01*
X715956Y3173389D01*
X715356Y3174189D01*
X714956Y3175122D01*
X714756Y3176189D01*
Y3177255D01*
X714956Y3178322D01*
X715356Y3179255D01*
X715956Y3180055D01*
X716656Y3180589D01*
X717456Y3180722D01*
X718256Y3180589D01*
X718956Y3180055D01*
X719556Y3179255D01*
X719956Y3178322D01*
X720156Y3177255D01*
Y3176189D01*
X719956Y3175122D01*
X719556Y3174189D01*
X718956Y3173389D01*
X718256Y3172855D01*
X717456Y3172722D01*
G01X723456D02*
Y3180722D01*
X725856D01*
X726656Y3180322D01*
X727256Y3179389D01*
X727456Y3178322D01*
X727256Y3177255D01*
X726756Y3176455D01*
X725856Y3176055D01*
X723456D01*
G01X739356Y3173788D02*
X740156Y3173122D01*
X741056Y3172722D01*
X741856D01*
X742656Y3173122D01*
X743256Y3173788D01*
X743556Y3174722D01*
X743356Y3175655D01*
X742856Y3176455D01*
X741956Y3176989D01*
X740756Y3177255D01*
X740056Y3177789D01*
X739756Y3178722D01*
X739956Y3179655D01*
X740456Y3180322D01*
X741156Y3180722D01*
X741856D01*
X742556Y3180455D01*
X743156Y3179789D01*
G01X748256Y3180722D02*
X750656D01*
G01X749456D02*
Y3172722D01*
G01X748256D02*
X750656D01*
G01X755256D02*
Y3180722D01*
X757256D01*
X758056Y3180322D01*
X758656Y3179789D01*
X759156Y3178989D01*
X759556Y3178055D01*
X759656Y3176722D01*
X759556Y3175389D01*
X759156Y3174455D01*
X758656Y3173655D01*
X758056Y3173122D01*
X757256Y3172722D01*
X755256D01*
G01X767456D02*
X763456D01*
Y3180722D01*
X767456D01*
G01X765856Y3176855D02*
X763456D01*
G01X784456Y3170055D02*
X779456Y3178055D01*
Y3179389D01*
X780456Y3180722D01*
X781456D01*
X782456Y3179389D01*
Y3178055D01*
X781456Y3176722D01*
X779456Y3175389D01*
X778456Y3174055D01*
Y3171389D01*
X779456Y3170055D01*
X782456D01*
X784456Y3172722D01*
G01X798256Y3176989D02*
X798656Y3177389D01*
X798956Y3178055D01*
X799156Y3178989D01*
X798956Y3179789D01*
X798556Y3180322D01*
X797856Y3180722D01*
X795156D01*
Y3172722D01*
X798456D01*
X799156Y3173255D01*
X799556Y3174055D01*
X799756Y3174989D01*
X799556Y3175922D01*
X798956Y3176722D01*
X798256Y3176989D01*
X795156D01*
G01X803456Y3172722D02*
Y3180722D01*
X805956D01*
X806756Y3180322D01*
X807256Y3179789D01*
X807456Y3178722D01*
X807256Y3177655D01*
X806656Y3176989D01*
X805956Y3176589D01*
X803456D01*
G01X805956D02*
X807456Y3172722D01*
G01X815456D02*
X811456D01*
Y3180722D01*
X815456D01*
G01X813856Y3176855D02*
X811456D01*
G01X818956Y3172722D02*
X821456Y3180722D01*
X823956Y3172722D01*
G01X823056Y3175522D02*
X819856D01*
G01X827256Y3172722D02*
Y3180722D01*
G01X831056D02*
X827256Y3175788D01*
G01X831656Y3172722D02*
X828956Y3178055D01*
G01X834956Y3172722D02*
X837456Y3180722D01*
X839956Y3172722D01*
G01X839056Y3175522D02*
X835856D01*
G01X842456Y3180722D02*
X843856Y3172722D01*
X845456Y3180722D01*
X847056Y3172722D01*
X848456Y3180722D01*
G01X850956Y3172722D02*
X853456Y3180722D01*
X855956Y3172722D01*
G01X855056Y3175522D02*
X851856D01*
G01X861456Y3172722D02*
Y3176322D01*
X859456Y3180722D01*
G01X863456D02*
X861456Y3176322D01*
G01X254056Y3161722D02*
X256056D01*
Y3159322D01*
X255456Y3158522D01*
X254756Y3157989D01*
X253756Y3157722D01*
X252756Y3157989D01*
X252056Y3158522D01*
X251456Y3159322D01*
X251056Y3160255D01*
X250856Y3161322D01*
Y3162255D01*
X251056Y3163055D01*
X251456Y3163989D01*
X252056Y3164789D01*
X252656Y3165322D01*
X253456Y3165722D01*
X254156D01*
X254956Y3165455D01*
X255556Y3164922D01*
G01X261456Y3157455D02*
X261256Y3157589D01*
Y3157855D01*
X261456Y3157989D01*
X261656Y3157855D01*
Y3157589D01*
X261456Y3157455D01*
G01X267156Y3157722D02*
Y3165722D01*
X271756Y3157722D01*
Y3165722D01*
G01X279456Y3157722D02*
X275456D01*
Y3165722D01*
X279456D01*
G01X277856Y3161855D02*
X275456D01*
G01X287456Y3157722D02*
X283456D01*
Y3165722D01*
X287456D01*
G01X285856Y3161855D02*
X283456D01*
G01X291256Y3157722D02*
Y3165722D01*
X293256D01*
X294056Y3165322D01*
X294656Y3164789D01*
X295156Y3163989D01*
X295556Y3163055D01*
X295656Y3161722D01*
X295556Y3160389D01*
X295156Y3159455D01*
X294656Y3158655D01*
X294056Y3158122D01*
X293256Y3157722D01*
X291256D01*
G01X307256Y3165722D02*
Y3159989D01*
X307656Y3158788D01*
X308456Y3157989D01*
X309456Y3157722D01*
X310456Y3157989D01*
X311256Y3158788D01*
X311656Y3159989D01*
Y3165722D01*
G01X315456D02*
Y3157722D01*
X319456D01*
G01X330856D02*
Y3165722D01*
X333456Y3159055D01*
X336056Y3165722D01*
Y3157722D01*
G01X338956D02*
X341456Y3165722D01*
X343956Y3157722D01*
G01X343056Y3160522D02*
X339856D01*
G01X347456Y3157722D02*
Y3165722D01*
X349956D01*
X350756Y3165322D01*
X351256Y3164789D01*
X351456Y3163722D01*
X351256Y3162655D01*
X350656Y3161989D01*
X349956Y3161589D01*
X347456D01*
G01X349956D02*
X351456Y3157722D01*
G01X355256D02*
Y3165722D01*
G01X359056D02*
X355256Y3160788D01*
G01X359656Y3157722D02*
X356956Y3163055D01*
G01X370956Y3157722D02*
X373456Y3165722D01*
X375956Y3157722D01*
G01X375056Y3160522D02*
X371856D01*
G01X379156Y3157722D02*
Y3165722D01*
X383756Y3157722D01*
Y3165722D01*
G01X387256Y3157722D02*
Y3165722D01*
X389256D01*
X390056Y3165322D01*
X390656Y3164789D01*
X391156Y3163989D01*
X391556Y3163055D01*
X391656Y3161722D01*
X391556Y3160389D01*
X391156Y3159455D01*
X390656Y3158655D01*
X390056Y3158122D01*
X389256Y3157722D01*
X387256D01*
G01X403256Y3165722D02*
Y3159989D01*
X403656Y3158788D01*
X404456Y3157989D01*
X405456Y3157722D01*
X406456Y3157989D01*
X407256Y3158788D01*
X407656Y3159989D01*
Y3165722D01*
G01X411456D02*
Y3157722D01*
X415456D01*
G01X427556D02*
Y3165722D01*
X431356D01*
G01X429956Y3161855D02*
X427556D01*
G01X436256Y3165722D02*
X438656D01*
G01X437456D02*
Y3157722D01*
G01X436256D02*
X438656D01*
G01X443456Y3165722D02*
Y3157722D01*
X447456D01*
G01X455456D02*
X451456D01*
Y3165722D01*
X455456D01*
G01X453856Y3161855D02*
X451456D01*
G01X467156Y3157722D02*
Y3165722D01*
X471756Y3157722D01*
Y3165722D01*
G01X475256D02*
Y3159989D01*
X475656Y3158788D01*
X476456Y3157989D01*
X477456Y3157722D01*
X478456Y3157989D01*
X479256Y3158788D01*
X479656Y3159989D01*
Y3165722D01*
G01X482856Y3157722D02*
Y3165722D01*
X485456Y3159055D01*
X488056Y3165722D01*
Y3157722D01*
G01X494256Y3161989D02*
X494656Y3162389D01*
X494956Y3163055D01*
X495156Y3163989D01*
X494956Y3164789D01*
X494556Y3165322D01*
X493856Y3165722D01*
X491156D01*
Y3157722D01*
X494456D01*
X495156Y3158255D01*
X495556Y3159055D01*
X495756Y3159989D01*
X495556Y3160922D01*
X494956Y3161722D01*
X494256Y3161989D01*
X491156D01*
G01X503456Y3157722D02*
X499456D01*
Y3165722D01*
X503456D01*
G01X501856Y3161855D02*
X499456D01*
G01X507456Y3157722D02*
Y3165722D01*
X509956D01*
X510756Y3165322D01*
X511256Y3164789D01*
X511456Y3163722D01*
X511256Y3162655D01*
X510656Y3161989D01*
X509956Y3161589D01*
X507456D01*
G01X509956D02*
X511456Y3157722D01*
G01X525456D02*
X524856Y3157855D01*
X524256Y3158389D01*
X523856Y3159322D01*
X523656Y3160389D01*
X523856Y3161455D01*
X524256Y3162389D01*
X524856Y3162922D01*
X525456Y3163055D01*
X526056Y3162922D01*
X526656Y3162389D01*
X527056Y3161455D01*
X527156Y3160389D01*
X527056Y3159322D01*
X526656Y3158389D01*
X526056Y3157855D01*
X525456Y3157722D01*
G01X531756D02*
Y3163055D01*
G01Y3161722D02*
X532156Y3162389D01*
X532756Y3162922D01*
X533556Y3163055D01*
X534256Y3162922D01*
X534856Y3162389D01*
X535156Y3161455D01*
Y3157722D01*
G01X547356Y3158788D02*
X548156Y3158122D01*
X549056Y3157722D01*
X549856D01*
X550656Y3158122D01*
X551256Y3158788D01*
X551556Y3159722D01*
X551356Y3160655D01*
X550856Y3161455D01*
X549956Y3161989D01*
X548756Y3162255D01*
X548056Y3162789D01*
X547756Y3163722D01*
X547956Y3164655D01*
X548456Y3165322D01*
X549156Y3165722D01*
X549856D01*
X550556Y3165455D01*
X551156Y3164789D01*
G01X556256Y3165722D02*
X558656D01*
G01X557456D02*
Y3157722D01*
G01X556256D02*
X558656D01*
G01X563456Y3165722D02*
Y3157722D01*
X567456D01*
G01X571256D02*
Y3165722D01*
G01X575056D02*
X571256Y3160788D01*
G01X575656Y3157722D02*
X572956Y3163055D01*
G01X579356Y3158788D02*
X580156Y3158122D01*
X581056Y3157722D01*
X581856D01*
X582656Y3158122D01*
X583256Y3158788D01*
X583556Y3159722D01*
X583356Y3160655D01*
X582856Y3161455D01*
X581956Y3161989D01*
X580756Y3162255D01*
X580056Y3162789D01*
X579756Y3163722D01*
X579956Y3164655D01*
X580456Y3165322D01*
X581156Y3165722D01*
X581856D01*
X582556Y3165455D01*
X583156Y3164789D01*
G01X591656Y3165055D02*
X591056Y3165455D01*
X590356Y3165722D01*
X589556D01*
X588656Y3165322D01*
X587956Y3164655D01*
X587456Y3163855D01*
X587056Y3162522D01*
X586956Y3161322D01*
X587156Y3160122D01*
X587456Y3159322D01*
X588056Y3158522D01*
X588756Y3157989D01*
X589456Y3157722D01*
X590156D01*
X590856Y3157989D01*
X591456Y3158389D01*
X591956Y3158922D01*
G01X595456Y3157722D02*
Y3165722D01*
X597956D01*
X598756Y3165322D01*
X599256Y3164789D01*
X599456Y3163722D01*
X599256Y3162655D01*
X598656Y3161989D01*
X597956Y3161589D01*
X595456D01*
G01X597956D02*
X599456Y3157722D01*
G01X607456D02*
X603456D01*
Y3165722D01*
X607456D01*
G01X605856Y3161855D02*
X603456D01*
G01X615456Y3157722D02*
X611456D01*
Y3165722D01*
X615456D01*
G01X613856Y3161855D02*
X611456D01*
G01X619156Y3157722D02*
Y3165722D01*
X623756Y3157722D01*
Y3165722D01*
G01X637456D02*
Y3157722D01*
G01X635156Y3165722D02*
X639756D01*
G01X645456Y3157722D02*
X644656Y3157855D01*
X643956Y3158389D01*
X643356Y3159189D01*
X642956Y3160122D01*
X642756Y3161189D01*
Y3162255D01*
X642956Y3163322D01*
X643356Y3164255D01*
X643956Y3165055D01*
X644656Y3165589D01*
X645456Y3165722D01*
X646256Y3165589D01*
X646956Y3165055D01*
X647556Y3164255D01*
X647956Y3163322D01*
X648156Y3162255D01*
Y3161189D01*
X647956Y3160122D01*
X647556Y3159189D01*
X646956Y3158389D01*
X646256Y3157855D01*
X645456Y3157722D01*
G01X651456D02*
Y3165722D01*
X653856D01*
X654656Y3165322D01*
X655256Y3164389D01*
X655456Y3163322D01*
X655256Y3162255D01*
X654756Y3161455D01*
X653856Y3161055D01*
X651456D01*
G01X667356Y3158788D02*
X668156Y3158122D01*
X669056Y3157722D01*
X669856D01*
X670656Y3158122D01*
X671256Y3158788D01*
X671556Y3159722D01*
X671356Y3160655D01*
X670856Y3161455D01*
X669956Y3161989D01*
X668756Y3162255D01*
X668056Y3162789D01*
X667756Y3163722D01*
X667956Y3164655D01*
X668456Y3165322D01*
X669156Y3165722D01*
X669856D01*
X670556Y3165455D01*
X671156Y3164789D01*
G01X676256Y3165722D02*
X678656D01*
G01X677456D02*
Y3157722D01*
G01X676256D02*
X678656D01*
G01X683256D02*
Y3165722D01*
X685256D01*
X686056Y3165322D01*
X686656Y3164789D01*
X687156Y3163989D01*
X687556Y3163055D01*
X687656Y3161722D01*
X687556Y3160389D01*
X687156Y3159455D01*
X686656Y3158655D01*
X686056Y3158122D01*
X685256Y3157722D01*
X683256D01*
G01X695456D02*
X691456D01*
Y3165722D01*
X695456D01*
G01X693856Y3161855D02*
X691456D01*
G01X255456Y3187722D02*
X251456D01*
Y3195722D01*
X255456D01*
G01X253856Y3191855D02*
X251456D01*
G01X261456Y3187455D02*
X261256Y3187589D01*
Y3187855D01*
X261456Y3187989D01*
X261656Y3187855D01*
Y3187589D01*
X261456Y3187455D01*
G01X267456Y3187722D02*
Y3195722D01*
X269856D01*
X270656Y3195322D01*
X271256Y3194389D01*
X271456Y3193322D01*
X271256Y3192255D01*
X270756Y3191455D01*
X269856Y3191055D01*
X267456D01*
G01X275456Y3187722D02*
Y3195722D01*
X277956D01*
X278756Y3195322D01*
X279256Y3194789D01*
X279456Y3193722D01*
X279256Y3192655D01*
X278656Y3191989D01*
X277956Y3191589D01*
X275456D01*
G01X277956D02*
X279456Y3187722D01*
G01X285456D02*
X284656Y3187855D01*
X283956Y3188389D01*
X283356Y3189189D01*
X282956Y3190122D01*
X282756Y3191189D01*
Y3192255D01*
X282956Y3193322D01*
X283356Y3194255D01*
X283956Y3195055D01*
X284656Y3195589D01*
X285456Y3195722D01*
X286256Y3195589D01*
X286956Y3195055D01*
X287556Y3194255D01*
X287956Y3193322D01*
X288156Y3192255D01*
Y3191189D01*
X287956Y3190122D01*
X287556Y3189189D01*
X286956Y3188389D01*
X286256Y3187855D01*
X285456Y3187722D01*
G01X290956Y3195722D02*
X293456Y3187722D01*
X295956Y3195722D01*
G01X300256D02*
X302656D01*
G01X301456D02*
Y3187722D01*
G01X300256D02*
X302656D01*
G01X307256D02*
Y3195722D01*
X309256D01*
X310056Y3195322D01*
X310656Y3194789D01*
X311156Y3193989D01*
X311556Y3193055D01*
X311656Y3191722D01*
X311556Y3190389D01*
X311156Y3189455D01*
X310656Y3188655D01*
X310056Y3188122D01*
X309256Y3187722D01*
X307256D01*
G01X319456D02*
X315456D01*
Y3195722D01*
X319456D01*
G01X317856Y3191855D02*
X315456D01*
G01X331456Y3187722D02*
Y3195722D01*
X333856D01*
X334656Y3195322D01*
X335256Y3194389D01*
X335456Y3193322D01*
X335256Y3192255D01*
X334756Y3191455D01*
X333856Y3191055D01*
X331456D01*
G01X343656Y3195055D02*
X343056Y3195455D01*
X342356Y3195722D01*
X341556D01*
X340656Y3195322D01*
X339956Y3194655D01*
X339456Y3193855D01*
X339056Y3192522D01*
X338956Y3191322D01*
X339156Y3190122D01*
X339456Y3189322D01*
X340056Y3188522D01*
X340756Y3187989D01*
X341456Y3187722D01*
X342156D01*
X342856Y3187989D01*
X343456Y3188389D01*
X343956Y3188922D01*
G01X350256Y3191989D02*
X350656Y3192389D01*
X350956Y3193055D01*
X351156Y3193989D01*
X350956Y3194789D01*
X350556Y3195322D01*
X349856Y3195722D01*
X347156D01*
Y3187722D01*
X350456D01*
X351156Y3188255D01*
X351556Y3189055D01*
X351756Y3189989D01*
X351556Y3190922D01*
X350956Y3191722D01*
X350256Y3191989D01*
X347156D01*
G01X363556Y3187722D02*
Y3195722D01*
X367356D01*
G01X365956Y3191855D02*
X363556D01*
G01X372256Y3195722D02*
X374656D01*
G01X373456D02*
Y3187722D01*
G01X372256D02*
X374656D01*
G01X379456Y3195722D02*
Y3187722D01*
X383456D01*
G01X386856D02*
Y3195722D01*
X389456Y3189055D01*
X392056Y3195722D01*
Y3187722D01*
G01X251256Y3202722D02*
Y3210722D01*
X253256D01*
X254056Y3210322D01*
X254656Y3209789D01*
X255156Y3208989D01*
X255556Y3208055D01*
X255656Y3206722D01*
X255556Y3205389D01*
X255156Y3204455D01*
X254656Y3203655D01*
X254056Y3203122D01*
X253256Y3202722D01*
X251256D01*
G01X261456Y3202455D02*
X261256Y3202589D01*
Y3202855D01*
X261456Y3202989D01*
X261656Y3202855D01*
Y3202589D01*
X261456Y3202455D01*
G01X267456Y3202722D02*
Y3210722D01*
X269856D01*
X270656Y3210322D01*
X271256Y3209389D01*
X271456Y3208322D01*
X271256Y3207255D01*
X270756Y3206455D01*
X269856Y3206055D01*
X267456D01*
G01X275456Y3202722D02*
Y3210722D01*
X277956D01*
X278756Y3210322D01*
X279256Y3209789D01*
X279456Y3208722D01*
X279256Y3207655D01*
X278656Y3206989D01*
X277956Y3206589D01*
X275456D01*
G01X277956D02*
X279456Y3202722D01*
G01X285456D02*
X284656Y3202855D01*
X283956Y3203389D01*
X283356Y3204189D01*
X282956Y3205122D01*
X282756Y3206189D01*
Y3207255D01*
X282956Y3208322D01*
X283356Y3209255D01*
X283956Y3210055D01*
X284656Y3210589D01*
X285456Y3210722D01*
X286256Y3210589D01*
X286956Y3210055D01*
X287556Y3209255D01*
X287956Y3208322D01*
X288156Y3207255D01*
Y3206189D01*
X287956Y3205122D01*
X287556Y3204189D01*
X286956Y3203389D01*
X286256Y3202855D01*
X285456Y3202722D01*
G01X290956Y3210722D02*
X293456Y3202722D01*
X295956Y3210722D01*
G01X300256D02*
X302656D01*
G01X301456D02*
Y3202722D01*
G01X300256D02*
X302656D01*
G01X307256D02*
Y3210722D01*
X309256D01*
X310056Y3210322D01*
X310656Y3209789D01*
X311156Y3208989D01*
X311556Y3208055D01*
X311656Y3206722D01*
X311556Y3205389D01*
X311156Y3204455D01*
X310656Y3203655D01*
X310056Y3203122D01*
X309256Y3202722D01*
X307256D01*
G01X319456D02*
X315456D01*
Y3210722D01*
X319456D01*
G01X317856Y3206855D02*
X315456D01*
G01X332256Y3210722D02*
X334656D01*
G01X333456D02*
Y3202722D01*
G01X332256D02*
X334656D01*
G01X338856D02*
Y3210722D01*
X341456Y3204055D01*
X344056Y3210722D01*
Y3202722D01*
G01X347456D02*
Y3210722D01*
X349856D01*
X350656Y3210322D01*
X351256Y3209389D01*
X351456Y3208322D01*
X351256Y3207255D01*
X350756Y3206455D01*
X349856Y3206055D01*
X347456D01*
G01X359456Y3202722D02*
X355456D01*
Y3210722D01*
X359456D01*
G01X357856Y3206855D02*
X355456D01*
G01X363256Y3202722D02*
Y3210722D01*
X365256D01*
X366056Y3210322D01*
X366656Y3209789D01*
X367156Y3208989D01*
X367556Y3208055D01*
X367656Y3206722D01*
X367556Y3205389D01*
X367156Y3204455D01*
X366656Y3203655D01*
X366056Y3203122D01*
X365256Y3202722D01*
X363256D01*
G01X370956D02*
X373456Y3210722D01*
X375956Y3202722D01*
G01X375056Y3205522D02*
X371856D01*
G01X379156Y3202722D02*
Y3210722D01*
X383756Y3202722D01*
Y3210722D01*
G01X391656Y3210055D02*
X391056Y3210455D01*
X390356Y3210722D01*
X389556D01*
X388656Y3210322D01*
X387956Y3209655D01*
X387456Y3208855D01*
X387056Y3207522D01*
X386956Y3206322D01*
X387156Y3205122D01*
X387456Y3204322D01*
X388056Y3203522D01*
X388756Y3202989D01*
X389456Y3202722D01*
X390156D01*
X390856Y3202989D01*
X391456Y3203389D01*
X391956Y3203922D01*
G01X399456Y3202722D02*
X395456D01*
Y3210722D01*
X399456D01*
G01X397856Y3206855D02*
X395456D01*
G01X415656Y3210055D02*
X415056Y3210455D01*
X414356Y3210722D01*
X413556D01*
X412656Y3210322D01*
X411956Y3209655D01*
X411456Y3208855D01*
X411056Y3207522D01*
X410956Y3206322D01*
X411156Y3205122D01*
X411456Y3204322D01*
X412056Y3203522D01*
X412756Y3202989D01*
X413456Y3202722D01*
X414156D01*
X414856Y3202989D01*
X415456Y3203389D01*
X415956Y3203922D01*
G01X421456Y3202722D02*
X420656Y3202855D01*
X419956Y3203389D01*
X419356Y3204189D01*
X418956Y3205122D01*
X418756Y3206189D01*
Y3207255D01*
X418956Y3208322D01*
X419356Y3209255D01*
X419956Y3210055D01*
X420656Y3210589D01*
X421456Y3210722D01*
X422256Y3210589D01*
X422956Y3210055D01*
X423556Y3209255D01*
X423956Y3208322D01*
X424156Y3207255D01*
Y3206189D01*
X423956Y3205122D01*
X423556Y3204189D01*
X422956Y3203389D01*
X422256Y3202855D01*
X421456Y3202722D01*
G01X427256Y3210722D02*
Y3204989D01*
X427656Y3203788D01*
X428456Y3202989D01*
X429456Y3202722D01*
X430456Y3202989D01*
X431256Y3203788D01*
X431656Y3204989D01*
Y3210722D01*
G01X435456Y3202722D02*
Y3210722D01*
X437856D01*
X438656Y3210322D01*
X439256Y3209389D01*
X439456Y3208322D01*
X439256Y3207255D01*
X438756Y3206455D01*
X437856Y3206055D01*
X435456D01*
G01X445456Y3202722D02*
X444656Y3202855D01*
X443956Y3203389D01*
X443356Y3204189D01*
X442956Y3205122D01*
X442756Y3206189D01*
Y3207255D01*
X442956Y3208322D01*
X443356Y3209255D01*
X443956Y3210055D01*
X444656Y3210589D01*
X445456Y3210722D01*
X446256Y3210589D01*
X446956Y3210055D01*
X447556Y3209255D01*
X447956Y3208322D01*
X448156Y3207255D01*
Y3206189D01*
X447956Y3205122D01*
X447556Y3204189D01*
X446956Y3203389D01*
X446256Y3202855D01*
X445456Y3202722D01*
G01X451156D02*
Y3210722D01*
X455756Y3202722D01*
Y3210722D01*
G01X466956Y3202722D02*
X469456Y3210722D01*
X471956Y3202722D01*
G01X471056Y3205522D02*
X467856D01*
G01X475156Y3202722D02*
Y3210722D01*
X479756Y3202722D01*
Y3210722D01*
G01X483256Y3202722D02*
Y3210722D01*
X485256D01*
X486056Y3210322D01*
X486656Y3209789D01*
X487156Y3208989D01*
X487556Y3208055D01*
X487656Y3206722D01*
X487556Y3205389D01*
X487156Y3204455D01*
X486656Y3203655D01*
X486056Y3203122D01*
X485256Y3202722D01*
X483256D01*
G01X498856D02*
Y3210722D01*
X501456Y3204055D01*
X504056Y3210722D01*
Y3202722D01*
G01X511456D02*
X507456D01*
Y3210722D01*
X511456D01*
G01X509856Y3206855D02*
X507456D01*
G01X514956Y3202722D02*
X517456Y3210722D01*
X519956Y3202722D01*
G01X519056Y3205522D02*
X515856D01*
G01X523356Y3203788D02*
X524156Y3203122D01*
X525056Y3202722D01*
X525856D01*
X526656Y3203122D01*
X527256Y3203788D01*
X527556Y3204722D01*
X527356Y3205655D01*
X526856Y3206455D01*
X525956Y3206989D01*
X524756Y3207255D01*
X524056Y3207789D01*
X523756Y3208722D01*
X523956Y3209655D01*
X524456Y3210322D01*
X525156Y3210722D01*
X525856D01*
X526556Y3210455D01*
X527156Y3209789D01*
G01X531256Y3210722D02*
Y3204989D01*
X531656Y3203788D01*
X532456Y3202989D01*
X533456Y3202722D01*
X534456Y3202989D01*
X535256Y3203788D01*
X535656Y3204989D01*
Y3210722D01*
G01X539456Y3202722D02*
Y3210722D01*
X541956D01*
X542756Y3210322D01*
X543256Y3209789D01*
X543456Y3208722D01*
X543256Y3207655D01*
X542656Y3206989D01*
X541956Y3206589D01*
X539456D01*
G01X541956D02*
X543456Y3202722D01*
G01X551456D02*
X547456D01*
Y3210722D01*
X551456D01*
G01X549856Y3206855D02*
X547456D01*
G01X554856Y3202722D02*
Y3210722D01*
X557456Y3204055D01*
X560056Y3210722D01*
Y3202722D01*
G01X567456D02*
X563456D01*
Y3210722D01*
X567456D01*
G01X565856Y3206855D02*
X563456D01*
G01X571156Y3202722D02*
Y3210722D01*
X575756Y3202722D01*
Y3210722D01*
G01X581456D02*
Y3202722D01*
G01X579156Y3210722D02*
X583756D01*
G01X595456Y3202722D02*
Y3210722D01*
X597956D01*
X598756Y3210322D01*
X599256Y3209789D01*
X599456Y3208722D01*
X599256Y3207655D01*
X598656Y3206989D01*
X597956Y3206589D01*
X595456D01*
G01X597956D02*
X599456Y3202722D01*
G01X607456D02*
X603456D01*
Y3210722D01*
X607456D01*
G01X605856Y3206855D02*
X603456D01*
G01X611456Y3202722D02*
Y3210722D01*
X613856D01*
X614656Y3210322D01*
X615256Y3209389D01*
X615456Y3208322D01*
X615256Y3207255D01*
X614756Y3206455D01*
X613856Y3206055D01*
X611456D01*
G01X621456Y3202722D02*
X620656Y3202855D01*
X619956Y3203389D01*
X619356Y3204189D01*
X618956Y3205122D01*
X618756Y3206189D01*
Y3207255D01*
X618956Y3208322D01*
X619356Y3209255D01*
X619956Y3210055D01*
X620656Y3210589D01*
X621456Y3210722D01*
X622256Y3210589D01*
X622956Y3210055D01*
X623556Y3209255D01*
X623956Y3208322D01*
X624156Y3207255D01*
Y3206189D01*
X623956Y3205122D01*
X623556Y3204189D01*
X622956Y3203389D01*
X622256Y3202855D01*
X621456Y3202722D01*
G01X627456D02*
Y3210722D01*
X629956D01*
X630756Y3210322D01*
X631256Y3209789D01*
X631456Y3208722D01*
X631256Y3207655D01*
X630656Y3206989D01*
X629956Y3206589D01*
X627456D01*
G01X629956D02*
X631456Y3202722D01*
G01X637456Y3210722D02*
Y3202722D01*
G01X635156Y3210722D02*
X639756D01*
G01X255656Y3225055D02*
X255056Y3225455D01*
X254356Y3225722D01*
X253556D01*
X252656Y3225322D01*
X251956Y3224655D01*
X251456Y3223855D01*
X251056Y3222522D01*
X250956Y3221322D01*
X251156Y3220122D01*
X251456Y3219322D01*
X252056Y3218522D01*
X252756Y3217989D01*
X253456Y3217722D01*
X254156D01*
X254856Y3217989D01*
X255456Y3218389D01*
X255956Y3218922D01*
G01X261456Y3217455D02*
X261256Y3217589D01*
Y3217855D01*
X261456Y3217989D01*
X261656Y3217855D01*
Y3217589D01*
X261456Y3217455D01*
G01X267156Y3217722D02*
Y3225722D01*
X271756Y3217722D01*
Y3225722D01*
G01X277456Y3217722D02*
X276656Y3217855D01*
X275956Y3218389D01*
X275356Y3219189D01*
X274956Y3220122D01*
X274756Y3221189D01*
Y3222255D01*
X274956Y3223322D01*
X275356Y3224255D01*
X275956Y3225055D01*
X276656Y3225589D01*
X277456Y3225722D01*
X278256Y3225589D01*
X278956Y3225055D01*
X279556Y3224255D01*
X279956Y3223322D01*
X280156Y3222255D01*
Y3221189D01*
X279956Y3220122D01*
X279556Y3219189D01*
X278956Y3218389D01*
X278256Y3217855D01*
X277456Y3217722D01*
G01X291156D02*
Y3225722D01*
X295756Y3217722D01*
Y3225722D01*
G01X303456Y3217722D02*
X299456D01*
Y3225722D01*
X303456D01*
G01X301856Y3221855D02*
X299456D01*
G01X311456Y3217722D02*
X307456D01*
Y3225722D01*
X311456D01*
G01X309856Y3221855D02*
X307456D01*
G01X315256Y3217722D02*
Y3225722D01*
X317256D01*
X318056Y3225322D01*
X318656Y3224789D01*
X319156Y3223989D01*
X319556Y3223055D01*
X319656Y3221722D01*
X319556Y3220389D01*
X319156Y3219455D01*
X318656Y3218655D01*
X318056Y3218122D01*
X317256Y3217722D01*
X315256D01*
G01X333456Y3225722D02*
Y3217722D01*
G01X331156Y3225722D02*
X335756D01*
G01X341456Y3217722D02*
X340656Y3217855D01*
X339956Y3218389D01*
X339356Y3219189D01*
X338956Y3220122D01*
X338756Y3221189D01*
Y3222255D01*
X338956Y3223322D01*
X339356Y3224255D01*
X339956Y3225055D01*
X340656Y3225589D01*
X341456Y3225722D01*
X342256Y3225589D01*
X342956Y3225055D01*
X343556Y3224255D01*
X343956Y3223322D01*
X344156Y3222255D01*
Y3221189D01*
X343956Y3220122D01*
X343556Y3219189D01*
X342956Y3218389D01*
X342256Y3217855D01*
X341456Y3217722D01*
G01X355456D02*
Y3225722D01*
X357856D01*
X358656Y3225322D01*
X359256Y3224389D01*
X359456Y3223322D01*
X359256Y3222255D01*
X358756Y3221455D01*
X357856Y3221055D01*
X355456D01*
G01X363456Y3225722D02*
Y3217722D01*
X367456D01*
G01X371256Y3225722D02*
Y3219989D01*
X371656Y3218788D01*
X372456Y3217989D01*
X373456Y3217722D01*
X374456Y3217989D01*
X375256Y3218788D01*
X375656Y3219989D01*
Y3225722D01*
G01X382056Y3221722D02*
X384056D01*
Y3219322D01*
X383456Y3218522D01*
X382756Y3217989D01*
X381756Y3217722D01*
X380756Y3217989D01*
X380056Y3218522D01*
X379456Y3219322D01*
X379056Y3220255D01*
X378856Y3221322D01*
Y3222255D01*
X379056Y3223055D01*
X379456Y3223989D01*
X380056Y3224789D01*
X380656Y3225322D01*
X381456Y3225722D01*
X382156D01*
X382956Y3225455D01*
X383556Y3224922D01*
G01X397456Y3217722D02*
X398156Y3217855D01*
X398956Y3218255D01*
X399456Y3218922D01*
X399656Y3219855D01*
X399456Y3220788D01*
X398856Y3221589D01*
X397956Y3221989D01*
X396956D01*
X396356Y3222255D01*
X395856Y3222922D01*
X395656Y3223855D01*
X395956Y3224789D01*
X396656Y3225455D01*
X397456Y3225722D01*
X398256Y3225455D01*
X398956Y3224789D01*
X399256Y3223855D01*
X399056Y3222922D01*
X398556Y3222255D01*
X397956Y3221989D01*
X396956D01*
X396056Y3221589D01*
X395456Y3220788D01*
X395256Y3219855D01*
X395456Y3218922D01*
X395956Y3218255D01*
X396756Y3217855D01*
X397456Y3217722D01*
G01X411356D02*
Y3225722D01*
G01X415556D02*
Y3217722D01*
G01Y3221722D02*
X411356D01*
G01X421456Y3217722D02*
X420656Y3217855D01*
X419956Y3218389D01*
X419356Y3219189D01*
X418956Y3220122D01*
X418756Y3221189D01*
Y3222255D01*
X418956Y3223322D01*
X419356Y3224255D01*
X419956Y3225055D01*
X420656Y3225589D01*
X421456Y3225722D01*
X422256Y3225589D01*
X422956Y3225055D01*
X423556Y3224255D01*
X423956Y3223322D01*
X424156Y3222255D01*
Y3221189D01*
X423956Y3220122D01*
X423556Y3219189D01*
X422956Y3218389D01*
X422256Y3217855D01*
X421456Y3217722D01*
G01X427456Y3225722D02*
Y3217722D01*
X431456D01*
G01X439456D02*
X435456D01*
Y3225722D01*
X439456D01*
G01X437856Y3221855D02*
X435456D01*
G01X443356Y3218788D02*
X444156Y3218122D01*
X445056Y3217722D01*
X445856D01*
X446656Y3218122D01*
X447256Y3218788D01*
X447556Y3219722D01*
X447356Y3220655D01*
X446856Y3221455D01*
X445956Y3221989D01*
X444756Y3222255D01*
X444056Y3222789D01*
X443756Y3223722D01*
X443956Y3224655D01*
X444456Y3225322D01*
X445156Y3225722D01*
X445856D01*
X446556Y3225455D01*
X447156Y3224789D01*
G01X459356Y3218788D02*
X460156Y3218122D01*
X461056Y3217722D01*
X461856D01*
X462656Y3218122D01*
X463256Y3218788D01*
X463556Y3219722D01*
X463356Y3220655D01*
X462856Y3221455D01*
X461956Y3221989D01*
X460756Y3222255D01*
X460056Y3222789D01*
X459756Y3223722D01*
X459956Y3224655D01*
X460456Y3225322D01*
X461156Y3225722D01*
X461856D01*
X462556Y3225455D01*
X463156Y3224789D01*
G01X467256Y3225722D02*
Y3219989D01*
X467656Y3218788D01*
X468456Y3217989D01*
X469456Y3217722D01*
X470456Y3217989D01*
X471256Y3218788D01*
X471656Y3219989D01*
Y3225722D01*
G01X475456Y3217722D02*
Y3225722D01*
X477956D01*
X478756Y3225322D01*
X479256Y3224789D01*
X479456Y3223722D01*
X479256Y3222655D01*
X478656Y3221989D01*
X477956Y3221589D01*
X475456D01*
G01X477956D02*
X479456Y3217722D01*
G01X483456D02*
Y3225722D01*
X485956D01*
X486756Y3225322D01*
X487256Y3224789D01*
X487456Y3223722D01*
X487256Y3222655D01*
X486656Y3221989D01*
X485956Y3221589D01*
X483456D01*
G01X485956D02*
X487456Y3217722D01*
G01X493456D02*
X492656Y3217855D01*
X491956Y3218389D01*
X491356Y3219189D01*
X490956Y3220122D01*
X490756Y3221189D01*
Y3222255D01*
X490956Y3223322D01*
X491356Y3224255D01*
X491956Y3225055D01*
X492656Y3225589D01*
X493456Y3225722D01*
X494256Y3225589D01*
X494956Y3225055D01*
X495556Y3224255D01*
X495956Y3223322D01*
X496156Y3222255D01*
Y3221189D01*
X495956Y3220122D01*
X495556Y3219189D01*
X494956Y3218389D01*
X494256Y3217855D01*
X493456Y3217722D01*
G01X499256Y3225722D02*
Y3219989D01*
X499656Y3218788D01*
X500456Y3217989D01*
X501456Y3217722D01*
X502456Y3217989D01*
X503256Y3218788D01*
X503656Y3219989D01*
Y3225722D01*
G01X507156Y3217722D02*
Y3225722D01*
X511756Y3217722D01*
Y3225722D01*
G01X515256Y3217722D02*
Y3225722D01*
X517256D01*
X518056Y3225322D01*
X518656Y3224789D01*
X519156Y3223989D01*
X519556Y3223055D01*
X519656Y3221722D01*
X519556Y3220389D01*
X519156Y3219455D01*
X518656Y3218655D01*
X518056Y3218122D01*
X517256Y3217722D01*
X515256D01*
G01X524256Y3225722D02*
X526656D01*
G01X525456D02*
Y3217722D01*
G01X524256D02*
X526656D01*
G01X531156D02*
Y3225722D01*
X535756Y3217722D01*
Y3225722D01*
G01X542056Y3221722D02*
X544056D01*
Y3219322D01*
X543456Y3218522D01*
X542756Y3217989D01*
X541756Y3217722D01*
X540756Y3217989D01*
X540056Y3218522D01*
X539456Y3219322D01*
X539056Y3220255D01*
X538856Y3221322D01*
Y3222255D01*
X539056Y3223055D01*
X539456Y3223989D01*
X540056Y3224789D01*
X540656Y3225322D01*
X541456Y3225722D01*
X542156D01*
X542956Y3225455D01*
X543556Y3224922D01*
G01X555356Y3218788D02*
X556156Y3218122D01*
X557056Y3217722D01*
X557856D01*
X558656Y3218122D01*
X559256Y3218788D01*
X559556Y3219722D01*
X559356Y3220655D01*
X558856Y3221455D01*
X557956Y3221989D01*
X556756Y3222255D01*
X556056Y3222789D01*
X555756Y3223722D01*
X555956Y3224655D01*
X556456Y3225322D01*
X557156Y3225722D01*
X557856D01*
X558556Y3225455D01*
X559156Y3224789D01*
G01X567656Y3225055D02*
X567056Y3225455D01*
X566356Y3225722D01*
X565556D01*
X564656Y3225322D01*
X563956Y3224655D01*
X563456Y3223855D01*
X563056Y3222522D01*
X562956Y3221322D01*
X563156Y3220122D01*
X563456Y3219322D01*
X564056Y3218522D01*
X564756Y3217989D01*
X565456Y3217722D01*
X566156D01*
X566856Y3217989D01*
X567456Y3218389D01*
X567956Y3218922D01*
G01X571456Y3217722D02*
Y3225722D01*
X573956D01*
X574756Y3225322D01*
X575256Y3224789D01*
X575456Y3223722D01*
X575256Y3222655D01*
X574656Y3221989D01*
X573956Y3221589D01*
X571456D01*
G01X573956D02*
X575456Y3217722D01*
G01X583456D02*
X579456D01*
Y3225722D01*
X583456D01*
G01X581856Y3221855D02*
X579456D01*
G01X586456Y3225722D02*
X587856Y3217722D01*
X589456Y3225722D01*
X591056Y3217722D01*
X592456Y3225722D01*
G01X597456Y3217455D02*
X597256Y3217589D01*
Y3217855D01*
X597456Y3217989D01*
X597656Y3217855D01*
Y3217589D01*
X597456Y3217455D01*
G01X604956Y3215055D02*
X603956Y3216389D01*
X603456Y3217722D01*
Y3223055D01*
X603956Y3224389D01*
X604956Y3225722D01*
G01X611456Y3217722D02*
Y3225722D01*
X613856D01*
X614656Y3225322D01*
X615256Y3224389D01*
X615456Y3223322D01*
X615256Y3222255D01*
X614756Y3221455D01*
X613856Y3221055D01*
X611456D01*
G01X619456Y3225722D02*
Y3217722D01*
X623456D01*
G01X631456D02*
X627456D01*
Y3225722D01*
X631456D01*
G01X629856Y3221855D02*
X627456D01*
G01X634956Y3217722D02*
X637456Y3225722D01*
X639956Y3217722D01*
G01X639056Y3220522D02*
X635856D01*
G01X643356Y3218788D02*
X644156Y3218122D01*
X645056Y3217722D01*
X645856D01*
X646656Y3218122D01*
X647256Y3218788D01*
X647556Y3219722D01*
X647356Y3220655D01*
X646856Y3221455D01*
X645956Y3221989D01*
X644756Y3222255D01*
X644056Y3222789D01*
X643756Y3223722D01*
X643956Y3224655D01*
X644456Y3225322D01*
X645156Y3225722D01*
X645856D01*
X646556Y3225455D01*
X647156Y3224789D01*
G01X655456Y3217722D02*
X651456D01*
Y3225722D01*
X655456D01*
G01X653856Y3221855D02*
X651456D01*
G01X668256Y3225722D02*
X670656D01*
G01X669456D02*
Y3217722D01*
G01X668256D02*
X670656D01*
G01X678056Y3221722D02*
X680056D01*
Y3219322D01*
X679456Y3218522D01*
X678756Y3217989D01*
X677756Y3217722D01*
X676756Y3217989D01*
X676056Y3218522D01*
X675456Y3219322D01*
X675056Y3220255D01*
X674856Y3221322D01*
Y3222255D01*
X675056Y3223055D01*
X675456Y3223989D01*
X676056Y3224789D01*
X676656Y3225322D01*
X677456Y3225722D01*
X678156D01*
X678956Y3225455D01*
X679556Y3224922D01*
G01X683156Y3217722D02*
Y3225722D01*
X687756Y3217722D01*
Y3225722D01*
G01X693456Y3217722D02*
X692656Y3217855D01*
X691956Y3218389D01*
X691356Y3219189D01*
X690956Y3220122D01*
X690756Y3221189D01*
Y3222255D01*
X690956Y3223322D01*
X691356Y3224255D01*
X691956Y3225055D01*
X692656Y3225589D01*
X693456Y3225722D01*
X694256Y3225589D01*
X694956Y3225055D01*
X695556Y3224255D01*
X695956Y3223322D01*
X696156Y3222255D01*
Y3221189D01*
X695956Y3220122D01*
X695556Y3219189D01*
X694956Y3218389D01*
X694256Y3217855D01*
X693456Y3217722D01*
G01X699456D02*
Y3225722D01*
X701956D01*
X702756Y3225322D01*
X703256Y3224789D01*
X703456Y3223722D01*
X703256Y3222655D01*
X702656Y3221989D01*
X701956Y3221589D01*
X699456D01*
G01X701956D02*
X703456Y3217722D01*
G01X711456D02*
X707456D01*
Y3225722D01*
X711456D01*
G01X709856Y3221855D02*
X707456D01*
G01X725456Y3225722D02*
Y3217722D01*
G01X723156Y3225722D02*
X727756D01*
G01X731356Y3217722D02*
Y3225722D01*
G01X735556D02*
Y3217722D01*
G01Y3221722D02*
X731356D01*
G01X740256Y3225722D02*
X742656D01*
G01X741456D02*
Y3217722D01*
G01X740256D02*
X742656D01*
G01X747356Y3218788D02*
X748156Y3218122D01*
X749056Y3217722D01*
X749856D01*
X750656Y3218122D01*
X751256Y3218788D01*
X751556Y3219722D01*
X751356Y3220655D01*
X750856Y3221455D01*
X749956Y3221989D01*
X748756Y3222255D01*
X748056Y3222789D01*
X747756Y3223722D01*
X747956Y3224655D01*
X748456Y3225322D01*
X749156Y3225722D01*
X749856D01*
X750556Y3225455D01*
X751156Y3224789D01*
G01X764256Y3225722D02*
X766656D01*
G01X765456D02*
Y3217722D01*
G01X764256D02*
X766656D01*
G01X771556D02*
Y3225722D01*
X775356D01*
G01X773956Y3221855D02*
X771556D01*
G01X787156Y3217722D02*
Y3225722D01*
X791756Y3217722D01*
Y3225722D01*
G01X797456Y3217722D02*
X796656Y3217855D01*
X795956Y3218389D01*
X795356Y3219189D01*
X794956Y3220122D01*
X794756Y3221189D01*
Y3222255D01*
X794956Y3223322D01*
X795356Y3224255D01*
X795956Y3225055D01*
X796656Y3225589D01*
X797456Y3225722D01*
X798256Y3225589D01*
X798956Y3225055D01*
X799556Y3224255D01*
X799956Y3223322D01*
X800156Y3222255D01*
Y3221189D01*
X799956Y3220122D01*
X799556Y3219189D01*
X798956Y3218389D01*
X798256Y3217855D01*
X797456Y3217722D01*
G01X813456Y3225722D02*
Y3217722D01*
G01X811156Y3225722D02*
X815756D01*
G01X819356Y3217722D02*
Y3225722D01*
G01X823556D02*
Y3217722D01*
G01Y3221722D02*
X819356D01*
G01X828256Y3225722D02*
X830656D01*
G01X829456D02*
Y3217722D01*
G01X828256D02*
X830656D01*
G01X835356Y3218788D02*
X836156Y3218122D01*
X837056Y3217722D01*
X837856D01*
X838656Y3218122D01*
X839256Y3218788D01*
X839556Y3219722D01*
X839356Y3220655D01*
X838856Y3221455D01*
X837956Y3221989D01*
X836756Y3222255D01*
X836056Y3222789D01*
X835756Y3223722D01*
X835956Y3224655D01*
X836456Y3225322D01*
X837156Y3225722D01*
X837856D01*
X838556Y3225455D01*
X839156Y3224789D01*
G01X852256Y3225722D02*
X854656D01*
G01X853456D02*
Y3217722D01*
G01X852256D02*
X854656D01*
G01X861456Y3225722D02*
Y3217722D01*
G01X859156Y3225722D02*
X863756D01*
G01X871456Y3217722D02*
X867456D01*
Y3225722D01*
X871456D01*
G01X869856Y3221855D02*
X867456D01*
G01X874856Y3217722D02*
Y3225722D01*
X877456Y3219055D01*
X880056Y3225722D01*
Y3217722D01*
G01X892256Y3225722D02*
X894656D01*
G01X893456D02*
Y3217722D01*
G01X892256D02*
X894656D01*
G01X899156D02*
Y3225722D01*
X903756Y3217722D01*
Y3225722D01*
G01X918256Y3221989D02*
X918656Y3222389D01*
X918956Y3223055D01*
X919156Y3223989D01*
X918956Y3224789D01*
X918556Y3225322D01*
X917856Y3225722D01*
X915156D01*
Y3217722D01*
X918456D01*
X919156Y3218255D01*
X919556Y3219055D01*
X919756Y3219989D01*
X919556Y3220922D01*
X918956Y3221722D01*
X918256Y3221989D01*
X915156D01*
G01X925456Y3217722D02*
X924656Y3217855D01*
X923956Y3218389D01*
X923356Y3219189D01*
X922956Y3220122D01*
X922756Y3221189D01*
Y3222255D01*
X922956Y3223322D01*
X923356Y3224255D01*
X923956Y3225055D01*
X924656Y3225589D01*
X925456Y3225722D01*
X926256Y3225589D01*
X926956Y3225055D01*
X927556Y3224255D01*
X927956Y3223322D01*
X928156Y3222255D01*
Y3221189D01*
X927956Y3220122D01*
X927556Y3219189D01*
X926956Y3218389D01*
X926256Y3217855D01*
X925456Y3217722D01*
G01X930956D02*
X933456Y3225722D01*
X935956Y3217722D01*
G01X935056Y3220522D02*
X931856D01*
G01X939456Y3217722D02*
Y3225722D01*
X941956D01*
X942756Y3225322D01*
X943256Y3224789D01*
X943456Y3223722D01*
X943256Y3222655D01*
X942656Y3221989D01*
X941956Y3221589D01*
X939456D01*
G01X941956D02*
X943456Y3217722D01*
G01X947256D02*
Y3225722D01*
X949256D01*
X950056Y3225322D01*
X950656Y3224789D01*
X951156Y3223989D01*
X951556Y3223055D01*
X951656Y3221722D01*
X951556Y3220389D01*
X951156Y3219455D01*
X950656Y3218655D01*
X950056Y3218122D01*
X949256Y3217722D01*
X947256D01*
G01X963556D02*
Y3225722D01*
X967356D01*
G01X965956Y3221855D02*
X963556D01*
G01X972256Y3225722D02*
X974656D01*
G01X973456D02*
Y3217722D01*
G01X972256D02*
X974656D01*
G01X979456Y3225722D02*
Y3217722D01*
X983456D01*
G01X991456D02*
X987456D01*
Y3225722D01*
X991456D01*
G01X989856Y3221855D02*
X987456D01*
G01X997956Y3215055D02*
X998956Y3216389D01*
X999456Y3217722D01*
Y3223055D01*
X998956Y3224389D01*
X997956Y3225722D01*
G01X254256Y3236989D02*
X254656Y3237389D01*
X254956Y3238055D01*
X255156Y3238989D01*
X254956Y3239789D01*
X254556Y3240322D01*
X253856Y3240722D01*
X251156D01*
Y3232722D01*
X254456D01*
X255156Y3233255D01*
X255556Y3234055D01*
X255756Y3234989D01*
X255556Y3235922D01*
X254956Y3236722D01*
X254256Y3236989D01*
X251156D01*
G01X261456Y3232455D02*
X261256Y3232589D01*
Y3232855D01*
X261456Y3232989D01*
X261656Y3232855D01*
Y3232589D01*
X261456Y3232455D01*
G01X266956Y3232722D02*
X269456Y3240722D01*
X271956Y3232722D01*
G01X271056Y3235522D02*
X267856D01*
G01X275456Y3240722D02*
Y3232722D01*
X279456D01*
G01X283456Y3240722D02*
Y3232722D01*
X287456D01*
G01X298956Y3240722D02*
X301456Y3232722D01*
X303956Y3240722D01*
G01X308256D02*
X310656D01*
G01X309456D02*
Y3232722D01*
G01X308256D02*
X310656D01*
G01X314956D02*
X317456Y3240722D01*
X319956Y3232722D01*
G01X319056Y3235522D02*
X315856D01*
G01X323356Y3233788D02*
X324156Y3233122D01*
X325056Y3232722D01*
X325856D01*
X326656Y3233122D01*
X327256Y3233788D01*
X327556Y3234722D01*
X327356Y3235655D01*
X326856Y3236455D01*
X325956Y3236989D01*
X324756Y3237255D01*
X324056Y3237789D01*
X323756Y3238722D01*
X323956Y3239655D01*
X324456Y3240322D01*
X325156Y3240722D01*
X325856D01*
X326556Y3240455D01*
X327156Y3239789D01*
G01X339456Y3232722D02*
Y3240722D01*
X341856D01*
X342656Y3240322D01*
X343256Y3239389D01*
X343456Y3238322D01*
X343256Y3237255D01*
X342756Y3236455D01*
X341856Y3236055D01*
X339456D01*
G01X347456Y3240722D02*
Y3232722D01*
X351456D01*
G01X355256Y3240722D02*
Y3234989D01*
X355656Y3233788D01*
X356456Y3232989D01*
X357456Y3232722D01*
X358456Y3232989D01*
X359256Y3233788D01*
X359656Y3234989D01*
Y3240722D01*
G01X366056Y3236722D02*
X368056D01*
Y3234322D01*
X367456Y3233522D01*
X366756Y3232989D01*
X365756Y3232722D01*
X364756Y3232989D01*
X364056Y3233522D01*
X363456Y3234322D01*
X363056Y3235255D01*
X362856Y3236322D01*
Y3237255D01*
X363056Y3238055D01*
X363456Y3238989D01*
X364056Y3239789D01*
X364656Y3240322D01*
X365456Y3240722D01*
X366156D01*
X366956Y3240455D01*
X367556Y3239922D01*
G01X374056Y3236722D02*
X376056D01*
Y3234322D01*
X375456Y3233522D01*
X374756Y3232989D01*
X373756Y3232722D01*
X372756Y3232989D01*
X372056Y3233522D01*
X371456Y3234322D01*
X371056Y3235255D01*
X370856Y3236322D01*
Y3237255D01*
X371056Y3238055D01*
X371456Y3238989D01*
X372056Y3239789D01*
X372656Y3240322D01*
X373456Y3240722D01*
X374156D01*
X374956Y3240455D01*
X375556Y3239922D01*
G01X383456Y3232722D02*
X379456D01*
Y3240722D01*
X383456D01*
G01X381856Y3236855D02*
X379456D01*
G01X387256Y3232722D02*
Y3240722D01*
X389256D01*
X390056Y3240322D01*
X390656Y3239789D01*
X391156Y3238989D01*
X391556Y3238055D01*
X391656Y3236722D01*
X391556Y3235389D01*
X391156Y3234455D01*
X390656Y3233655D01*
X390056Y3233122D01*
X389256Y3232722D01*
X387256D01*
G01X407456D02*
X403456D01*
Y3240722D01*
X407456D01*
G01X405856Y3236855D02*
X403456D01*
G01X411356Y3232722D02*
X415556Y3240722D01*
G01X411356D02*
X415556Y3232722D01*
G01X423656Y3240055D02*
X423056Y3240455D01*
X422356Y3240722D01*
X421556D01*
X420656Y3240322D01*
X419956Y3239655D01*
X419456Y3238855D01*
X419056Y3237522D01*
X418956Y3236322D01*
X419156Y3235122D01*
X419456Y3234322D01*
X420056Y3233522D01*
X420756Y3232989D01*
X421456Y3232722D01*
X422156D01*
X422856Y3232989D01*
X423456Y3233389D01*
X423956Y3233922D01*
G01X431456Y3232722D02*
X427456D01*
Y3240722D01*
X431456D01*
G01X429856Y3236855D02*
X427456D01*
G01X435456Y3232722D02*
Y3240722D01*
X437856D01*
X438656Y3240322D01*
X439256Y3239389D01*
X439456Y3238322D01*
X439256Y3237255D01*
X438756Y3236455D01*
X437856Y3236055D01*
X435456D01*
G01X445456Y3240722D02*
Y3232722D01*
G01X443156Y3240722D02*
X447756D01*
G01X459556Y3232722D02*
Y3240722D01*
X463356D01*
G01X461956Y3236855D02*
X459556D01*
G01X469456Y3232722D02*
X468656Y3232855D01*
X467956Y3233389D01*
X467356Y3234189D01*
X466956Y3235122D01*
X466756Y3236189D01*
Y3237255D01*
X466956Y3238322D01*
X467356Y3239255D01*
X467956Y3240055D01*
X468656Y3240589D01*
X469456Y3240722D01*
X470256Y3240589D01*
X470956Y3240055D01*
X471556Y3239255D01*
X471956Y3238322D01*
X472156Y3237255D01*
Y3236189D01*
X471956Y3235122D01*
X471556Y3234189D01*
X470956Y3233389D01*
X470256Y3232855D01*
X469456Y3232722D01*
G01X475456D02*
Y3240722D01*
X477956D01*
X478756Y3240322D01*
X479256Y3239789D01*
X479456Y3238722D01*
X479256Y3237655D01*
X478656Y3236989D01*
X477956Y3236589D01*
X475456D01*
G01X477956D02*
X479456Y3232722D01*
G01X250956Y3247722D02*
X253456Y3255722D01*
X255956Y3247722D01*
G01X255056Y3250522D02*
X251856D01*
G01X261456Y3247455D02*
X261256Y3247589D01*
Y3247855D01*
X261456Y3247989D01*
X261656Y3247855D01*
Y3247589D01*
X261456Y3247455D01*
G01X266956Y3255722D02*
X269456Y3247722D01*
X271956Y3255722D01*
G01X276256D02*
X278656D01*
G01X277456D02*
Y3247722D01*
G01X276256D02*
X278656D01*
G01X282956D02*
X285456Y3255722D01*
X287956Y3247722D01*
G01X287056Y3250522D02*
X283856D01*
G01X301456Y3255722D02*
Y3247722D01*
G01X299156Y3255722D02*
X303756D01*
G01X311456Y3247722D02*
X307456D01*
Y3255722D01*
X311456D01*
G01X309856Y3251855D02*
X307456D01*
G01X314956Y3247722D02*
X317456Y3255722D01*
X319956Y3247722D01*
G01X319056Y3250522D02*
X315856D01*
G01X323456Y3247722D02*
Y3255722D01*
X325956D01*
X326756Y3255322D01*
X327256Y3254789D01*
X327456Y3253722D01*
X327256Y3252655D01*
X326656Y3251989D01*
X325956Y3251589D01*
X323456D01*
G01X325956D02*
X327456Y3247722D01*
G01X339256D02*
Y3255722D01*
X341256D01*
X342056Y3255322D01*
X342656Y3254789D01*
X343156Y3253989D01*
X343556Y3253055D01*
X343656Y3251722D01*
X343556Y3250389D01*
X343156Y3249455D01*
X342656Y3248655D01*
X342056Y3248122D01*
X341256Y3247722D01*
X339256D01*
G01X347456D02*
Y3255722D01*
X349956D01*
X350756Y3255322D01*
X351256Y3254789D01*
X351456Y3253722D01*
X351256Y3252655D01*
X350656Y3251989D01*
X349956Y3251589D01*
X347456D01*
G01X349956D02*
X351456Y3247722D01*
G01X357456D02*
X356656Y3247855D01*
X355956Y3248389D01*
X355356Y3249189D01*
X354956Y3250122D01*
X354756Y3251189D01*
Y3252255D01*
X354956Y3253322D01*
X355356Y3254255D01*
X355956Y3255055D01*
X356656Y3255589D01*
X357456Y3255722D01*
X358256Y3255589D01*
X358956Y3255055D01*
X359556Y3254255D01*
X359956Y3253322D01*
X360156Y3252255D01*
Y3251189D01*
X359956Y3250122D01*
X359556Y3249189D01*
X358956Y3248389D01*
X358256Y3247855D01*
X357456Y3247722D01*
G01X363456D02*
Y3255722D01*
X365856D01*
X366656Y3255322D01*
X367256Y3254389D01*
X367456Y3253322D01*
X367256Y3252255D01*
X366756Y3251455D01*
X365856Y3251055D01*
X363456D01*
G01X380956Y3245055D02*
X379956Y3246389D01*
X379456Y3247722D01*
Y3253055D01*
X379956Y3254389D01*
X380956Y3255722D01*
G01X387556Y3247722D02*
Y3255722D01*
X391356D01*
G01X389956Y3251855D02*
X387556D01*
G01X397456Y3247722D02*
X396656Y3247855D01*
X395956Y3248389D01*
X395356Y3249189D01*
X394956Y3250122D01*
X394756Y3251189D01*
Y3252255D01*
X394956Y3253322D01*
X395356Y3254255D01*
X395956Y3255055D01*
X396656Y3255589D01*
X397456Y3255722D01*
X398256Y3255589D01*
X398956Y3255055D01*
X399556Y3254255D01*
X399956Y3253322D01*
X400156Y3252255D01*
Y3251189D01*
X399956Y3250122D01*
X399556Y3249189D01*
X398956Y3248389D01*
X398256Y3247855D01*
X397456Y3247722D01*
G01X403456D02*
Y3255722D01*
X405956D01*
X406756Y3255322D01*
X407256Y3254789D01*
X407456Y3253722D01*
X407256Y3252655D01*
X406656Y3251989D01*
X405956Y3251589D01*
X403456D01*
G01X405956D02*
X407456Y3247722D01*
G01X418956D02*
X421456Y3255722D01*
X423956Y3247722D01*
G01X423056Y3250522D02*
X419856D01*
G01X427456Y3255722D02*
Y3247722D01*
X431456D01*
G01X435456Y3255722D02*
Y3247722D01*
X439456D01*
G01X450956Y3255722D02*
X453456Y3247722D01*
X455956Y3255722D01*
G01X460256D02*
X462656D01*
G01X461456D02*
Y3247722D01*
G01X460256D02*
X462656D01*
G01X466956D02*
X469456Y3255722D01*
X471956Y3247722D01*
G01X471056Y3250522D02*
X467856D01*
G01X475356Y3248788D02*
X476156Y3248122D01*
X477056Y3247722D01*
X477856D01*
X478656Y3248122D01*
X479256Y3248788D01*
X479556Y3249722D01*
X479356Y3250655D01*
X478856Y3251455D01*
X477956Y3251989D01*
X476756Y3252255D01*
X476056Y3252789D01*
X475756Y3253722D01*
X475956Y3254655D01*
X476456Y3255322D01*
X477156Y3255722D01*
X477856D01*
X478556Y3255455D01*
X479156Y3254789D01*
G01X490956Y3247722D02*
X493456Y3255722D01*
X495956Y3247722D01*
G01X495056Y3250522D02*
X491856D01*
G01X499156Y3247722D02*
Y3255722D01*
X503756Y3247722D01*
Y3255722D01*
G01X507256Y3247722D02*
Y3255722D01*
X509256D01*
X510056Y3255322D01*
X510656Y3254789D01*
X511156Y3253989D01*
X511556Y3253055D01*
X511656Y3251722D01*
X511556Y3250389D01*
X511156Y3249455D01*
X510656Y3248655D01*
X510056Y3248122D01*
X509256Y3247722D01*
X507256D01*
G01X523456D02*
Y3255722D01*
X525856D01*
X526656Y3255322D01*
X527256Y3254389D01*
X527456Y3253322D01*
X527256Y3252255D01*
X526756Y3251455D01*
X525856Y3251055D01*
X523456D01*
G01X532256Y3255722D02*
X534656D01*
G01X533456D02*
Y3247722D01*
G01X532256D02*
X534656D01*
G01X539156D02*
Y3255722D01*
X543756Y3247722D01*
Y3255722D01*
G01X547356Y3248788D02*
X548156Y3248122D01*
X549056Y3247722D01*
X549856D01*
X550656Y3248122D01*
X551256Y3248788D01*
X551556Y3249722D01*
X551356Y3250655D01*
X550856Y3251455D01*
X549956Y3251989D01*
X548756Y3252255D01*
X548056Y3252789D01*
X547756Y3253722D01*
X547956Y3254655D01*
X548456Y3255322D01*
X549156Y3255722D01*
X549856D01*
X550556Y3255455D01*
X551156Y3254789D01*
G01X557956Y3245055D02*
X558956Y3246389D01*
X559456Y3247722D01*
Y3253055D01*
X558956Y3254389D01*
X557956Y3255722D01*
G01X565456Y3247455D02*
X565256Y3247589D01*
Y3247855D01*
X565456Y3247989D01*
X565656Y3247855D01*
Y3247589D01*
X565456Y3247455D01*
G01X233256Y3264322D02*
X233856Y3263389D01*
X234656Y3262855D01*
X235556Y3262722D01*
X236356Y3262855D01*
X237156Y3263522D01*
X237656Y3264322D01*
X237756Y3265122D01*
X237556Y3266055D01*
X236856Y3266722D01*
X236156Y3266989D01*
X235256D01*
G01X236156D02*
X236756Y3267389D01*
X237256Y3268055D01*
X237456Y3268855D01*
X237256Y3269655D01*
X236756Y3270322D01*
X235856Y3270722D01*
X234956Y3270589D01*
X234056Y3270055D01*
G01X243456Y3262455D02*
X243256Y3262589D01*
Y3262855D01*
X243456Y3262989D01*
X243656Y3262855D01*
Y3262589D01*
X243456Y3262455D01*
G01X249456Y3262722D02*
Y3270722D01*
X251856D01*
X252656Y3270322D01*
X253256Y3269389D01*
X253456Y3268322D01*
X253256Y3267255D01*
X252756Y3266455D01*
X251856Y3266055D01*
X249456D01*
G01X261656Y3270055D02*
X261056Y3270455D01*
X260356Y3270722D01*
X259556D01*
X258656Y3270322D01*
X257956Y3269655D01*
X257456Y3268855D01*
X257056Y3267522D01*
X256956Y3266322D01*
X257156Y3265122D01*
X257456Y3264322D01*
X258056Y3263522D01*
X258756Y3262989D01*
X259456Y3262722D01*
X260156D01*
X260856Y3262989D01*
X261456Y3263389D01*
X261956Y3263922D01*
G01X268256Y3266989D02*
X268656Y3267389D01*
X268956Y3268055D01*
X269156Y3268989D01*
X268956Y3269789D01*
X268556Y3270322D01*
X267856Y3270722D01*
X265156D01*
Y3262722D01*
X268456D01*
X269156Y3263255D01*
X269556Y3264055D01*
X269756Y3264989D01*
X269556Y3265922D01*
X268956Y3266722D01*
X268256Y3266989D01*
X265156D01*
G01X281456Y3262722D02*
Y3270722D01*
X283856D01*
X284656Y3270322D01*
X285256Y3269389D01*
X285456Y3268322D01*
X285256Y3267255D01*
X284756Y3266455D01*
X283856Y3266055D01*
X281456D01*
G01X289456Y3262722D02*
Y3270722D01*
X291956D01*
X292756Y3270322D01*
X293256Y3269789D01*
X293456Y3268722D01*
X293256Y3267655D01*
X292656Y3266989D01*
X291956Y3266589D01*
X289456D01*
G01X291956D02*
X293456Y3262722D01*
G01X299456D02*
X298656Y3262855D01*
X297956Y3263389D01*
X297356Y3264189D01*
X296956Y3265122D01*
X296756Y3266189D01*
Y3267255D01*
X296956Y3268322D01*
X297356Y3269255D01*
X297956Y3270055D01*
X298656Y3270589D01*
X299456Y3270722D01*
X300256Y3270589D01*
X300956Y3270055D01*
X301556Y3269255D01*
X301956Y3268322D01*
X302156Y3267255D01*
Y3266189D01*
X301956Y3265122D01*
X301556Y3264189D01*
X300956Y3263389D01*
X300256Y3262855D01*
X299456Y3262722D01*
G01X309656Y3270055D02*
X309056Y3270455D01*
X308356Y3270722D01*
X307556D01*
X306656Y3270322D01*
X305956Y3269655D01*
X305456Y3268855D01*
X305056Y3267522D01*
X304956Y3266322D01*
X305156Y3265122D01*
X305456Y3264322D01*
X306056Y3263522D01*
X306756Y3262989D01*
X307456Y3262722D01*
X308156D01*
X308856Y3262989D01*
X309456Y3263389D01*
X309956Y3263922D01*
G01X317456Y3262722D02*
X313456D01*
Y3270722D01*
X317456D01*
G01X315856Y3266855D02*
X313456D01*
G01X321356Y3263788D02*
X322156Y3263122D01*
X323056Y3262722D01*
X323856D01*
X324656Y3263122D01*
X325256Y3263788D01*
X325556Y3264722D01*
X325356Y3265655D01*
X324856Y3266455D01*
X323956Y3266989D01*
X322756Y3267255D01*
X322056Y3267789D01*
X321756Y3268722D01*
X321956Y3269655D01*
X322456Y3270322D01*
X323156Y3270722D01*
X323856D01*
X324556Y3270455D01*
X325156Y3269789D01*
G01X329356Y3263788D02*
X330156Y3263122D01*
X331056Y3262722D01*
X331856D01*
X332656Y3263122D01*
X333256Y3263788D01*
X333556Y3264722D01*
X333356Y3265655D01*
X332856Y3266455D01*
X331956Y3266989D01*
X330756Y3267255D01*
X330056Y3267789D01*
X329756Y3268722D01*
X329956Y3269655D01*
X330456Y3270322D01*
X331156Y3270722D01*
X331856D01*
X332556Y3270455D01*
X333156Y3269789D01*
G01X339456Y3262455D02*
X339256Y3262589D01*
Y3262855D01*
X339456Y3262989D01*
X339656Y3262855D01*
Y3262589D01*
X339456Y3262455D01*
G01Y3266055D02*
X339256Y3266189D01*
Y3266455D01*
X339456Y3266589D01*
X339656Y3266455D01*
Y3266189D01*
X339456Y3266055D01*
G01X233556Y3284389D02*
X234156Y3285189D01*
X234856Y3285589D01*
X235656Y3285722D01*
X236656Y3285455D01*
X237356Y3284789D01*
X237556Y3283989D01*
X237456Y3283188D01*
X237056Y3282522D01*
X235056Y3281189D01*
X234156Y3280255D01*
X233556Y3278922D01*
X233356Y3277722D01*
X237556D01*
G01X243456Y3277455D02*
X243256Y3277589D01*
Y3277855D01*
X243456Y3277989D01*
X243656Y3277855D01*
Y3277589D01*
X243456Y3277455D01*
G01X249556Y3277722D02*
Y3285722D01*
X253356D01*
G01X251956Y3281855D02*
X249556D01*
G01X256956Y3277722D02*
X259456Y3285722D01*
X261956Y3277722D01*
G01X261056Y3280522D02*
X257856D01*
G01X268256Y3281989D02*
X268656Y3282389D01*
X268956Y3283055D01*
X269156Y3283989D01*
X268956Y3284789D01*
X268556Y3285322D01*
X267856Y3285722D01*
X265156D01*
Y3277722D01*
X268456D01*
X269156Y3278255D01*
X269556Y3279055D01*
X269756Y3279989D01*
X269556Y3280922D01*
X268956Y3281722D01*
X268256Y3281989D01*
X265156D01*
G01X273456Y3277722D02*
Y3285722D01*
X275956D01*
X276756Y3285322D01*
X277256Y3284789D01*
X277456Y3283722D01*
X277256Y3282655D01*
X276656Y3281989D01*
X275956Y3281589D01*
X273456D01*
G01X275956D02*
X277456Y3277722D01*
G01X282256Y3285722D02*
X284656D01*
G01X283456D02*
Y3277722D01*
G01X282256D02*
X284656D01*
G01X293656Y3285055D02*
X293056Y3285455D01*
X292356Y3285722D01*
X291556D01*
X290656Y3285322D01*
X289956Y3284655D01*
X289456Y3283855D01*
X289056Y3282522D01*
X288956Y3281322D01*
X289156Y3280122D01*
X289456Y3279322D01*
X290056Y3278522D01*
X290756Y3277989D01*
X291456Y3277722D01*
X292156D01*
X292856Y3277989D01*
X293456Y3278389D01*
X293956Y3278922D01*
G01X296956Y3277722D02*
X299456Y3285722D01*
X301956Y3277722D01*
G01X301056Y3280522D02*
X297856D01*
G01X307456Y3285722D02*
Y3277722D01*
G01X305156Y3285722D02*
X309756D01*
G01X317456Y3277722D02*
X313456D01*
Y3285722D01*
X317456D01*
G01X315856Y3281855D02*
X313456D01*
G01X329456Y3277722D02*
Y3285722D01*
X331856D01*
X332656Y3285322D01*
X333256Y3284389D01*
X333456Y3283322D01*
X333256Y3282255D01*
X332756Y3281455D01*
X331856Y3281055D01*
X329456D01*
G01X341456Y3277722D02*
X337456D01*
Y3285722D01*
X341456D01*
G01X339856Y3281855D02*
X337456D01*
G01X345456Y3277722D02*
Y3285722D01*
X347956D01*
X348756Y3285322D01*
X349256Y3284789D01*
X349456Y3283722D01*
X349256Y3282655D01*
X348656Y3281989D01*
X347956Y3281589D01*
X345456D01*
G01X347956D02*
X349456Y3277722D01*
G01X363456D02*
X362656Y3277855D01*
X361956Y3278389D01*
X361356Y3279189D01*
X360956Y3280122D01*
X360756Y3281189D01*
Y3282255D01*
X360956Y3283322D01*
X361356Y3284255D01*
X361956Y3285055D01*
X362656Y3285589D01*
X363456Y3285722D01*
X364256Y3285589D01*
X364956Y3285055D01*
X365556Y3284255D01*
X365956Y3283322D01*
X366156Y3282255D01*
Y3281189D01*
X365956Y3280122D01*
X365556Y3279189D01*
X364956Y3278389D01*
X364256Y3277855D01*
X363456Y3277722D01*
G01X364256Y3279855D02*
X365456Y3277722D01*
G01X369256Y3285722D02*
Y3279989D01*
X369656Y3278788D01*
X370456Y3277989D01*
X371456Y3277722D01*
X372456Y3277989D01*
X373256Y3278788D01*
X373656Y3279989D01*
Y3285722D01*
G01X376956Y3277722D02*
X379456Y3285722D01*
X381956Y3277722D01*
G01X381056Y3280522D02*
X377856D01*
G01X385156Y3277722D02*
Y3285722D01*
X389756Y3277722D01*
Y3285722D01*
G01X395456D02*
Y3277722D01*
G01X393156Y3285722D02*
X397756D01*
G01X400956Y3277722D02*
X403456Y3285722D01*
X405956Y3277722D01*
G01X405056Y3280522D02*
X401856D01*
G01X417456Y3277722D02*
Y3285722D01*
X419856D01*
X420656Y3285322D01*
X421256Y3284389D01*
X421456Y3283322D01*
X421256Y3282255D01*
X420756Y3281455D01*
X419856Y3281055D01*
X417456D01*
G01X429656Y3285055D02*
X429056Y3285455D01*
X428356Y3285722D01*
X427556D01*
X426656Y3285322D01*
X425956Y3284655D01*
X425456Y3283855D01*
X425056Y3282522D01*
X424956Y3281322D01*
X425156Y3280122D01*
X425456Y3279322D01*
X426056Y3278522D01*
X426756Y3277989D01*
X427456Y3277722D01*
X428156D01*
X428856Y3277989D01*
X429456Y3278389D01*
X429956Y3278922D01*
G01X436256Y3281989D02*
X436656Y3282389D01*
X436956Y3283055D01*
X437156Y3283989D01*
X436956Y3284789D01*
X436556Y3285322D01*
X435856Y3285722D01*
X433156D01*
Y3277722D01*
X436456D01*
X437156Y3278255D01*
X437556Y3279055D01*
X437756Y3279989D01*
X437556Y3280922D01*
X436956Y3281722D01*
X436256Y3281989D01*
X433156D01*
G01X449356Y3278788D02*
X450156Y3278122D01*
X451056Y3277722D01*
X451856D01*
X452656Y3278122D01*
X453256Y3278788D01*
X453556Y3279722D01*
X453356Y3280655D01*
X452856Y3281455D01*
X451956Y3281989D01*
X450756Y3282255D01*
X450056Y3282789D01*
X449756Y3283722D01*
X449956Y3284655D01*
X450456Y3285322D01*
X451156Y3285722D01*
X451856D01*
X452556Y3285455D01*
X453156Y3284789D01*
G01X457456Y3277722D02*
Y3285722D01*
X459856D01*
X460656Y3285322D01*
X461256Y3284389D01*
X461456Y3283322D01*
X461256Y3282255D01*
X460756Y3281455D01*
X459856Y3281055D01*
X457456D01*
G01X469456Y3277722D02*
X465456D01*
Y3285722D01*
X469456D01*
G01X467856Y3281855D02*
X465456D01*
G01X477656Y3285055D02*
X477056Y3285455D01*
X476356Y3285722D01*
X475556D01*
X474656Y3285322D01*
X473956Y3284655D01*
X473456Y3283855D01*
X473056Y3282522D01*
X472956Y3281322D01*
X473156Y3280122D01*
X473456Y3279322D01*
X474056Y3278522D01*
X474756Y3277989D01*
X475456Y3277722D01*
X476156D01*
X476856Y3277989D01*
X477456Y3278389D01*
X477956Y3278922D01*
G01X482256Y3285722D02*
X484656D01*
G01X483456D02*
Y3277722D01*
G01X482256D02*
X484656D01*
G01X489556D02*
Y3285722D01*
X493356D01*
G01X491956Y3281855D02*
X489556D01*
G01X498256Y3285722D02*
X500656D01*
G01X499456D02*
Y3277722D01*
G01X498256D02*
X500656D01*
G01X509656Y3285055D02*
X509056Y3285455D01*
X508356Y3285722D01*
X507556D01*
X506656Y3285322D01*
X505956Y3284655D01*
X505456Y3283855D01*
X505056Y3282522D01*
X504956Y3281322D01*
X505156Y3280122D01*
X505456Y3279322D01*
X506056Y3278522D01*
X506756Y3277989D01*
X507456Y3277722D01*
X508156D01*
X508856Y3277989D01*
X509456Y3278389D01*
X509956Y3278922D01*
G01X512956Y3277722D02*
X515456Y3285722D01*
X517956Y3277722D01*
G01X517056Y3280522D02*
X513856D01*
G01X523456Y3285722D02*
Y3277722D01*
G01X521156Y3285722D02*
X525756D01*
G01X530256D02*
X532656D01*
G01X531456D02*
Y3277722D01*
G01X530256D02*
X532656D01*
G01X539456D02*
X538656Y3277855D01*
X537956Y3278389D01*
X537356Y3279189D01*
X536956Y3280122D01*
X536756Y3281189D01*
Y3282255D01*
X536956Y3283322D01*
X537356Y3284255D01*
X537956Y3285055D01*
X538656Y3285589D01*
X539456Y3285722D01*
X540256Y3285589D01*
X540956Y3285055D01*
X541556Y3284255D01*
X541956Y3283322D01*
X542156Y3282255D01*
Y3281189D01*
X541956Y3280122D01*
X541556Y3279189D01*
X540956Y3278389D01*
X540256Y3277855D01*
X539456Y3277722D01*
G01X545156D02*
Y3285722D01*
X549756Y3277722D01*
Y3285722D01*
G01X566456Y3275055D02*
X561456Y3283055D01*
Y3284389D01*
X562456Y3285722D01*
X563456D01*
X564456Y3284389D01*
Y3283055D01*
X563456Y3281722D01*
X561456Y3280389D01*
X560456Y3279055D01*
Y3276389D01*
X561456Y3275055D01*
X564456D01*
X566456Y3277722D01*
G01X579456D02*
X578656Y3277855D01*
X577956Y3278389D01*
X577356Y3279189D01*
X576956Y3280122D01*
X576756Y3281189D01*
Y3282255D01*
X576956Y3283322D01*
X577356Y3284255D01*
X577956Y3285055D01*
X578656Y3285589D01*
X579456Y3285722D01*
X580256Y3285589D01*
X580956Y3285055D01*
X581556Y3284255D01*
X581956Y3283322D01*
X582156Y3282255D01*
Y3281189D01*
X581956Y3280122D01*
X581556Y3279189D01*
X580956Y3278389D01*
X580256Y3277855D01*
X579456Y3277722D01*
G01X580256Y3279855D02*
X581456Y3277722D01*
G01X589656Y3285055D02*
X589056Y3285455D01*
X588356Y3285722D01*
X587556D01*
X586656Y3285322D01*
X585956Y3284655D01*
X585456Y3283855D01*
X585056Y3282522D01*
X584956Y3281322D01*
X585156Y3280122D01*
X585456Y3279322D01*
X586056Y3278522D01*
X586756Y3277989D01*
X587456Y3277722D01*
X588156D01*
X588856Y3277989D01*
X589456Y3278389D01*
X589956Y3278922D01*
G01X595456Y3285722D02*
Y3277722D01*
G01X593156Y3285722D02*
X597756D01*
G01X613456Y3277722D02*
X609456D01*
Y3285722D01*
X613456D01*
G01X611856Y3281855D02*
X609456D01*
G01X619456Y3277722D02*
X618656Y3277855D01*
X617956Y3278389D01*
X617356Y3279189D01*
X616956Y3280122D01*
X616756Y3281189D01*
Y3282255D01*
X616956Y3283322D01*
X617356Y3284255D01*
X617956Y3285055D01*
X618656Y3285589D01*
X619456Y3285722D01*
X620256Y3285589D01*
X620956Y3285055D01*
X621556Y3284255D01*
X621956Y3283322D01*
X622156Y3282255D01*
Y3281189D01*
X621956Y3280122D01*
X621556Y3279189D01*
X620956Y3278389D01*
X620256Y3277855D01*
X619456Y3277722D01*
G01X620256Y3279855D02*
X621456Y3277722D01*
G01X633556D02*
Y3285722D01*
X637356D01*
G01X635956Y3281855D02*
X633556D01*
G01X640956Y3277722D02*
X643456Y3285722D01*
X645956Y3277722D01*
G01X645056Y3280522D02*
X641856D01*
G01X651456Y3277722D02*
X650656Y3277855D01*
X649956Y3278389D01*
X649356Y3279189D01*
X648956Y3280122D01*
X648756Y3281189D01*
Y3282255D01*
X648956Y3283322D01*
X649356Y3284255D01*
X649956Y3285055D01*
X650656Y3285589D01*
X651456Y3285722D01*
X652256Y3285589D01*
X652956Y3285055D01*
X653556Y3284255D01*
X653956Y3283322D01*
X654156Y3282255D01*
Y3281189D01*
X653956Y3280122D01*
X653556Y3279189D01*
X652956Y3278389D01*
X652256Y3277855D01*
X651456Y3277722D01*
G01X652256Y3279855D02*
X653456Y3277722D01*
G01X659456Y3277455D02*
X659256Y3277589D01*
Y3277855D01*
X659456Y3277989D01*
X659656Y3277855D01*
Y3277589D01*
X659456Y3277455D01*
G01X235456Y3292722D02*
Y3300722D01*
X234256Y3299122D01*
G01Y3292722D02*
X236656D01*
G01X243456Y3292455D02*
X243256Y3292589D01*
Y3292855D01*
X243456Y3292989D01*
X243656Y3292855D01*
Y3292589D01*
X243456Y3292455D01*
G01X249456Y3292722D02*
Y3300722D01*
X251856D01*
X252656Y3300322D01*
X253256Y3299389D01*
X253456Y3298322D01*
X253256Y3297255D01*
X252756Y3296455D01*
X251856Y3296055D01*
X249456D01*
G01X261656Y3300055D02*
X261056Y3300455D01*
X260356Y3300722D01*
X259556D01*
X258656Y3300322D01*
X257956Y3299655D01*
X257456Y3298855D01*
X257056Y3297522D01*
X256956Y3296322D01*
X257156Y3295122D01*
X257456Y3294322D01*
X258056Y3293522D01*
X258756Y3292989D01*
X259456Y3292722D01*
X260156D01*
X260856Y3292989D01*
X261456Y3293389D01*
X261956Y3293922D01*
G01X268256Y3296989D02*
X268656Y3297389D01*
X268956Y3298055D01*
X269156Y3298989D01*
X268956Y3299789D01*
X268556Y3300322D01*
X267856Y3300722D01*
X265156D01*
Y3292722D01*
X268456D01*
X269156Y3293255D01*
X269556Y3294055D01*
X269756Y3294989D01*
X269556Y3295922D01*
X268956Y3296722D01*
X268256Y3296989D01*
X265156D01*
G01X281356Y3293788D02*
X282156Y3293122D01*
X283056Y3292722D01*
X283856D01*
X284656Y3293122D01*
X285256Y3293788D01*
X285556Y3294722D01*
X285356Y3295655D01*
X284856Y3296455D01*
X283956Y3296989D01*
X282756Y3297255D01*
X282056Y3297789D01*
X281756Y3298722D01*
X281956Y3299655D01*
X282456Y3300322D01*
X283156Y3300722D01*
X283856D01*
X284556Y3300455D01*
X285156Y3299789D01*
G01X290256Y3300722D02*
X292656D01*
G01X291456D02*
Y3292722D01*
G01X290256D02*
X292656D01*
G01X297556Y3300722D02*
X301356D01*
X297556Y3292722D01*
X301356D01*
G01X309456D02*
X305456D01*
Y3300722D01*
X309456D01*
G01X307856Y3296855D02*
X305456D01*
G01X339456Y3292455D02*
X339256Y3292589D01*
Y3292855D01*
X339456Y3292989D01*
X339656Y3292855D01*
Y3292589D01*
X339456Y3292455D01*
G01Y3296055D02*
X339256Y3296189D01*
Y3296455D01*
X339456Y3296589D01*
X339656Y3296455D01*
Y3296189D01*
X339456Y3296055D01*
G01X353556Y3292722D02*
Y3300722D01*
X357356D01*
G01X355956Y3296855D02*
X353556D01*
G01X363456Y3292722D02*
X362656Y3292855D01*
X361956Y3293389D01*
X361356Y3294189D01*
X360956Y3295122D01*
X360756Y3296189D01*
Y3297255D01*
X360956Y3298322D01*
X361356Y3299255D01*
X361956Y3300055D01*
X362656Y3300589D01*
X363456Y3300722D01*
X364256Y3300589D01*
X364956Y3300055D01*
X365556Y3299255D01*
X365956Y3298322D01*
X366156Y3297255D01*
Y3296189D01*
X365956Y3295122D01*
X365556Y3294189D01*
X364956Y3293389D01*
X364256Y3292855D01*
X363456Y3292722D01*
G01X369456Y3300722D02*
Y3292722D01*
X373456D01*
G01X377456Y3300722D02*
Y3292722D01*
X381456D01*
G01X387456D02*
X386656Y3292855D01*
X385956Y3293389D01*
X385356Y3294189D01*
X384956Y3295122D01*
X384756Y3296189D01*
Y3297255D01*
X384956Y3298322D01*
X385356Y3299255D01*
X385956Y3300055D01*
X386656Y3300589D01*
X387456Y3300722D01*
X388256Y3300589D01*
X388956Y3300055D01*
X389556Y3299255D01*
X389956Y3298322D01*
X390156Y3297255D01*
Y3296189D01*
X389956Y3295122D01*
X389556Y3294189D01*
X388956Y3293389D01*
X388256Y3292855D01*
X387456Y3292722D01*
G01X392456Y3300722D02*
X393856Y3292722D01*
X395456Y3300722D01*
X397056Y3292722D01*
X398456Y3300722D01*
G01X412056Y3296722D02*
X414056D01*
Y3294322D01*
X413456Y3293522D01*
X412756Y3292989D01*
X411756Y3292722D01*
X410756Y3292989D01*
X410056Y3293522D01*
X409456Y3294322D01*
X409056Y3295255D01*
X408856Y3296322D01*
Y3297255D01*
X409056Y3298055D01*
X409456Y3298989D01*
X410056Y3299789D01*
X410656Y3300322D01*
X411456Y3300722D01*
X412156D01*
X412956Y3300455D01*
X413556Y3299922D01*
G01X421456Y3292722D02*
X417456D01*
Y3300722D01*
X421456D01*
G01X419856Y3296855D02*
X417456D01*
G01X425456Y3292722D02*
Y3300722D01*
X427956D01*
X428756Y3300322D01*
X429256Y3299789D01*
X429456Y3298722D01*
X429256Y3297655D01*
X428656Y3296989D01*
X427956Y3296589D01*
X425456D01*
G01X427956D02*
X429456Y3292722D01*
G01X436256Y3296989D02*
X436656Y3297389D01*
X436956Y3298055D01*
X437156Y3298989D01*
X436956Y3299789D01*
X436556Y3300322D01*
X435856Y3300722D01*
X433156D01*
Y3292722D01*
X436456D01*
X437156Y3293255D01*
X437556Y3294055D01*
X437756Y3294989D01*
X437556Y3295922D01*
X436956Y3296722D01*
X436256Y3296989D01*
X433156D01*
G01X445456Y3292722D02*
X441456D01*
Y3300722D01*
X445456D01*
G01X443856Y3296855D02*
X441456D01*
G01X449456Y3292722D02*
Y3300722D01*
X451956D01*
X452756Y3300322D01*
X453256Y3299789D01*
X453456Y3298722D01*
X453256Y3297655D01*
X452656Y3296989D01*
X451956Y3296589D01*
X449456D01*
G01X451956D02*
X453456Y3292722D01*
G01X465556D02*
Y3300722D01*
X469356D01*
G01X467956Y3296855D02*
X465556D01*
G01X474256Y3300722D02*
X476656D01*
G01X475456D02*
Y3292722D01*
G01X474256D02*
X476656D01*
G01X481456Y3300722D02*
Y3292722D01*
X485456D01*
G01X493456D02*
X489456D01*
Y3300722D01*
X493456D01*
G01X491856Y3296855D02*
X489456D01*
G01X498756Y3290322D02*
X500156Y3292189D01*
Y3294055D01*
X498756D01*
Y3292189D01*
X500156D01*
G01Y3295389D02*
Y3297255D01*
X498756D01*
Y3295389D01*
X500156D01*
G01X512456Y3300722D02*
X513856Y3292722D01*
X515456Y3300722D01*
X517056Y3292722D01*
X518456Y3300722D01*
G01X522256D02*
X524656D01*
G01X523456D02*
Y3292722D01*
G01X522256D02*
X524656D01*
G01X531456Y3300722D02*
Y3292722D01*
G01X529156Y3300722D02*
X533756D01*
G01X537356Y3292722D02*
Y3300722D01*
G01X541556D02*
Y3292722D01*
G01Y3296722D02*
X537356D01*
G01X555456Y3300722D02*
Y3292722D01*
G01X553156Y3300722D02*
X557756D01*
G01X563456Y3292722D02*
X562656Y3292855D01*
X561956Y3293389D01*
X561356Y3294189D01*
X560956Y3295122D01*
X560756Y3296189D01*
Y3297255D01*
X560956Y3298322D01*
X561356Y3299255D01*
X561956Y3300055D01*
X562656Y3300589D01*
X563456Y3300722D01*
X564256Y3300589D01*
X564956Y3300055D01*
X565556Y3299255D01*
X565956Y3298322D01*
X566156Y3297255D01*
Y3296189D01*
X565956Y3295122D01*
X565556Y3294189D01*
X564956Y3293389D01*
X564256Y3292855D01*
X563456Y3292722D01*
G01X569456Y3300722D02*
Y3292722D01*
X573456D01*
G01X581456D02*
X577456D01*
Y3300722D01*
X581456D01*
G01X579856Y3296855D02*
X577456D01*
G01X585456Y3292722D02*
Y3300722D01*
X587956D01*
X588756Y3300322D01*
X589256Y3299789D01*
X589456Y3298722D01*
X589256Y3297655D01*
X588656Y3296989D01*
X587956Y3296589D01*
X585456D01*
G01X587956D02*
X589456Y3292722D01*
G01X592956D02*
X595456Y3300722D01*
X597956Y3292722D01*
G01X597056Y3295522D02*
X593856D01*
G01X601156Y3292722D02*
Y3300722D01*
X605756Y3292722D01*
Y3300722D01*
G01X613656Y3300055D02*
X613056Y3300455D01*
X612356Y3300722D01*
X611556D01*
X610656Y3300322D01*
X609956Y3299655D01*
X609456Y3298855D01*
X609056Y3297522D01*
X608956Y3296322D01*
X609156Y3295122D01*
X609456Y3294322D01*
X610056Y3293522D01*
X610756Y3292989D01*
X611456Y3292722D01*
X612156D01*
X612856Y3292989D01*
X613456Y3293389D01*
X613956Y3293922D01*
G01X621456Y3292722D02*
X617456D01*
Y3300722D01*
X621456D01*
G01X619856Y3296855D02*
X617456D01*
G01X634156Y3294189D02*
X636756D01*
G01Y3296589D02*
X634156D01*
G01X642356Y3295389D02*
X644756D01*
G01X643456Y3297122D02*
Y3293655D01*
G01X649656Y3292455D02*
X653256Y3300722D01*
G01X658156Y3295389D02*
X660756D01*
G01X667456Y3300722D02*
X666656Y3300455D01*
X666056Y3299789D01*
X665656Y3298989D01*
X665356Y3297922D01*
X665256Y3296722D01*
X665356Y3295522D01*
X665656Y3294455D01*
X666056Y3293655D01*
X666656Y3292989D01*
X667456Y3292722D01*
X668256Y3292989D01*
X668856Y3293655D01*
X669256Y3294455D01*
X669556Y3295522D01*
X669656Y3296722D01*
X669556Y3297922D01*
X669256Y3298989D01*
X668856Y3299789D01*
X668256Y3300455D01*
X667456Y3300722D01*
G01X675456Y3292455D02*
X675256Y3292589D01*
Y3292855D01*
X675456Y3292989D01*
X675656Y3292855D01*
Y3292589D01*
X675456Y3292455D01*
G01X683456Y3292722D02*
Y3300722D01*
X682256Y3299122D01*
G01Y3292722D02*
X684656D01*
G01X689256Y3293922D02*
X689856Y3293255D01*
X690556Y3292855D01*
X691456Y3292722D01*
X692356Y3292989D01*
X693056Y3293522D01*
X693556Y3294455D01*
X693656Y3295522D01*
X693456Y3296589D01*
X692956Y3297255D01*
X692256Y3297789D01*
X691556Y3297922D01*
X690856Y3297789D01*
X689956Y3297255D01*
X690256Y3300722D01*
X692956D01*
G01X696856Y3292722D02*
Y3300722D01*
X699456Y3294055D01*
X702056Y3300722D01*
Y3292722D01*
G01X704856D02*
Y3300722D01*
X707456Y3294055D01*
X710056Y3300722D01*
Y3292722D01*
G01X233156Y3307722D02*
Y3315722D01*
X237756Y3307722D01*
Y3315722D01*
G01X243456Y3307722D02*
X242656Y3307855D01*
X241956Y3308389D01*
X241356Y3309189D01*
X240956Y3310122D01*
X240756Y3311189D01*
Y3312255D01*
X240956Y3313322D01*
X241356Y3314255D01*
X241956Y3315055D01*
X242656Y3315589D01*
X243456Y3315722D01*
X244256Y3315589D01*
X244956Y3315055D01*
X245556Y3314255D01*
X245956Y3313322D01*
X246156Y3312255D01*
Y3311189D01*
X245956Y3310122D01*
X245556Y3309189D01*
X244956Y3308389D01*
X244256Y3307855D01*
X243456Y3307722D01*
G01X251456Y3315722D02*
Y3307722D01*
G01X249156Y3315722D02*
X253756D01*
G01X261456Y3307722D02*
X257456D01*
Y3315722D01*
X261456D01*
G01X259856Y3311855D02*
X257456D01*
G01X265356Y3308788D02*
X266156Y3308122D01*
X267056Y3307722D01*
X267856D01*
X268656Y3308122D01*
X269256Y3308788D01*
X269556Y3309722D01*
X269356Y3310655D01*
X268856Y3311455D01*
X267956Y3311989D01*
X266756Y3312255D01*
X266056Y3312789D01*
X265756Y3313722D01*
X265956Y3314655D01*
X266456Y3315322D01*
X267156Y3315722D01*
X267856D01*
X268556Y3315455D01*
X269156Y3314789D01*
G01X275456Y3307455D02*
X275256Y3307589D01*
Y3307855D01*
X275456Y3307989D01*
X275656Y3307855D01*
Y3307589D01*
X275456Y3307455D01*
G01Y3311055D02*
X275256Y3311189D01*
Y3311455D01*
X275456Y3311589D01*
X275656Y3311455D01*
Y3311189D01*
X275456Y3311055D01*
G01X290956Y3305055D02*
X289956Y3306389D01*
X289456Y3307722D01*
Y3313055D01*
X289956Y3314389D01*
X290956Y3315722D01*
G01X297256D02*
Y3309989D01*
X297656Y3308788D01*
X298456Y3307989D01*
X299456Y3307722D01*
X300456Y3307989D01*
X301256Y3308788D01*
X301656Y3309989D01*
Y3315722D01*
G01X305156Y3307722D02*
Y3315722D01*
X309756Y3307722D01*
Y3315722D01*
G01X313456D02*
Y3307722D01*
X317456D01*
G01X325456D02*
X321456D01*
Y3315722D01*
X325456D01*
G01X323856Y3311855D02*
X321456D01*
G01X329356Y3308788D02*
X330156Y3308122D01*
X331056Y3307722D01*
X331856D01*
X332656Y3308122D01*
X333256Y3308788D01*
X333556Y3309722D01*
X333356Y3310655D01*
X332856Y3311455D01*
X331956Y3311989D01*
X330756Y3312255D01*
X330056Y3312789D01*
X329756Y3313722D01*
X329956Y3314655D01*
X330456Y3315322D01*
X331156Y3315722D01*
X331856D01*
X332556Y3315455D01*
X333156Y3314789D01*
G01X337356Y3308788D02*
X338156Y3308122D01*
X339056Y3307722D01*
X339856D01*
X340656Y3308122D01*
X341256Y3308788D01*
X341556Y3309722D01*
X341356Y3310655D01*
X340856Y3311455D01*
X339956Y3311989D01*
X338756Y3312255D01*
X338056Y3312789D01*
X337756Y3313722D01*
X337956Y3314655D01*
X338456Y3315322D01*
X339156Y3315722D01*
X339856D01*
X340556Y3315455D01*
X341156Y3314789D01*
G01X355456Y3307722D02*
X354656Y3307855D01*
X353956Y3308389D01*
X353356Y3309189D01*
X352956Y3310122D01*
X352756Y3311189D01*
Y3312255D01*
X352956Y3313322D01*
X353356Y3314255D01*
X353956Y3315055D01*
X354656Y3315589D01*
X355456Y3315722D01*
X356256Y3315589D01*
X356956Y3315055D01*
X357556Y3314255D01*
X357956Y3313322D01*
X358156Y3312255D01*
Y3311189D01*
X357956Y3310122D01*
X357556Y3309189D01*
X356956Y3308389D01*
X356256Y3307855D01*
X355456Y3307722D01*
G01X363456Y3315722D02*
Y3307722D01*
G01X361156Y3315722D02*
X365756D01*
G01X369356Y3307722D02*
Y3315722D01*
G01X373556D02*
Y3307722D01*
G01Y3311722D02*
X369356D01*
G01X381456Y3307722D02*
X377456D01*
Y3315722D01*
X381456D01*
G01X379856Y3311855D02*
X377456D01*
G01X385456Y3307722D02*
Y3315722D01*
X387956D01*
X388756Y3315322D01*
X389256Y3314789D01*
X389456Y3313722D01*
X389256Y3312655D01*
X388656Y3311989D01*
X387956Y3311589D01*
X385456D01*
G01X387956D02*
X389456Y3307722D01*
G01X392456Y3315722D02*
X393856Y3307722D01*
X395456Y3315722D01*
X397056Y3307722D01*
X398456Y3315722D01*
G01X402256D02*
X404656D01*
G01X403456D02*
Y3307722D01*
G01X402256D02*
X404656D01*
G01X409356Y3308788D02*
X410156Y3308122D01*
X411056Y3307722D01*
X411856D01*
X412656Y3308122D01*
X413256Y3308788D01*
X413556Y3309722D01*
X413356Y3310655D01*
X412856Y3311455D01*
X411956Y3311989D01*
X410756Y3312255D01*
X410056Y3312789D01*
X409756Y3313722D01*
X409956Y3314655D01*
X410456Y3315322D01*
X411156Y3315722D01*
X411856D01*
X412556Y3315455D01*
X413156Y3314789D01*
G01X421456Y3307722D02*
X417456D01*
Y3315722D01*
X421456D01*
G01X419856Y3311855D02*
X417456D01*
G01X433356Y3308788D02*
X434156Y3308122D01*
X435056Y3307722D01*
X435856D01*
X436656Y3308122D01*
X437256Y3308788D01*
X437556Y3309722D01*
X437356Y3310655D01*
X436856Y3311455D01*
X435956Y3311989D01*
X434756Y3312255D01*
X434056Y3312789D01*
X433756Y3313722D01*
X433956Y3314655D01*
X434456Y3315322D01*
X435156Y3315722D01*
X435856D01*
X436556Y3315455D01*
X437156Y3314789D01*
G01X441456Y3307722D02*
Y3315722D01*
X443856D01*
X444656Y3315322D01*
X445256Y3314389D01*
X445456Y3313322D01*
X445256Y3312255D01*
X444756Y3311455D01*
X443856Y3311055D01*
X441456D01*
G01X453456Y3307722D02*
X449456D01*
Y3315722D01*
X453456D01*
G01X451856Y3311855D02*
X449456D01*
G01X461656Y3315055D02*
X461056Y3315455D01*
X460356Y3315722D01*
X459556D01*
X458656Y3315322D01*
X457956Y3314655D01*
X457456Y3313855D01*
X457056Y3312522D01*
X456956Y3311322D01*
X457156Y3310122D01*
X457456Y3309322D01*
X458056Y3308522D01*
X458756Y3307989D01*
X459456Y3307722D01*
X460156D01*
X460856Y3307989D01*
X461456Y3308389D01*
X461956Y3308922D01*
G01X466256Y3315722D02*
X468656D01*
G01X467456D02*
Y3307722D01*
G01X466256D02*
X468656D01*
G01X473556D02*
Y3315722D01*
X477356D01*
G01X475956Y3311855D02*
X473556D01*
G01X482256Y3315722D02*
X484656D01*
G01X483456D02*
Y3307722D01*
G01X482256D02*
X484656D01*
G01X493456D02*
X489456D01*
Y3315722D01*
X493456D01*
G01X491856Y3311855D02*
X489456D01*
G01X497256Y3307722D02*
Y3315722D01*
X499256D01*
X500056Y3315322D01*
X500656Y3314789D01*
X501156Y3313989D01*
X501556Y3313055D01*
X501656Y3311722D01*
X501556Y3310389D01*
X501156Y3309455D01*
X500656Y3308655D01*
X500056Y3308122D01*
X499256Y3307722D01*
X497256D01*
G01X514256Y3315722D02*
X516656D01*
G01X515456D02*
Y3307722D01*
G01X514256D02*
X516656D01*
G01X521156D02*
Y3315722D01*
X525756Y3307722D01*
Y3315722D01*
G01X537456Y3307722D02*
Y3315722D01*
X539856D01*
X540656Y3315322D01*
X541256Y3314389D01*
X541456Y3313322D01*
X541256Y3312255D01*
X540756Y3311455D01*
X539856Y3311055D01*
X537456D01*
G01X549656Y3315055D02*
X549056Y3315455D01*
X548356Y3315722D01*
X547556D01*
X546656Y3315322D01*
X545956Y3314655D01*
X545456Y3313855D01*
X545056Y3312522D01*
X544956Y3311322D01*
X545156Y3310122D01*
X545456Y3309322D01*
X546056Y3308522D01*
X546756Y3307989D01*
X547456Y3307722D01*
X548156D01*
X548856Y3307989D01*
X549456Y3308389D01*
X549956Y3308922D01*
G01X556256Y3311989D02*
X556656Y3312389D01*
X556956Y3313055D01*
X557156Y3313989D01*
X556956Y3314789D01*
X556556Y3315322D01*
X555856Y3315722D01*
X553156D01*
Y3307722D01*
X556456D01*
X557156Y3308255D01*
X557556Y3309055D01*
X557756Y3309989D01*
X557556Y3310922D01*
X556956Y3311722D01*
X556256Y3311989D01*
X553156D01*
G01X569356Y3308788D02*
X570156Y3308122D01*
X571056Y3307722D01*
X571856D01*
X572656Y3308122D01*
X573256Y3308788D01*
X573556Y3309722D01*
X573356Y3310655D01*
X572856Y3311455D01*
X571956Y3311989D01*
X570756Y3312255D01*
X570056Y3312789D01*
X569756Y3313722D01*
X569956Y3314655D01*
X570456Y3315322D01*
X571156Y3315722D01*
X571856D01*
X572556Y3315455D01*
X573156Y3314789D01*
G01X577456Y3307722D02*
Y3315722D01*
X579856D01*
X580656Y3315322D01*
X581256Y3314389D01*
X581456Y3313322D01*
X581256Y3312255D01*
X580756Y3311455D01*
X579856Y3311055D01*
X577456D01*
G01X589456Y3307722D02*
X585456D01*
Y3315722D01*
X589456D01*
G01X587856Y3311855D02*
X585456D01*
G01X597656Y3315055D02*
X597056Y3315455D01*
X596356Y3315722D01*
X595556D01*
X594656Y3315322D01*
X593956Y3314655D01*
X593456Y3313855D01*
X593056Y3312522D01*
X592956Y3311322D01*
X593156Y3310122D01*
X593456Y3309322D01*
X594056Y3308522D01*
X594756Y3307989D01*
X595456Y3307722D01*
X596156D01*
X596856Y3307989D01*
X597456Y3308389D01*
X597956Y3308922D01*
G01X603956Y3305055D02*
X604956Y3306389D01*
X605456Y3307722D01*
Y3313055D01*
X604956Y3314389D01*
X603956Y3315722D01*
G01X235456Y3322722D02*
X234656Y3322855D01*
X233956Y3323389D01*
X233356Y3324189D01*
X232956Y3325122D01*
X232756Y3326189D01*
Y3327255D01*
X232956Y3328322D01*
X233356Y3329255D01*
X233956Y3330055D01*
X234656Y3330589D01*
X235456Y3330722D01*
X236256Y3330589D01*
X236956Y3330055D01*
X237556Y3329255D01*
X237956Y3328322D01*
X238156Y3327255D01*
Y3326189D01*
X237956Y3325122D01*
X237556Y3324189D01*
X236956Y3323389D01*
X236256Y3322855D01*
X235456Y3322722D01*
G01X236256Y3324855D02*
X237456Y3322722D01*
G01X241756Y3328055D02*
Y3324322D01*
X242156Y3323389D01*
X242756Y3322855D01*
X243456Y3322722D01*
X244156Y3322855D01*
X244756Y3323389D01*
X245156Y3324322D01*
G01Y3322722D02*
Y3328055D01*
G01X253256Y3322722D02*
Y3328055D01*
G01Y3327122D02*
X252856Y3327655D01*
X252256Y3327922D01*
X251556Y3328055D01*
X250856Y3327789D01*
X250256Y3327255D01*
X249856Y3326455D01*
X249656Y3325389D01*
X249856Y3324322D01*
X250256Y3323522D01*
X250856Y3322989D01*
X251556Y3322722D01*
X252256Y3322855D01*
X252856Y3323255D01*
X253256Y3323788D01*
G01X257756Y3322722D02*
Y3328055D01*
G01Y3326722D02*
X258156Y3327389D01*
X258756Y3327922D01*
X259556Y3328055D01*
X260256Y3327922D01*
X260856Y3327389D01*
X261156Y3326455D01*
Y3322722D01*
G01X267456Y3330722D02*
Y3322722D01*
G01X266056Y3328055D02*
X268856D01*
G01X277256Y3322722D02*
Y3328055D01*
G01Y3327122D02*
X276856Y3327655D01*
X276256Y3327922D01*
X275556Y3328055D01*
X274856Y3327789D01*
X274256Y3327255D01*
X273856Y3326455D01*
X273656Y3325389D01*
X273856Y3324322D01*
X274256Y3323522D01*
X274856Y3322989D01*
X275556Y3322722D01*
X276256Y3322855D01*
X276856Y3323255D01*
X277256Y3323788D01*
G01X289556Y3322722D02*
Y3330722D01*
X293356D01*
G01X291956Y3326855D02*
X289556D01*
G01X296956Y3322722D02*
X299456Y3330722D01*
X301956Y3322722D01*
G01X301056Y3325522D02*
X297856D01*
G01X308256Y3326989D02*
X308656Y3327389D01*
X308956Y3328055D01*
X309156Y3328989D01*
X308956Y3329789D01*
X308556Y3330322D01*
X307856Y3330722D01*
X305156D01*
Y3322722D01*
X308456D01*
X309156Y3323255D01*
X309556Y3324055D01*
X309756Y3324989D01*
X309556Y3325922D01*
X308956Y3326722D01*
X308256Y3326989D01*
X305156D01*
G01X321156Y3322722D02*
Y3330722D01*
X325756Y3322722D01*
Y3330722D01*
G01X331456Y3322722D02*
X330656Y3322855D01*
X329956Y3323389D01*
X329356Y3324189D01*
X328956Y3325122D01*
X328756Y3326189D01*
Y3327255D01*
X328956Y3328322D01*
X329356Y3329255D01*
X329956Y3330055D01*
X330656Y3330589D01*
X331456Y3330722D01*
X332256Y3330589D01*
X332956Y3330055D01*
X333556Y3329255D01*
X333956Y3328322D01*
X334156Y3327255D01*
Y3326189D01*
X333956Y3325122D01*
X333556Y3324189D01*
X332956Y3323389D01*
X332256Y3322855D01*
X331456Y3322722D01*
G01X339456Y3330722D02*
Y3322722D01*
G01X337156Y3330722D02*
X341756D01*
G01X349456Y3322722D02*
X345456D01*
Y3330722D01*
X349456D01*
G01X347856Y3326855D02*
X345456D01*
G01X361456Y3322722D02*
Y3330722D01*
X363956D01*
X364756Y3330322D01*
X365256Y3329789D01*
X365456Y3328722D01*
X365256Y3327655D01*
X364656Y3326989D01*
X363956Y3326589D01*
X361456D01*
G01X363956D02*
X365456Y3322722D01*
G01X373456D02*
X369456D01*
Y3330722D01*
X373456D01*
G01X371856Y3326855D02*
X369456D01*
G01X376956Y3330722D02*
X379456Y3322722D01*
X381956Y3330722D01*
G01X387456Y3322455D02*
X387256Y3322589D01*
Y3322855D01*
X387456Y3322989D01*
X387656Y3322855D01*
Y3322589D01*
X387456Y3322455D01*
G01Y3326055D02*
X387256Y3326189D01*
Y3326455D01*
X387456Y3326589D01*
X387656Y3326455D01*
Y3326189D01*
X387456Y3326055D01*
G01X393556Y3322722D02*
Y3330722D01*
X397356D01*
G01X395956Y3326855D02*
X393556D01*
G01X270756Y2768782D02*
X258256D01*
X267214Y2763047D01*
Y2770797D01*
G01X270756Y2775292D02*
X258256D01*
X268673Y2779322D01*
X258256Y2783352D01*
X270756D01*
G01Y2787692D02*
X258256D01*
X268673Y2791722D01*
X258256Y2795752D01*
X270756D01*
G01X261256Y2906989D02*
X261656Y2907389D01*
X261956Y2908055D01*
X262156Y2908989D01*
X261956Y2909789D01*
X261556Y2910322D01*
X260856Y2910722D01*
X258156D01*
Y2902722D01*
X261456D01*
X262156Y2903255D01*
X262556Y2904055D01*
X262756Y2904989D01*
X262556Y2905922D01*
X261956Y2906722D01*
X261256Y2906989D01*
X258156D01*
G01X268456Y2902455D02*
X268256Y2902589D01*
Y2902855D01*
X268456Y2902989D01*
X268656Y2902855D01*
Y2902589D01*
X268456Y2902455D01*
G01X275256Y2910722D02*
X277656D01*
G01X276456D02*
Y2902722D01*
G01X275256D02*
X277656D01*
G01X282556D02*
Y2910722D01*
X286356D01*
G01X284956Y2906855D02*
X282556D01*
G01X300456Y2910722D02*
Y2902722D01*
G01X298156Y2910722D02*
X302756D01*
G01X306356Y2902722D02*
Y2910722D01*
G01X310556D02*
Y2902722D01*
G01Y2906722D02*
X306356D01*
G01X318456Y2902722D02*
X314456D01*
Y2910722D01*
X318456D01*
G01X316856Y2906855D02*
X314456D01*
G01X330456Y2902722D02*
Y2910722D01*
X332856D01*
X333656Y2910322D01*
X334256Y2909389D01*
X334456Y2908322D01*
X334256Y2907255D01*
X333756Y2906455D01*
X332856Y2906055D01*
X330456D01*
G01X340456Y2910722D02*
Y2902722D01*
G01X338156Y2910722D02*
X342756D01*
G01X346356Y2902722D02*
Y2910722D01*
G01X350556D02*
Y2902722D01*
G01Y2906722D02*
X346356D01*
G01X364456Y2910722D02*
Y2902722D01*
G01X362156Y2910722D02*
X366756D01*
G01X372456Y2902722D02*
X371656Y2902855D01*
X370956Y2903389D01*
X370356Y2904189D01*
X369956Y2905122D01*
X369756Y2906189D01*
Y2907255D01*
X369956Y2908322D01*
X370356Y2909255D01*
X370956Y2910055D01*
X371656Y2910589D01*
X372456Y2910722D01*
X373256Y2910589D01*
X373956Y2910055D01*
X374556Y2909255D01*
X374956Y2908322D01*
X375156Y2907255D01*
Y2906189D01*
X374956Y2905122D01*
X374556Y2904189D01*
X373956Y2903389D01*
X373256Y2902855D01*
X372456Y2902722D01*
G01X380456D02*
X379656Y2902855D01*
X378956Y2903389D01*
X378356Y2904189D01*
X377956Y2905122D01*
X377756Y2906189D01*
Y2907255D01*
X377956Y2908322D01*
X378356Y2909255D01*
X378956Y2910055D01*
X379656Y2910589D01*
X380456Y2910722D01*
X381256Y2910589D01*
X381956Y2910055D01*
X382556Y2909255D01*
X382956Y2908322D01*
X383156Y2907255D01*
Y2906189D01*
X382956Y2905122D01*
X382556Y2904189D01*
X381956Y2903389D01*
X381256Y2902855D01*
X380456Y2902722D01*
G01X386456Y2910722D02*
Y2902722D01*
X390456D01*
G01X395256Y2910722D02*
X397656D01*
G01X396456D02*
Y2902722D01*
G01X395256D02*
X397656D01*
G01X402156D02*
Y2910722D01*
X406756Y2902722D01*
Y2910722D01*
G01X413056Y2906722D02*
X415056D01*
Y2904322D01*
X414456Y2903522D01*
X413756Y2902989D01*
X412756Y2902722D01*
X411756Y2902989D01*
X411056Y2903522D01*
X410456Y2904322D01*
X410056Y2905255D01*
X409856Y2906322D01*
Y2907255D01*
X410056Y2908055D01*
X410456Y2908989D01*
X411056Y2909789D01*
X411656Y2910322D01*
X412456Y2910722D01*
X413156D01*
X413956Y2910455D01*
X414556Y2909922D01*
G01X426356Y2902722D02*
Y2910722D01*
G01X430556D02*
Y2902722D01*
G01Y2906722D02*
X426356D01*
G01X436456Y2902722D02*
X435656Y2902855D01*
X434956Y2903389D01*
X434356Y2904189D01*
X433956Y2905122D01*
X433756Y2906189D01*
Y2907255D01*
X433956Y2908322D01*
X434356Y2909255D01*
X434956Y2910055D01*
X435656Y2910589D01*
X436456Y2910722D01*
X437256Y2910589D01*
X437956Y2910055D01*
X438556Y2909255D01*
X438956Y2908322D01*
X439156Y2907255D01*
Y2906189D01*
X438956Y2905122D01*
X438556Y2904189D01*
X437956Y2903389D01*
X437256Y2902855D01*
X436456Y2902722D01*
G01X442456Y2910722D02*
Y2902722D01*
X446456D01*
G01X454456D02*
X450456D01*
Y2910722D01*
X454456D01*
G01X452856Y2906855D02*
X450456D01*
G01X467256Y2910722D02*
X469656D01*
G01X468456D02*
Y2902722D01*
G01X467256D02*
X469656D01*
G01X474356Y2903788D02*
X475156Y2903122D01*
X476056Y2902722D01*
X476856D01*
X477656Y2903122D01*
X478256Y2903788D01*
X478556Y2904722D01*
X478356Y2905655D01*
X477856Y2906455D01*
X476956Y2906989D01*
X475756Y2907255D01*
X475056Y2907789D01*
X474756Y2908722D01*
X474956Y2909655D01*
X475456Y2910322D01*
X476156Y2910722D01*
X476856D01*
X477556Y2910455D01*
X478156Y2909789D01*
G01X489856Y2902722D02*
Y2910722D01*
X492456Y2904055D01*
X495056Y2910722D01*
Y2902722D01*
G01X497956D02*
X500456Y2910722D01*
X502956Y2902722D01*
G01X502056Y2905522D02*
X498856D01*
G01X506256Y2902722D02*
Y2910722D01*
X508256D01*
X509056Y2910322D01*
X509656Y2909789D01*
X510156Y2908989D01*
X510556Y2908055D01*
X510656Y2906722D01*
X510556Y2905389D01*
X510156Y2904455D01*
X509656Y2903655D01*
X509056Y2903122D01*
X508256Y2902722D01*
X506256D01*
G01X518456D02*
X514456D01*
Y2910722D01*
X518456D01*
G01X516856Y2906855D02*
X514456D01*
G01X533256Y2906989D02*
X533656Y2907389D01*
X533956Y2908055D01*
X534156Y2908989D01*
X533956Y2909789D01*
X533556Y2910322D01*
X532856Y2910722D01*
X530156D01*
Y2902722D01*
X533456D01*
X534156Y2903255D01*
X534556Y2904055D01*
X534756Y2904989D01*
X534556Y2905922D01*
X533956Y2906722D01*
X533256Y2906989D01*
X530156D01*
G01X540456Y2902722D02*
Y2906322D01*
X538456Y2910722D01*
G01X542456D02*
X540456Y2906322D01*
G01X554456Y2902722D02*
Y2910722D01*
X556956D01*
X557756Y2910322D01*
X558256Y2909789D01*
X558456Y2908722D01*
X558256Y2907655D01*
X557656Y2906989D01*
X556956Y2906589D01*
X554456D01*
G01X556956D02*
X558456Y2902722D01*
G01X564456D02*
X563656Y2902855D01*
X562956Y2903389D01*
X562356Y2904189D01*
X561956Y2905122D01*
X561756Y2906189D01*
Y2907255D01*
X561956Y2908322D01*
X562356Y2909255D01*
X562956Y2910055D01*
X563656Y2910589D01*
X564456Y2910722D01*
X565256Y2910589D01*
X565956Y2910055D01*
X566556Y2909255D01*
X566956Y2908322D01*
X567156Y2907255D01*
Y2906189D01*
X566956Y2905122D01*
X566556Y2904189D01*
X565956Y2903389D01*
X565256Y2902855D01*
X564456Y2902722D01*
G01X570256Y2910722D02*
Y2904989D01*
X570656Y2903788D01*
X571456Y2902989D01*
X572456Y2902722D01*
X573456Y2902989D01*
X574256Y2903788D01*
X574656Y2904989D01*
Y2910722D01*
G01X580456D02*
Y2902722D01*
G01X578156Y2910722D02*
X582756D01*
G01X587256D02*
X589656D01*
G01X588456D02*
Y2902722D01*
G01X587256D02*
X589656D01*
G01X594156D02*
Y2910722D01*
X598756Y2902722D01*
Y2910722D01*
G01X605056Y2906722D02*
X607056D01*
Y2904322D01*
X606456Y2903522D01*
X605756Y2902989D01*
X604756Y2902722D01*
X603756Y2902989D01*
X603056Y2903522D01*
X602456Y2904322D01*
X602056Y2905255D01*
X601856Y2906322D01*
Y2907255D01*
X602056Y2908055D01*
X602456Y2908989D01*
X603056Y2909789D01*
X603656Y2910322D01*
X604456Y2910722D01*
X605156D01*
X605956Y2910455D01*
X606556Y2909922D01*
G01X612256Y2901255D02*
X612656Y2902989D01*
G01X626156Y2902722D02*
Y2910722D01*
X630756Y2902722D01*
Y2910722D01*
G01X636456Y2902722D02*
X635656Y2902855D01*
X634956Y2903389D01*
X634356Y2904189D01*
X633956Y2905122D01*
X633756Y2906189D01*
Y2907255D01*
X633956Y2908322D01*
X634356Y2909255D01*
X634956Y2910055D01*
X635656Y2910589D01*
X636456Y2910722D01*
X637256Y2910589D01*
X637956Y2910055D01*
X638556Y2909255D01*
X638956Y2908322D01*
X639156Y2907255D01*
Y2906189D01*
X638956Y2905122D01*
X638556Y2904189D01*
X637956Y2903389D01*
X637256Y2902855D01*
X636456Y2902722D01*
G01X642156D02*
Y2910722D01*
X646756Y2902722D01*
Y2910722D01*
G01X651156Y2905389D02*
X653756D01*
G01X658556Y2902722D02*
Y2910722D01*
X662356D01*
G01X660956Y2906855D02*
X658556D01*
G01X666256Y2910722D02*
Y2904989D01*
X666656Y2903788D01*
X667456Y2902989D01*
X668456Y2902722D01*
X669456Y2902989D01*
X670256Y2903788D01*
X670656Y2904989D01*
Y2910722D01*
G01X674156Y2902722D02*
Y2910722D01*
X678756Y2902722D01*
Y2910722D01*
G01X686656Y2910055D02*
X686056Y2910455D01*
X685356Y2910722D01*
X684556D01*
X683656Y2910322D01*
X682956Y2909655D01*
X682456Y2908855D01*
X682056Y2907522D01*
X681956Y2906322D01*
X682156Y2905122D01*
X682456Y2904322D01*
X683056Y2903522D01*
X683756Y2902989D01*
X684456Y2902722D01*
X685156D01*
X685856Y2902989D01*
X686456Y2903389D01*
X686956Y2903922D01*
G01X692456Y2910722D02*
Y2902722D01*
G01X690156Y2910722D02*
X694756D01*
G01X699256D02*
X701656D01*
G01X700456D02*
Y2902722D01*
G01X699256D02*
X701656D01*
G01X708456D02*
X707656Y2902855D01*
X706956Y2903389D01*
X706356Y2904189D01*
X705956Y2905122D01*
X705756Y2906189D01*
Y2907255D01*
X705956Y2908322D01*
X706356Y2909255D01*
X706956Y2910055D01*
X707656Y2910589D01*
X708456Y2910722D01*
X709256Y2910589D01*
X709956Y2910055D01*
X710556Y2909255D01*
X710956Y2908322D01*
X711156Y2907255D01*
Y2906189D01*
X710956Y2905122D01*
X710556Y2904189D01*
X709956Y2903389D01*
X709256Y2902855D01*
X708456Y2902722D01*
G01X714156D02*
Y2910722D01*
X718756Y2902722D01*
Y2910722D01*
G01X721956Y2902722D02*
X724456Y2910722D01*
X726956Y2902722D01*
G01X726056Y2905522D02*
X722856D01*
G01X730456Y2910722D02*
Y2902722D01*
X734456D01*
G01X746456D02*
Y2910722D01*
X748856D01*
X749656Y2910322D01*
X750256Y2909389D01*
X750456Y2908322D01*
X750256Y2907255D01*
X749756Y2906455D01*
X748856Y2906055D01*
X746456D01*
G01X753956Y2902722D02*
X756456Y2910722D01*
X758956Y2902722D01*
G01X758056Y2905522D02*
X754856D01*
G01X762256Y2902722D02*
Y2910722D01*
X764256D01*
X765056Y2910322D01*
X765656Y2909789D01*
X766156Y2908989D01*
X766556Y2908055D01*
X766656Y2906722D01*
X766556Y2905389D01*
X766156Y2904455D01*
X765656Y2903655D01*
X765056Y2903122D01*
X764256Y2902722D01*
X762256D01*
G01X778356Y2903788D02*
X779156Y2903122D01*
X780056Y2902722D01*
X780856D01*
X781656Y2903122D01*
X782256Y2903788D01*
X782556Y2904722D01*
X782356Y2905655D01*
X781856Y2906455D01*
X780956Y2906989D01*
X779756Y2907255D01*
X779056Y2907789D01*
X778756Y2908722D01*
X778956Y2909655D01*
X779456Y2910322D01*
X780156Y2910722D01*
X780856D01*
X781556Y2910455D01*
X782156Y2909789D01*
G01X787256Y2910722D02*
X789656D01*
G01X788456D02*
Y2902722D01*
G01X787256D02*
X789656D01*
G01X794556Y2910722D02*
X798356D01*
X794556Y2902722D01*
X798356D01*
G01X806456D02*
X802456D01*
Y2910722D01*
X806456D01*
G01X804856Y2906855D02*
X802456D01*
G01X819256Y2910722D02*
X821656D01*
G01X820456D02*
Y2902722D01*
G01X819256D02*
X821656D01*
G01X826356Y2903788D02*
X827156Y2903122D01*
X828056Y2902722D01*
X828856D01*
X829656Y2903122D01*
X830256Y2903788D01*
X830556Y2904722D01*
X830356Y2905655D01*
X829856Y2906455D01*
X828956Y2906989D01*
X827756Y2907255D01*
X827056Y2907789D01*
X826756Y2908722D01*
X826956Y2909655D01*
X827456Y2910322D01*
X828156Y2910722D01*
X828856D01*
X829556Y2910455D01*
X830156Y2909789D01*
G01X844456Y2910722D02*
Y2902722D01*
G01X842156Y2910722D02*
X846756D01*
G01X850356Y2902722D02*
Y2910722D01*
G01X854556D02*
Y2902722D01*
G01Y2906722D02*
X850356D01*
G01X862456Y2902722D02*
X858456D01*
Y2910722D01*
X862456D01*
G01X860856Y2906855D02*
X858456D01*
G01X874456Y2902722D02*
Y2910722D01*
X876856D01*
X877656Y2910322D01*
X878256Y2909389D01*
X878456Y2908322D01*
X878256Y2907255D01*
X877756Y2906455D01*
X876856Y2906055D01*
X874456D01*
G01X882456Y2902722D02*
Y2910722D01*
X884956D01*
X885756Y2910322D01*
X886256Y2909789D01*
X886456Y2908722D01*
X886256Y2907655D01*
X885656Y2906989D01*
X884956Y2906589D01*
X882456D01*
G01X884956D02*
X886456Y2902722D01*
G01X892456D02*
X891656Y2902855D01*
X890956Y2903389D01*
X890356Y2904189D01*
X889956Y2905122D01*
X889756Y2906189D01*
Y2907255D01*
X889956Y2908322D01*
X890356Y2909255D01*
X890956Y2910055D01*
X891656Y2910589D01*
X892456Y2910722D01*
X893256Y2910589D01*
X893956Y2910055D01*
X894556Y2909255D01*
X894956Y2908322D01*
X895156Y2907255D01*
Y2906189D01*
X894956Y2905122D01*
X894556Y2904189D01*
X893956Y2903389D01*
X893256Y2902855D01*
X892456Y2902722D01*
G01X898556D02*
Y2910722D01*
X902356D01*
G01X900956Y2906855D02*
X898556D01*
G01X907256Y2910722D02*
X909656D01*
G01X908456D02*
Y2902722D01*
G01X907256D02*
X909656D01*
G01X914456Y2910722D02*
Y2902722D01*
X918456D01*
G01X926456D02*
X922456D01*
Y2910722D01*
X926456D01*
G01X924856Y2906855D02*
X922456D01*
G01X938356Y2903788D02*
X939156Y2903122D01*
X940056Y2902722D01*
X940856D01*
X941656Y2903122D01*
X942256Y2903788D01*
X942556Y2904722D01*
X942356Y2905655D01*
X941856Y2906455D01*
X940956Y2906989D01*
X939756Y2907255D01*
X939056Y2907789D01*
X938756Y2908722D01*
X938956Y2909655D01*
X939456Y2910322D01*
X940156Y2910722D01*
X940856D01*
X941556Y2910455D01*
X942156Y2909789D01*
G01X947256Y2910722D02*
X949656D01*
G01X948456D02*
Y2902722D01*
G01X947256D02*
X949656D01*
G01X954556Y2910722D02*
X958356D01*
X954556Y2902722D01*
X958356D01*
G01X966456D02*
X962456D01*
Y2910722D01*
X966456D01*
G01X964856Y2906855D02*
X962456D01*
G01X979356Y2905389D02*
X981756D01*
G01X980456Y2907122D02*
Y2903655D01*
G01X994556Y2909389D02*
X995156Y2910189D01*
X995856Y2910589D01*
X996656Y2910722D01*
X997656Y2910455D01*
X998356Y2909789D01*
X998556Y2908989D01*
X998456Y2908188D01*
X998056Y2907522D01*
X996056Y2906189D01*
X995156Y2905255D01*
X994556Y2903922D01*
X994356Y2902722D01*
X998556D01*
G01X1004456Y2910722D02*
X1003656Y2910455D01*
X1003056Y2909789D01*
X1002656Y2908989D01*
X1002356Y2907922D01*
X1002256Y2906722D01*
X1002356Y2905522D01*
X1002656Y2904455D01*
X1003056Y2903655D01*
X1003656Y2902989D01*
X1004456Y2902722D01*
X1005256Y2902989D01*
X1005856Y2903655D01*
X1006256Y2904455D01*
X1006556Y2905522D01*
X1006656Y2906722D01*
X1006556Y2907922D01*
X1006256Y2908989D01*
X1005856Y2909789D01*
X1005256Y2910455D01*
X1004456Y2910722D01*
G01X1009856Y2902722D02*
Y2910722D01*
X1012456Y2904055D01*
X1015056Y2910722D01*
Y2902722D01*
G01X1019256Y2910722D02*
X1021656D01*
G01X1020456D02*
Y2902722D01*
G01X1019256D02*
X1021656D01*
G01X1026456Y2910722D02*
Y2902722D01*
X1030456D01*
G01X257956Y2917722D02*
X260456Y2925722D01*
X262956Y2917722D01*
G01X262056Y2920522D02*
X258856D01*
G01X268456Y2917455D02*
X268256Y2917589D01*
Y2917855D01*
X268456Y2917989D01*
X268656Y2917855D01*
Y2917589D01*
X268456Y2917455D01*
G01X275256Y2925722D02*
X277656D01*
G01X276456D02*
Y2917722D01*
G01X275256D02*
X277656D01*
G01X282556D02*
Y2925722D01*
X286356D01*
G01X284956Y2921855D02*
X282556D01*
G01X300456Y2925722D02*
Y2917722D01*
G01X298156Y2925722D02*
X302756D01*
G01X306356Y2917722D02*
Y2925722D01*
G01X310556D02*
Y2917722D01*
G01Y2921722D02*
X306356D01*
G01X318456Y2917722D02*
X314456D01*
Y2925722D01*
X318456D01*
G01X316856Y2921855D02*
X314456D01*
G01X330456Y2917722D02*
Y2925722D01*
X332856D01*
X333656Y2925322D01*
X334256Y2924389D01*
X334456Y2923322D01*
X334256Y2922255D01*
X333756Y2921455D01*
X332856Y2921055D01*
X330456D01*
G01X340456Y2925722D02*
Y2917722D01*
G01X338156Y2925722D02*
X342756D01*
G01X346356Y2917722D02*
Y2925722D01*
G01X350556D02*
Y2917722D01*
G01Y2921722D02*
X346356D01*
G01X364456Y2925722D02*
Y2917722D01*
G01X362156Y2925722D02*
X366756D01*
G01X372456Y2917722D02*
X371656Y2917855D01*
X370956Y2918389D01*
X370356Y2919189D01*
X369956Y2920122D01*
X369756Y2921189D01*
Y2922255D01*
X369956Y2923322D01*
X370356Y2924255D01*
X370956Y2925055D01*
X371656Y2925589D01*
X372456Y2925722D01*
X373256Y2925589D01*
X373956Y2925055D01*
X374556Y2924255D01*
X374956Y2923322D01*
X375156Y2922255D01*
Y2921189D01*
X374956Y2920122D01*
X374556Y2919189D01*
X373956Y2918389D01*
X373256Y2917855D01*
X372456Y2917722D01*
G01X380456D02*
X379656Y2917855D01*
X378956Y2918389D01*
X378356Y2919189D01*
X377956Y2920122D01*
X377756Y2921189D01*
Y2922255D01*
X377956Y2923322D01*
X378356Y2924255D01*
X378956Y2925055D01*
X379656Y2925589D01*
X380456Y2925722D01*
X381256Y2925589D01*
X381956Y2925055D01*
X382556Y2924255D01*
X382956Y2923322D01*
X383156Y2922255D01*
Y2921189D01*
X382956Y2920122D01*
X382556Y2919189D01*
X381956Y2918389D01*
X381256Y2917855D01*
X380456Y2917722D01*
G01X386456Y2925722D02*
Y2917722D01*
X390456D01*
G01X395256Y2925722D02*
X397656D01*
G01X396456D02*
Y2917722D01*
G01X395256D02*
X397656D01*
G01X402156D02*
Y2925722D01*
X406756Y2917722D01*
Y2925722D01*
G01X413056Y2921722D02*
X415056D01*
Y2919322D01*
X414456Y2918522D01*
X413756Y2917989D01*
X412756Y2917722D01*
X411756Y2917989D01*
X411056Y2918522D01*
X410456Y2919322D01*
X410056Y2920255D01*
X409856Y2921322D01*
Y2922255D01*
X410056Y2923055D01*
X410456Y2923989D01*
X411056Y2924789D01*
X411656Y2925322D01*
X412456Y2925722D01*
X413156D01*
X413956Y2925455D01*
X414556Y2924922D01*
G01X426356Y2917722D02*
Y2925722D01*
G01X430556D02*
Y2917722D01*
G01Y2921722D02*
X426356D01*
G01X436456Y2917722D02*
X435656Y2917855D01*
X434956Y2918389D01*
X434356Y2919189D01*
X433956Y2920122D01*
X433756Y2921189D01*
Y2922255D01*
X433956Y2923322D01*
X434356Y2924255D01*
X434956Y2925055D01*
X435656Y2925589D01*
X436456Y2925722D01*
X437256Y2925589D01*
X437956Y2925055D01*
X438556Y2924255D01*
X438956Y2923322D01*
X439156Y2922255D01*
Y2921189D01*
X438956Y2920122D01*
X438556Y2919189D01*
X437956Y2918389D01*
X437256Y2917855D01*
X436456Y2917722D01*
G01X442456Y2925722D02*
Y2917722D01*
X446456D01*
G01X454456D02*
X450456D01*
Y2925722D01*
X454456D01*
G01X452856Y2921855D02*
X450456D01*
G01X467256Y2925722D02*
X469656D01*
G01X468456D02*
Y2917722D01*
G01X467256D02*
X469656D01*
G01X474356Y2918788D02*
X475156Y2918122D01*
X476056Y2917722D01*
X476856D01*
X477656Y2918122D01*
X478256Y2918788D01*
X478556Y2919722D01*
X478356Y2920655D01*
X477856Y2921455D01*
X476956Y2921989D01*
X475756Y2922255D01*
X475056Y2922789D01*
X474756Y2923722D01*
X474956Y2924655D01*
X475456Y2925322D01*
X476156Y2925722D01*
X476856D01*
X477556Y2925455D01*
X478156Y2924789D01*
G01X489856Y2917722D02*
Y2925722D01*
X492456Y2919055D01*
X495056Y2925722D01*
Y2917722D01*
G01X497956D02*
X500456Y2925722D01*
X502956Y2917722D01*
G01X502056Y2920522D02*
X498856D01*
G01X506256Y2917722D02*
Y2925722D01*
X508256D01*
X509056Y2925322D01*
X509656Y2924789D01*
X510156Y2923989D01*
X510556Y2923055D01*
X510656Y2921722D01*
X510556Y2920389D01*
X510156Y2919455D01*
X509656Y2918655D01*
X509056Y2918122D01*
X508256Y2917722D01*
X506256D01*
G01X518456D02*
X514456D01*
Y2925722D01*
X518456D01*
G01X516856Y2921855D02*
X514456D01*
G01X533256Y2921989D02*
X533656Y2922389D01*
X533956Y2923055D01*
X534156Y2923989D01*
X533956Y2924789D01*
X533556Y2925322D01*
X532856Y2925722D01*
X530156D01*
Y2917722D01*
X533456D01*
X534156Y2918255D01*
X534556Y2919055D01*
X534756Y2919989D01*
X534556Y2920922D01*
X533956Y2921722D01*
X533256Y2921989D01*
X530156D01*
G01X540456Y2917722D02*
Y2921322D01*
X538456Y2925722D01*
G01X542456D02*
X540456Y2921322D01*
G01X554256Y2917722D02*
Y2925722D01*
X556256D01*
X557056Y2925322D01*
X557656Y2924789D01*
X558156Y2923989D01*
X558556Y2923055D01*
X558656Y2921722D01*
X558556Y2920389D01*
X558156Y2919455D01*
X557656Y2918655D01*
X557056Y2918122D01*
X556256Y2917722D01*
X554256D01*
G01X562456D02*
Y2925722D01*
X564956D01*
X565756Y2925322D01*
X566256Y2924789D01*
X566456Y2923722D01*
X566256Y2922655D01*
X565656Y2921989D01*
X564956Y2921589D01*
X562456D01*
G01X564956D02*
X566456Y2917722D01*
G01X571256Y2925722D02*
X573656D01*
G01X572456D02*
Y2917722D01*
G01X571256D02*
X573656D01*
G01X578456Y2925722D02*
Y2917722D01*
X582456D01*
G01X586456Y2925722D02*
Y2917722D01*
X590456D01*
G01X595256Y2925722D02*
X597656D01*
G01X596456D02*
Y2917722D01*
G01X595256D02*
X597656D01*
G01X602156D02*
Y2925722D01*
X606756Y2917722D01*
Y2925722D01*
G01X613056Y2921722D02*
X615056D01*
Y2919322D01*
X614456Y2918522D01*
X613756Y2917989D01*
X612756Y2917722D01*
X611756Y2917989D01*
X611056Y2918522D01*
X610456Y2919322D01*
X610056Y2920255D01*
X609856Y2921322D01*
Y2922255D01*
X610056Y2923055D01*
X610456Y2923989D01*
X611056Y2924789D01*
X611656Y2925322D01*
X612456Y2925722D01*
X613156D01*
X613956Y2925455D01*
X614556Y2924922D01*
G01X620256Y2916255D02*
X620656Y2917989D01*
G01X634156Y2917722D02*
Y2925722D01*
X638756Y2917722D01*
Y2925722D01*
G01X644456Y2917722D02*
X643656Y2917855D01*
X642956Y2918389D01*
X642356Y2919189D01*
X641956Y2920122D01*
X641756Y2921189D01*
Y2922255D01*
X641956Y2923322D01*
X642356Y2924255D01*
X642956Y2925055D01*
X643656Y2925589D01*
X644456Y2925722D01*
X645256Y2925589D01*
X645956Y2925055D01*
X646556Y2924255D01*
X646956Y2923322D01*
X647156Y2922255D01*
Y2921189D01*
X646956Y2920122D01*
X646556Y2919189D01*
X645956Y2918389D01*
X645256Y2917855D01*
X644456Y2917722D01*
G01X650156D02*
Y2925722D01*
X654756Y2917722D01*
Y2925722D01*
G01X659156Y2920389D02*
X661756D01*
G01X666556Y2917722D02*
Y2925722D01*
X670356D01*
G01X668956Y2921855D02*
X666556D01*
G01X674256Y2925722D02*
Y2919989D01*
X674656Y2918788D01*
X675456Y2917989D01*
X676456Y2917722D01*
X677456Y2917989D01*
X678256Y2918788D01*
X678656Y2919989D01*
Y2925722D01*
G01X682156Y2917722D02*
Y2925722D01*
X686756Y2917722D01*
Y2925722D01*
G01X694656Y2925055D02*
X694056Y2925455D01*
X693356Y2925722D01*
X692556D01*
X691656Y2925322D01*
X690956Y2924655D01*
X690456Y2923855D01*
X690056Y2922522D01*
X689956Y2921322D01*
X690156Y2920122D01*
X690456Y2919322D01*
X691056Y2918522D01*
X691756Y2917989D01*
X692456Y2917722D01*
X693156D01*
X693856Y2917989D01*
X694456Y2918389D01*
X694956Y2918922D01*
G01X700456Y2925722D02*
Y2917722D01*
G01X698156Y2925722D02*
X702756D01*
G01X707256D02*
X709656D01*
G01X708456D02*
Y2917722D01*
G01X707256D02*
X709656D01*
G01X716456D02*
X715656Y2917855D01*
X714956Y2918389D01*
X714356Y2919189D01*
X713956Y2920122D01*
X713756Y2921189D01*
Y2922255D01*
X713956Y2923322D01*
X714356Y2924255D01*
X714956Y2925055D01*
X715656Y2925589D01*
X716456Y2925722D01*
X717256Y2925589D01*
X717956Y2925055D01*
X718556Y2924255D01*
X718956Y2923322D01*
X719156Y2922255D01*
Y2921189D01*
X718956Y2920122D01*
X718556Y2919189D01*
X717956Y2918389D01*
X717256Y2917855D01*
X716456Y2917722D01*
G01X722156D02*
Y2925722D01*
X726756Y2917722D01*
Y2925722D01*
G01X729956Y2917722D02*
X732456Y2925722D01*
X734956Y2917722D01*
G01X734056Y2920522D02*
X730856D01*
G01X738456Y2925722D02*
Y2917722D01*
X742456D01*
G01X754456D02*
Y2925722D01*
X756856D01*
X757656Y2925322D01*
X758256Y2924389D01*
X758456Y2923322D01*
X758256Y2922255D01*
X757756Y2921455D01*
X756856Y2921055D01*
X754456D01*
G01X761956Y2917722D02*
X764456Y2925722D01*
X766956Y2917722D01*
G01X766056Y2920522D02*
X762856D01*
G01X770256Y2917722D02*
Y2925722D01*
X772256D01*
X773056Y2925322D01*
X773656Y2924789D01*
X774156Y2923989D01*
X774556Y2923055D01*
X774656Y2921722D01*
X774556Y2920389D01*
X774156Y2919455D01*
X773656Y2918655D01*
X773056Y2918122D01*
X772256Y2917722D01*
X770256D01*
G01X786356Y2918788D02*
X787156Y2918122D01*
X788056Y2917722D01*
X788856D01*
X789656Y2918122D01*
X790256Y2918788D01*
X790556Y2919722D01*
X790356Y2920655D01*
X789856Y2921455D01*
X788956Y2921989D01*
X787756Y2922255D01*
X787056Y2922789D01*
X786756Y2923722D01*
X786956Y2924655D01*
X787456Y2925322D01*
X788156Y2925722D01*
X788856D01*
X789556Y2925455D01*
X790156Y2924789D01*
G01X795256Y2925722D02*
X797656D01*
G01X796456D02*
Y2917722D01*
G01X795256D02*
X797656D01*
G01X802556Y2925722D02*
X806356D01*
X802556Y2917722D01*
X806356D01*
G01X814456D02*
X810456D01*
Y2925722D01*
X814456D01*
G01X812856Y2921855D02*
X810456D01*
G01X827256Y2925722D02*
X829656D01*
G01X828456D02*
Y2917722D01*
G01X827256D02*
X829656D01*
G01X834356Y2918788D02*
X835156Y2918122D01*
X836056Y2917722D01*
X836856D01*
X837656Y2918122D01*
X838256Y2918788D01*
X838556Y2919722D01*
X838356Y2920655D01*
X837856Y2921455D01*
X836956Y2921989D01*
X835756Y2922255D01*
X835056Y2922789D01*
X834756Y2923722D01*
X834956Y2924655D01*
X835456Y2925322D01*
X836156Y2925722D01*
X836856D01*
X837556Y2925455D01*
X838156Y2924789D01*
G01X852456Y2925722D02*
Y2917722D01*
G01X850156Y2925722D02*
X854756D01*
G01X858356Y2917722D02*
Y2925722D01*
G01X862556D02*
Y2917722D01*
G01Y2921722D02*
X858356D01*
G01X870456Y2917722D02*
X866456D01*
Y2925722D01*
X870456D01*
G01X868856Y2921855D02*
X866456D01*
G01X882256Y2917722D02*
Y2925722D01*
X884256D01*
X885056Y2925322D01*
X885656Y2924789D01*
X886156Y2923989D01*
X886556Y2923055D01*
X886656Y2921722D01*
X886556Y2920389D01*
X886156Y2919455D01*
X885656Y2918655D01*
X885056Y2918122D01*
X884256Y2917722D01*
X882256D01*
G01X890456D02*
Y2925722D01*
X892956D01*
X893756Y2925322D01*
X894256Y2924789D01*
X894456Y2923722D01*
X894256Y2922655D01*
X893656Y2921989D01*
X892956Y2921589D01*
X890456D01*
G01X892956D02*
X894456Y2917722D01*
G01X899256Y2925722D02*
X901656D01*
G01X900456D02*
Y2917722D01*
G01X899256D02*
X901656D01*
G01X906456Y2925722D02*
Y2917722D01*
X910456D01*
G01X914456Y2925722D02*
Y2917722D01*
X918456D01*
G01X930356Y2918788D02*
X931156Y2918122D01*
X932056Y2917722D01*
X932856D01*
X933656Y2918122D01*
X934256Y2918788D01*
X934556Y2919722D01*
X934356Y2920655D01*
X933856Y2921455D01*
X932956Y2921989D01*
X931756Y2922255D01*
X931056Y2922789D01*
X930756Y2923722D01*
X930956Y2924655D01*
X931456Y2925322D01*
X932156Y2925722D01*
X932856D01*
X933556Y2925455D01*
X934156Y2924789D01*
G01X939256Y2925722D02*
X941656D01*
G01X940456D02*
Y2917722D01*
G01X939256D02*
X941656D01*
G01X946556Y2925722D02*
X950356D01*
X946556Y2917722D01*
X950356D01*
G01X958456D02*
X954456D01*
Y2925722D01*
X958456D01*
G01X956856Y2921855D02*
X954456D01*
G01X971356Y2920389D02*
X973756D01*
G01X972456Y2922122D02*
Y2918655D01*
G01X988456Y2917722D02*
Y2925722D01*
X987256Y2924122D01*
G01Y2917722D02*
X989656D01*
G01X996456Y2925722D02*
X995656Y2925455D01*
X995056Y2924789D01*
X994656Y2923989D01*
X994356Y2922922D01*
X994256Y2921722D01*
X994356Y2920522D01*
X994656Y2919455D01*
X995056Y2918655D01*
X995656Y2917989D01*
X996456Y2917722D01*
X997256Y2917989D01*
X997856Y2918655D01*
X998256Y2919455D01*
X998556Y2920522D01*
X998656Y2921722D01*
X998556Y2922922D01*
X998256Y2923989D01*
X997856Y2924789D01*
X997256Y2925455D01*
X996456Y2925722D01*
G01X1001856Y2917722D02*
Y2925722D01*
X1004456Y2919055D01*
X1007056Y2925722D01*
Y2917722D01*
G01X1011256Y2925722D02*
X1013656D01*
G01X1012456D02*
Y2917722D01*
G01X1011256D02*
X1013656D01*
G01X1018456Y2925722D02*
Y2917722D01*
X1022456D01*
G01X251056Y3026722D02*
X253056D01*
Y3024322D01*
X252456Y3023522D01*
X251756Y3022989D01*
X250756Y3022722D01*
X249756Y3022989D01*
X249056Y3023522D01*
X248456Y3024322D01*
X248056Y3025255D01*
X247856Y3026322D01*
Y3027255D01*
X248056Y3028055D01*
X248456Y3028989D01*
X249056Y3029789D01*
X249656Y3030322D01*
X250456Y3030722D01*
X251156D01*
X251956Y3030455D01*
X252556Y3029922D01*
G01X256456Y3022722D02*
Y3030722D01*
X258956D01*
X259756Y3030322D01*
X260256Y3029789D01*
X260456Y3028722D01*
X260256Y3027655D01*
X259656Y3026989D01*
X258956Y3026589D01*
X256456D01*
G01X258956D02*
X260456Y3022722D01*
G01X266456D02*
X265656Y3022855D01*
X264956Y3023389D01*
X264356Y3024189D01*
X263956Y3025122D01*
X263756Y3026189D01*
Y3027255D01*
X263956Y3028322D01*
X264356Y3029255D01*
X264956Y3030055D01*
X265656Y3030589D01*
X266456Y3030722D01*
X267256Y3030589D01*
X267956Y3030055D01*
X268556Y3029255D01*
X268956Y3028322D01*
X269156Y3027255D01*
Y3026189D01*
X268956Y3025122D01*
X268556Y3024189D01*
X267956Y3023389D01*
X267256Y3022855D01*
X266456Y3022722D01*
G01X272256Y3030722D02*
Y3024989D01*
X272656Y3023788D01*
X273456Y3022989D01*
X274456Y3022722D01*
X275456Y3022989D01*
X276256Y3023788D01*
X276656Y3024989D01*
Y3030722D01*
G01X280456Y3022722D02*
Y3030722D01*
X282856D01*
X283656Y3030322D01*
X284256Y3029389D01*
X284456Y3028322D01*
X284256Y3027255D01*
X283756Y3026455D01*
X282856Y3026055D01*
X280456D01*
G01X288356Y3023788D02*
X289156Y3023122D01*
X290056Y3022722D01*
X290856D01*
X291656Y3023122D01*
X292256Y3023788D01*
X292556Y3024722D01*
X292356Y3025655D01*
X291856Y3026455D01*
X290956Y3026989D01*
X289756Y3027255D01*
X289056Y3027789D01*
X288756Y3028722D01*
X288956Y3029655D01*
X289456Y3030322D01*
X290156Y3030722D01*
X290856D01*
X291556Y3030455D01*
X292156Y3029789D01*
G01X303956Y3022722D02*
X306456Y3030722D01*
X308956Y3022722D01*
G01X308056Y3025522D02*
X304856D01*
G01X319956Y3022722D02*
X322456Y3030722D01*
X324956Y3022722D01*
G01X324056Y3025522D02*
X320856D01*
G01X328156Y3022722D02*
Y3030722D01*
X332756Y3022722D01*
Y3030722D01*
G01X336256Y3022722D02*
Y3030722D01*
X338256D01*
X339056Y3030322D01*
X339656Y3029789D01*
X340156Y3028989D01*
X340556Y3028055D01*
X340656Y3026722D01*
X340556Y3025389D01*
X340156Y3024455D01*
X339656Y3023655D01*
X339056Y3023122D01*
X338256Y3022722D01*
X336256D01*
G01X355256Y3026989D02*
X355656Y3027389D01*
X355956Y3028055D01*
X356156Y3028989D01*
X355956Y3029789D01*
X355556Y3030322D01*
X354856Y3030722D01*
X352156D01*
Y3022722D01*
X355456D01*
X356156Y3023255D01*
X356556Y3024055D01*
X356756Y3024989D01*
X356556Y3025922D01*
X355956Y3026722D01*
X355256Y3026989D01*
X352156D01*
G01X362256Y3021255D02*
X362656Y3022989D01*
G01X370456Y3030722D02*
Y3022722D01*
G01X368156Y3030722D02*
X372756D01*
G01X376356Y3022722D02*
Y3030722D01*
G01X380556D02*
Y3022722D01*
G01Y3026722D02*
X376356D01*
G01X388456Y3022722D02*
X384456D01*
Y3030722D01*
X388456D01*
G01X386856Y3026855D02*
X384456D01*
G01X392156Y3022722D02*
Y3030722D01*
X396756Y3022722D01*
Y3030722D01*
G01X411056Y3026722D02*
X413056D01*
Y3024322D01*
X412456Y3023522D01*
X411756Y3022989D01*
X410756Y3022722D01*
X409756Y3022989D01*
X409056Y3023522D01*
X408456Y3024322D01*
X408056Y3025255D01*
X407856Y3026322D01*
Y3027255D01*
X408056Y3028055D01*
X408456Y3028989D01*
X409056Y3029789D01*
X409656Y3030322D01*
X410456Y3030722D01*
X411156D01*
X411956Y3030455D01*
X412556Y3029922D01*
G01X416456Y3022722D02*
Y3030722D01*
X418956D01*
X419756Y3030322D01*
X420256Y3029789D01*
X420456Y3028722D01*
X420256Y3027655D01*
X419656Y3026989D01*
X418956Y3026589D01*
X416456D01*
G01X418956D02*
X420456Y3022722D01*
G01X426456D02*
X425656Y3022855D01*
X424956Y3023389D01*
X424356Y3024189D01*
X423956Y3025122D01*
X423756Y3026189D01*
Y3027255D01*
X423956Y3028322D01*
X424356Y3029255D01*
X424956Y3030055D01*
X425656Y3030589D01*
X426456Y3030722D01*
X427256Y3030589D01*
X427956Y3030055D01*
X428556Y3029255D01*
X428956Y3028322D01*
X429156Y3027255D01*
Y3026189D01*
X428956Y3025122D01*
X428556Y3024189D01*
X427956Y3023389D01*
X427256Y3022855D01*
X426456Y3022722D01*
G01X432256Y3030722D02*
Y3024989D01*
X432656Y3023788D01*
X433456Y3022989D01*
X434456Y3022722D01*
X435456Y3022989D01*
X436256Y3023788D01*
X436656Y3024989D01*
Y3030722D01*
G01X440456Y3022722D02*
Y3030722D01*
X442856D01*
X443656Y3030322D01*
X444256Y3029389D01*
X444456Y3028322D01*
X444256Y3027255D01*
X443756Y3026455D01*
X442856Y3026055D01*
X440456D01*
G01X455956Y3022722D02*
X458456Y3030722D01*
X460956Y3022722D01*
G01X460056Y3025522D02*
X456856D01*
G01X476656Y3030055D02*
X476056Y3030455D01*
X475356Y3030722D01*
X474556D01*
X473656Y3030322D01*
X472956Y3029655D01*
X472456Y3028855D01*
X472056Y3027522D01*
X471956Y3026322D01*
X472156Y3025122D01*
X472456Y3024322D01*
X473056Y3023522D01*
X473756Y3022989D01*
X474456Y3022722D01*
X475156D01*
X475856Y3022989D01*
X476456Y3023389D01*
X476956Y3023922D01*
G01X479956Y3022722D02*
X482456Y3030722D01*
X484956Y3022722D01*
G01X484056Y3025522D02*
X480856D01*
G01X488156Y3022722D02*
Y3030722D01*
X492756Y3022722D01*
Y3030722D01*
G01X507256Y3026989D02*
X507656Y3027389D01*
X507956Y3028055D01*
X508156Y3028989D01*
X507956Y3029789D01*
X507556Y3030322D01*
X506856Y3030722D01*
X504156D01*
Y3022722D01*
X507456D01*
X508156Y3023255D01*
X508556Y3024055D01*
X508756Y3024989D01*
X508556Y3025922D01*
X507956Y3026722D01*
X507256Y3026989D01*
X504156D01*
G01X516456Y3022722D02*
X512456D01*
Y3030722D01*
X516456D01*
G01X514856Y3026855D02*
X512456D01*
G01X528456Y3022722D02*
Y3030722D01*
X530856D01*
X531656Y3030322D01*
X532256Y3029389D01*
X532456Y3028322D01*
X532256Y3027255D01*
X531756Y3026455D01*
X530856Y3026055D01*
X528456D01*
G01X536456Y3030722D02*
Y3022722D01*
X540456D01*
G01X543956D02*
X546456Y3030722D01*
X548956Y3022722D01*
G01X548056Y3025522D02*
X544856D01*
G01X556656Y3030055D02*
X556056Y3030455D01*
X555356Y3030722D01*
X554556D01*
X553656Y3030322D01*
X552956Y3029655D01*
X552456Y3028855D01*
X552056Y3027522D01*
X551956Y3026322D01*
X552156Y3025122D01*
X552456Y3024322D01*
X553056Y3023522D01*
X553756Y3022989D01*
X554456Y3022722D01*
X555156D01*
X555856Y3022989D01*
X556456Y3023389D01*
X556956Y3023922D01*
G01X564456Y3022722D02*
X560456D01*
Y3030722D01*
X564456D01*
G01X562856Y3026855D02*
X560456D01*
G01X568256Y3022722D02*
Y3030722D01*
X570256D01*
X571056Y3030322D01*
X571656Y3029789D01*
X572156Y3028989D01*
X572556Y3028055D01*
X572656Y3026722D01*
X572556Y3025389D01*
X572156Y3024455D01*
X571656Y3023655D01*
X571056Y3023122D01*
X570256Y3022722D01*
X568256D01*
G01X584356Y3023788D02*
X585156Y3023122D01*
X586056Y3022722D01*
X586856D01*
X587656Y3023122D01*
X588256Y3023788D01*
X588556Y3024722D01*
X588356Y3025655D01*
X587856Y3026455D01*
X586956Y3026989D01*
X585756Y3027255D01*
X585056Y3027789D01*
X584756Y3028722D01*
X584956Y3029655D01*
X585456Y3030322D01*
X586156Y3030722D01*
X586856D01*
X587556Y3030455D01*
X588156Y3029789D01*
G01X596456Y3022722D02*
X592456D01*
Y3030722D01*
X596456D01*
G01X594856Y3026855D02*
X592456D01*
G01X600456Y3022722D02*
Y3030722D01*
X602856D01*
X603656Y3030322D01*
X604256Y3029389D01*
X604456Y3028322D01*
X604256Y3027255D01*
X603756Y3026455D01*
X602856Y3026055D01*
X600456D01*
G01X607956Y3022722D02*
X610456Y3030722D01*
X612956Y3022722D01*
G01X612056Y3025522D02*
X608856D01*
G01X616456Y3022722D02*
Y3030722D01*
X618956D01*
X619756Y3030322D01*
X620256Y3029789D01*
X620456Y3028722D01*
X620256Y3027655D01*
X619656Y3026989D01*
X618956Y3026589D01*
X616456D01*
G01X618956D02*
X620456Y3022722D01*
G01X623956D02*
X626456Y3030722D01*
X628956Y3022722D01*
G01X628056Y3025522D02*
X624856D01*
G01X634456Y3030722D02*
Y3022722D01*
G01X632156Y3030722D02*
X636756D01*
G01X644456Y3022722D02*
X640456D01*
Y3030722D01*
X644456D01*
G01X642856Y3026855D02*
X640456D01*
G01X648456Y3030722D02*
Y3022722D01*
X652456D01*
G01X658456D02*
Y3026322D01*
X656456Y3030722D01*
G01X660456D02*
X658456Y3026322D01*
G01X672556Y3022722D02*
Y3030722D01*
X676356D01*
G01X674956Y3026855D02*
X672556D01*
G01X680456Y3022722D02*
Y3030722D01*
X682956D01*
X683756Y3030322D01*
X684256Y3029789D01*
X684456Y3028722D01*
X684256Y3027655D01*
X683656Y3026989D01*
X682956Y3026589D01*
X680456D01*
G01X682956D02*
X684456Y3022722D01*
G01X690456D02*
X689656Y3022855D01*
X688956Y3023389D01*
X688356Y3024189D01*
X687956Y3025122D01*
X687756Y3026189D01*
Y3027255D01*
X687956Y3028322D01*
X688356Y3029255D01*
X688956Y3030055D01*
X689656Y3030589D01*
X690456Y3030722D01*
X691256Y3030589D01*
X691956Y3030055D01*
X692556Y3029255D01*
X692956Y3028322D01*
X693156Y3027255D01*
Y3026189D01*
X692956Y3025122D01*
X692556Y3024189D01*
X691956Y3023389D01*
X691256Y3022855D01*
X690456Y3022722D01*
G01X695856D02*
Y3030722D01*
X698456Y3024055D01*
X701056Y3030722D01*
Y3022722D01*
G01X715056Y3026722D02*
X717056D01*
Y3024322D01*
X716456Y3023522D01*
X715756Y3022989D01*
X714756Y3022722D01*
X713756Y3022989D01*
X713056Y3023522D01*
X712456Y3024322D01*
X712056Y3025255D01*
X711856Y3026322D01*
Y3027255D01*
X712056Y3028055D01*
X712456Y3028989D01*
X713056Y3029789D01*
X713656Y3030322D01*
X714456Y3030722D01*
X715156D01*
X715956Y3030455D01*
X716556Y3029922D01*
G01X720456Y3022722D02*
Y3030722D01*
X722956D01*
X723756Y3030322D01*
X724256Y3029789D01*
X724456Y3028722D01*
X724256Y3027655D01*
X723656Y3026989D01*
X722956Y3026589D01*
X720456D01*
G01X722956D02*
X724456Y3022722D01*
G01X730456D02*
X729656Y3022855D01*
X728956Y3023389D01*
X728356Y3024189D01*
X727956Y3025122D01*
X727756Y3026189D01*
Y3027255D01*
X727956Y3028322D01*
X728356Y3029255D01*
X728956Y3030055D01*
X729656Y3030589D01*
X730456Y3030722D01*
X731256Y3030589D01*
X731956Y3030055D01*
X732556Y3029255D01*
X732956Y3028322D01*
X733156Y3027255D01*
Y3026189D01*
X732956Y3025122D01*
X732556Y3024189D01*
X731956Y3023389D01*
X731256Y3022855D01*
X730456Y3022722D01*
G01X736256Y3030722D02*
Y3024989D01*
X736656Y3023788D01*
X737456Y3022989D01*
X738456Y3022722D01*
X739456Y3022989D01*
X740256Y3023788D01*
X740656Y3024989D01*
Y3030722D01*
G01X744456Y3022722D02*
Y3030722D01*
X746856D01*
X747656Y3030322D01*
X748256Y3029389D01*
X748456Y3028322D01*
X748256Y3027255D01*
X747756Y3026455D01*
X746856Y3026055D01*
X744456D01*
G01X763256Y3026989D02*
X763656Y3027389D01*
X763956Y3028055D01*
X764156Y3028989D01*
X763956Y3029789D01*
X763556Y3030322D01*
X762856Y3030722D01*
X760156D01*
Y3022722D01*
X763456D01*
X764156Y3023255D01*
X764556Y3024055D01*
X764756Y3024989D01*
X764556Y3025922D01*
X763956Y3026722D01*
X763256Y3026989D01*
X760156D01*
G01X770456Y3022455D02*
X770256Y3022589D01*
Y3022855D01*
X770456Y3022989D01*
X770656Y3022855D01*
Y3022589D01*
X770456Y3022455D01*
G01X250456Y3045722D02*
Y3037722D01*
G01X248156Y3045722D02*
X252756D01*
G01X258456Y3037722D02*
X257656Y3037855D01*
X256956Y3038389D01*
X256356Y3039189D01*
X255956Y3040122D01*
X255756Y3041189D01*
Y3042255D01*
X255956Y3043322D01*
X256356Y3044255D01*
X256956Y3045055D01*
X257656Y3045589D01*
X258456Y3045722D01*
X259256Y3045589D01*
X259956Y3045055D01*
X260556Y3044255D01*
X260956Y3043322D01*
X261156Y3042255D01*
Y3041189D01*
X260956Y3040122D01*
X260556Y3039189D01*
X259956Y3038389D01*
X259256Y3037855D01*
X258456Y3037722D01*
G01X274456Y3045722D02*
Y3037722D01*
G01X272156Y3045722D02*
X276756D01*
G01X280356Y3037722D02*
Y3045722D01*
G01X284556D02*
Y3037722D01*
G01Y3041722D02*
X280356D01*
G01X292456Y3037722D02*
X288456D01*
Y3045722D01*
X292456D01*
G01X290856Y3041855D02*
X288456D01*
G01X307256Y3041989D02*
X307656Y3042389D01*
X307956Y3043055D01*
X308156Y3043989D01*
X307956Y3044789D01*
X307556Y3045322D01*
X306856Y3045722D01*
X304156D01*
Y3037722D01*
X307456D01*
X308156Y3038255D01*
X308556Y3039055D01*
X308756Y3039989D01*
X308556Y3040922D01*
X307956Y3041722D01*
X307256Y3041989D01*
X304156D01*
G01X314456Y3037722D02*
X313656Y3037855D01*
X312956Y3038389D01*
X312356Y3039189D01*
X311956Y3040122D01*
X311756Y3041189D01*
Y3042255D01*
X311956Y3043322D01*
X312356Y3044255D01*
X312956Y3045055D01*
X313656Y3045589D01*
X314456Y3045722D01*
X315256Y3045589D01*
X315956Y3045055D01*
X316556Y3044255D01*
X316956Y3043322D01*
X317156Y3042255D01*
Y3041189D01*
X316956Y3040122D01*
X316556Y3039189D01*
X315956Y3038389D01*
X315256Y3037855D01*
X314456Y3037722D01*
G01X319956D02*
X322456Y3045722D01*
X324956Y3037722D01*
G01X324056Y3040522D02*
X320856D01*
G01X328456Y3037722D02*
Y3045722D01*
X330956D01*
X331756Y3045322D01*
X332256Y3044789D01*
X332456Y3043722D01*
X332256Y3042655D01*
X331656Y3041989D01*
X330956Y3041589D01*
X328456D01*
G01X330956D02*
X332456Y3037722D01*
G01X336256D02*
Y3045722D01*
X338256D01*
X339056Y3045322D01*
X339656Y3044789D01*
X340156Y3043989D01*
X340556Y3043055D01*
X340656Y3041722D01*
X340556Y3040389D01*
X340156Y3039455D01*
X339656Y3038655D01*
X339056Y3038122D01*
X338256Y3037722D01*
X336256D01*
G01X356656Y3045055D02*
X356056Y3045455D01*
X355356Y3045722D01*
X354556D01*
X353656Y3045322D01*
X352956Y3044655D01*
X352456Y3043855D01*
X352056Y3042522D01*
X351956Y3041322D01*
X352156Y3040122D01*
X352456Y3039322D01*
X353056Y3038522D01*
X353756Y3037989D01*
X354456Y3037722D01*
X355156D01*
X355856Y3037989D01*
X356456Y3038389D01*
X356956Y3038922D01*
G01X362456Y3037722D02*
X361656Y3037855D01*
X360956Y3038389D01*
X360356Y3039189D01*
X359956Y3040122D01*
X359756Y3041189D01*
Y3042255D01*
X359956Y3043322D01*
X360356Y3044255D01*
X360956Y3045055D01*
X361656Y3045589D01*
X362456Y3045722D01*
X363256Y3045589D01*
X363956Y3045055D01*
X364556Y3044255D01*
X364956Y3043322D01*
X365156Y3042255D01*
Y3041189D01*
X364956Y3040122D01*
X364556Y3039189D01*
X363956Y3038389D01*
X363256Y3037855D01*
X362456Y3037722D01*
G01X368256Y3045722D02*
Y3039989D01*
X368656Y3038788D01*
X369456Y3037989D01*
X370456Y3037722D01*
X371456Y3037989D01*
X372256Y3038788D01*
X372656Y3039989D01*
Y3045722D01*
G01X376456Y3037722D02*
Y3045722D01*
X378856D01*
X379656Y3045322D01*
X380256Y3044389D01*
X380456Y3043322D01*
X380256Y3042255D01*
X379756Y3041455D01*
X378856Y3041055D01*
X376456D01*
G01X386456Y3037722D02*
X385656Y3037855D01*
X384956Y3038389D01*
X384356Y3039189D01*
X383956Y3040122D01*
X383756Y3041189D01*
Y3042255D01*
X383956Y3043322D01*
X384356Y3044255D01*
X384956Y3045055D01*
X385656Y3045589D01*
X386456Y3045722D01*
X387256Y3045589D01*
X387956Y3045055D01*
X388556Y3044255D01*
X388956Y3043322D01*
X389156Y3042255D01*
Y3041189D01*
X388956Y3040122D01*
X388556Y3039189D01*
X387956Y3038389D01*
X387256Y3037855D01*
X386456Y3037722D01*
G01X392156D02*
Y3045722D01*
X396756Y3037722D01*
Y3045722D01*
G01X400356Y3038788D02*
X401156Y3038122D01*
X402056Y3037722D01*
X402856D01*
X403656Y3038122D01*
X404256Y3038788D01*
X404556Y3039722D01*
X404356Y3040655D01*
X403856Y3041455D01*
X402956Y3041989D01*
X401756Y3042255D01*
X401056Y3042789D01*
X400756Y3043722D01*
X400956Y3044655D01*
X401456Y3045322D01*
X402156Y3045722D01*
X402856D01*
X403556Y3045455D01*
X404156Y3044789D01*
G01X410456Y3037455D02*
X410256Y3037589D01*
Y3037855D01*
X410456Y3037989D01*
X410656Y3037855D01*
Y3037589D01*
X410456Y3037455D01*
G01X417256Y3045722D02*
X419656D01*
G01X418456D02*
Y3037722D01*
G01X417256D02*
X419656D01*
G01X424556D02*
Y3045722D01*
X428356D01*
G01X426956Y3041855D02*
X424556D01*
G01X441256Y3045722D02*
X443656D01*
G01X442456D02*
Y3037722D01*
G01X441256D02*
X443656D01*
G01X450456Y3045722D02*
Y3037722D01*
G01X448156Y3045722D02*
X452756D01*
G01X465256D02*
X467656D01*
G01X466456D02*
Y3037722D01*
G01X465256D02*
X467656D01*
G01X472356Y3038788D02*
X473156Y3038122D01*
X474056Y3037722D01*
X474856D01*
X475656Y3038122D01*
X476256Y3038788D01*
X476556Y3039722D01*
X476356Y3040655D01*
X475856Y3041455D01*
X474956Y3041989D01*
X473756Y3042255D01*
X473056Y3042789D01*
X472756Y3043722D01*
X472956Y3044655D01*
X473456Y3045322D01*
X474156Y3045722D01*
X474856D01*
X475556Y3045455D01*
X476156Y3044789D01*
G01X488156Y3037722D02*
Y3045722D01*
X492756Y3037722D01*
Y3045722D01*
G01X498456Y3037722D02*
X497656Y3037855D01*
X496956Y3038389D01*
X496356Y3039189D01*
X495956Y3040122D01*
X495756Y3041189D01*
Y3042255D01*
X495956Y3043322D01*
X496356Y3044255D01*
X496956Y3045055D01*
X497656Y3045589D01*
X498456Y3045722D01*
X499256Y3045589D01*
X499956Y3045055D01*
X500556Y3044255D01*
X500956Y3043322D01*
X501156Y3042255D01*
Y3041189D01*
X500956Y3040122D01*
X500556Y3039189D01*
X499956Y3038389D01*
X499256Y3037855D01*
X498456Y3037722D01*
G01X506456Y3045722D02*
Y3037722D01*
G01X504156Y3045722D02*
X508756D01*
G01X520456Y3037722D02*
Y3045722D01*
X522856D01*
X523656Y3045322D01*
X524256Y3044389D01*
X524456Y3043322D01*
X524256Y3042255D01*
X523756Y3041455D01*
X522856Y3041055D01*
X520456D01*
G01X530456Y3037722D02*
X529656Y3037855D01*
X528956Y3038389D01*
X528356Y3039189D01*
X527956Y3040122D01*
X527756Y3041189D01*
Y3042255D01*
X527956Y3043322D01*
X528356Y3044255D01*
X528956Y3045055D01*
X529656Y3045589D01*
X530456Y3045722D01*
X531256Y3045589D01*
X531956Y3045055D01*
X532556Y3044255D01*
X532956Y3043322D01*
X533156Y3042255D01*
Y3041189D01*
X532956Y3040122D01*
X532556Y3039189D01*
X531956Y3038389D01*
X531256Y3037855D01*
X530456Y3037722D01*
G01X536356Y3038788D02*
X537156Y3038122D01*
X538056Y3037722D01*
X538856D01*
X539656Y3038122D01*
X540256Y3038788D01*
X540556Y3039722D01*
X540356Y3040655D01*
X539856Y3041455D01*
X538956Y3041989D01*
X537756Y3042255D01*
X537056Y3042789D01*
X536756Y3043722D01*
X536956Y3044655D01*
X537456Y3045322D01*
X538156Y3045722D01*
X538856D01*
X539556Y3045455D01*
X540156Y3044789D01*
G01X544356Y3038788D02*
X545156Y3038122D01*
X546056Y3037722D01*
X546856D01*
X547656Y3038122D01*
X548256Y3038788D01*
X548556Y3039722D01*
X548356Y3040655D01*
X547856Y3041455D01*
X546956Y3041989D01*
X545756Y3042255D01*
X545056Y3042789D01*
X544756Y3043722D01*
X544956Y3044655D01*
X545456Y3045322D01*
X546156Y3045722D01*
X546856D01*
X547556Y3045455D01*
X548156Y3044789D01*
G01X553256Y3045722D02*
X555656D01*
G01X554456D02*
Y3037722D01*
G01X553256D02*
X555656D01*
G01X563256Y3041989D02*
X563656Y3042389D01*
X563956Y3043055D01*
X564156Y3043989D01*
X563956Y3044789D01*
X563556Y3045322D01*
X562856Y3045722D01*
X560156D01*
Y3037722D01*
X563456D01*
X564156Y3038255D01*
X564556Y3039055D01*
X564756Y3039989D01*
X564556Y3040922D01*
X563956Y3041722D01*
X563256Y3041989D01*
X560156D01*
G01X568456Y3045722D02*
Y3037722D01*
X572456D01*
G01X580456D02*
X576456D01*
Y3045722D01*
X580456D01*
G01X578856Y3041855D02*
X576456D01*
G01X594456Y3045722D02*
Y3037722D01*
G01X592156Y3045722D02*
X596756D01*
G01X602456Y3037722D02*
X601656Y3037855D01*
X600956Y3038389D01*
X600356Y3039189D01*
X599956Y3040122D01*
X599756Y3041189D01*
Y3042255D01*
X599956Y3043322D01*
X600356Y3044255D01*
X600956Y3045055D01*
X601656Y3045589D01*
X602456Y3045722D01*
X603256Y3045589D01*
X603956Y3045055D01*
X604556Y3044255D01*
X604956Y3043322D01*
X605156Y3042255D01*
Y3041189D01*
X604956Y3040122D01*
X604556Y3039189D01*
X603956Y3038389D01*
X603256Y3037855D01*
X602456Y3037722D01*
G01X616556D02*
Y3045722D01*
X620356D01*
G01X618956Y3041855D02*
X616556D01*
G01X625256Y3045722D02*
X627656D01*
G01X626456D02*
Y3037722D01*
G01X625256D02*
X627656D01*
G01X634456Y3045722D02*
Y3037722D01*
G01X632156Y3045722D02*
X636756D01*
G01X649256D02*
X651656D01*
G01X650456D02*
Y3037722D01*
G01X649256D02*
X651656D01*
G01X656156D02*
Y3045722D01*
X660756Y3037722D01*
Y3045722D01*
G01X674456D02*
Y3037722D01*
G01X672156Y3045722D02*
X676756D01*
G01X680356Y3037722D02*
Y3045722D01*
G01X684556D02*
Y3037722D01*
G01Y3041722D02*
X680356D01*
G01X692456Y3037722D02*
X688456D01*
Y3045722D01*
X692456D01*
G01X690856Y3041855D02*
X688456D01*
G01X704456Y3045722D02*
Y3037722D01*
X708456D01*
G01X714456D02*
X713656Y3037855D01*
X712956Y3038389D01*
X712356Y3039189D01*
X711956Y3040122D01*
X711756Y3041189D01*
Y3042255D01*
X711956Y3043322D01*
X712356Y3044255D01*
X712956Y3045055D01*
X713656Y3045589D01*
X714456Y3045722D01*
X715256Y3045589D01*
X715956Y3045055D01*
X716556Y3044255D01*
X716956Y3043322D01*
X717156Y3042255D01*
Y3041189D01*
X716956Y3040122D01*
X716556Y3039189D01*
X715956Y3038389D01*
X715256Y3037855D01*
X714456Y3037722D01*
G01X724656Y3045055D02*
X724056Y3045455D01*
X723356Y3045722D01*
X722556D01*
X721656Y3045322D01*
X720956Y3044655D01*
X720456Y3043855D01*
X720056Y3042522D01*
X719956Y3041322D01*
X720156Y3040122D01*
X720456Y3039322D01*
X721056Y3038522D01*
X721756Y3037989D01*
X722456Y3037722D01*
X723156D01*
X723856Y3037989D01*
X724456Y3038389D01*
X724956Y3038922D01*
G01X727956Y3037722D02*
X730456Y3045722D01*
X732956Y3037722D01*
G01X732056Y3040522D02*
X728856D01*
G01X738456Y3045722D02*
Y3037722D01*
G01X736156Y3045722D02*
X740756D01*
G01X745256D02*
X747656D01*
G01X746456D02*
Y3037722D01*
G01X745256D02*
X747656D01*
G01X754456D02*
X753656Y3037855D01*
X752956Y3038389D01*
X752356Y3039189D01*
X751956Y3040122D01*
X751756Y3041189D01*
Y3042255D01*
X751956Y3043322D01*
X752356Y3044255D01*
X752956Y3045055D01*
X753656Y3045589D01*
X754456Y3045722D01*
X755256Y3045589D01*
X755956Y3045055D01*
X756556Y3044255D01*
X756956Y3043322D01*
X757156Y3042255D01*
Y3041189D01*
X756956Y3040122D01*
X756556Y3039189D01*
X755956Y3038389D01*
X755256Y3037855D01*
X754456Y3037722D01*
G01X760156D02*
Y3045722D01*
X764756Y3037722D01*
Y3045722D01*
G01X768356Y3038788D02*
X769156Y3038122D01*
X770056Y3037722D01*
X770856D01*
X771656Y3038122D01*
X772256Y3038788D01*
X772556Y3039722D01*
X772356Y3040655D01*
X771856Y3041455D01*
X770956Y3041989D01*
X769756Y3042255D01*
X769056Y3042789D01*
X768756Y3043722D01*
X768956Y3044655D01*
X769456Y3045322D01*
X770156Y3045722D01*
X770856D01*
X771556Y3045455D01*
X772156Y3044789D01*
G01X784556Y3037722D02*
Y3045722D01*
X788356D01*
G01X786956Y3041855D02*
X784556D01*
G01X794456Y3037722D02*
X793656Y3037855D01*
X792956Y3038389D01*
X792356Y3039189D01*
X791956Y3040122D01*
X791756Y3041189D01*
Y3042255D01*
X791956Y3043322D01*
X792356Y3044255D01*
X792956Y3045055D01*
X793656Y3045589D01*
X794456Y3045722D01*
X795256Y3045589D01*
X795956Y3045055D01*
X796556Y3044255D01*
X796956Y3043322D01*
X797156Y3042255D01*
Y3041189D01*
X796956Y3040122D01*
X796556Y3039189D01*
X795956Y3038389D01*
X795256Y3037855D01*
X794456Y3037722D01*
G01X800456D02*
Y3045722D01*
X802956D01*
X803756Y3045322D01*
X804256Y3044789D01*
X804456Y3043722D01*
X804256Y3042655D01*
X803656Y3041989D01*
X802956Y3041589D01*
X800456D01*
G01X802956D02*
X804456Y3037722D01*
G01X819256Y3041989D02*
X819656Y3042389D01*
X819956Y3043055D01*
X820156Y3043989D01*
X819956Y3044789D01*
X819556Y3045322D01*
X818856Y3045722D01*
X816156D01*
Y3037722D01*
X819456D01*
X820156Y3038255D01*
X820556Y3039055D01*
X820756Y3039989D01*
X820556Y3040922D01*
X819956Y3041722D01*
X819256Y3041989D01*
X816156D01*
G01X826456Y3037722D02*
X825656Y3037855D01*
X824956Y3038389D01*
X824356Y3039189D01*
X823956Y3040122D01*
X823756Y3041189D01*
Y3042255D01*
X823956Y3043322D01*
X824356Y3044255D01*
X824956Y3045055D01*
X825656Y3045589D01*
X826456Y3045722D01*
X827256Y3045589D01*
X827956Y3045055D01*
X828556Y3044255D01*
X828956Y3043322D01*
X829156Y3042255D01*
Y3041189D01*
X828956Y3040122D01*
X828556Y3039189D01*
X827956Y3038389D01*
X827256Y3037855D01*
X826456Y3037722D01*
G01X834456Y3045722D02*
Y3037722D01*
G01X832156Y3045722D02*
X836756D01*
G01X840356Y3037722D02*
Y3045722D01*
G01X844556D02*
Y3037722D01*
G01Y3041722D02*
X840356D01*
G01X248456Y3052722D02*
Y3060722D01*
X250856D01*
X251656Y3060322D01*
X252256Y3059389D01*
X252456Y3058322D01*
X252256Y3057255D01*
X251756Y3056455D01*
X250856Y3056055D01*
X248456D01*
G01X256456Y3060722D02*
Y3052722D01*
X260456D01*
G01X268456D02*
X264456D01*
Y3060722D01*
X268456D01*
G01X266856Y3056855D02*
X264456D01*
G01X271956Y3052722D02*
X274456Y3060722D01*
X276956Y3052722D01*
G01X276056Y3055522D02*
X272856D01*
G01X280356Y3053788D02*
X281156Y3053122D01*
X282056Y3052722D01*
X282856D01*
X283656Y3053122D01*
X284256Y3053788D01*
X284556Y3054722D01*
X284356Y3055655D01*
X283856Y3056455D01*
X282956Y3056989D01*
X281756Y3057255D01*
X281056Y3057789D01*
X280756Y3058722D01*
X280956Y3059655D01*
X281456Y3060322D01*
X282156Y3060722D01*
X282856D01*
X283556Y3060455D01*
X284156Y3059789D01*
G01X292456Y3052722D02*
X288456D01*
Y3060722D01*
X292456D01*
G01X290856Y3056855D02*
X288456D01*
G01X304556Y3052722D02*
Y3060722D01*
X308356D01*
G01X306956Y3056855D02*
X304556D01*
G01X314456Y3052722D02*
X313656Y3052855D01*
X312956Y3053389D01*
X312356Y3054189D01*
X311956Y3055122D01*
X311756Y3056189D01*
Y3057255D01*
X311956Y3058322D01*
X312356Y3059255D01*
X312956Y3060055D01*
X313656Y3060589D01*
X314456Y3060722D01*
X315256Y3060589D01*
X315956Y3060055D01*
X316556Y3059255D01*
X316956Y3058322D01*
X317156Y3057255D01*
Y3056189D01*
X316956Y3055122D01*
X316556Y3054189D01*
X315956Y3053389D01*
X315256Y3052855D01*
X314456Y3052722D01*
G01X320456Y3060722D02*
Y3052722D01*
X324456D01*
G01X328456Y3060722D02*
Y3052722D01*
X332456D01*
G01X338456D02*
X337656Y3052855D01*
X336956Y3053389D01*
X336356Y3054189D01*
X335956Y3055122D01*
X335756Y3056189D01*
Y3057255D01*
X335956Y3058322D01*
X336356Y3059255D01*
X336956Y3060055D01*
X337656Y3060589D01*
X338456Y3060722D01*
X339256Y3060589D01*
X339956Y3060055D01*
X340556Y3059255D01*
X340956Y3058322D01*
X341156Y3057255D01*
Y3056189D01*
X340956Y3055122D01*
X340556Y3054189D01*
X339956Y3053389D01*
X339256Y3052855D01*
X338456Y3052722D01*
G01X343456Y3060722D02*
X344856Y3052722D01*
X346456Y3060722D01*
X348056Y3052722D01*
X349456Y3060722D01*
G01X362456D02*
Y3052722D01*
G01X360156Y3060722D02*
X364756D01*
G01X368356Y3052722D02*
Y3060722D01*
G01X372556D02*
Y3052722D01*
G01Y3056722D02*
X368356D01*
G01X380456Y3052722D02*
X376456D01*
Y3060722D01*
X380456D01*
G01X378856Y3056855D02*
X376456D01*
G01X392356Y3053788D02*
X393156Y3053122D01*
X394056Y3052722D01*
X394856D01*
X395656Y3053122D01*
X396256Y3053788D01*
X396556Y3054722D01*
X396356Y3055655D01*
X395856Y3056455D01*
X394956Y3056989D01*
X393756Y3057255D01*
X393056Y3057789D01*
X392756Y3058722D01*
X392956Y3059655D01*
X393456Y3060322D01*
X394156Y3060722D01*
X394856D01*
X395556Y3060455D01*
X396156Y3059789D01*
G01X400456Y3060722D02*
Y3052722D01*
X404456D01*
G01X409256Y3060722D02*
X411656D01*
G01X410456D02*
Y3052722D01*
G01X409256D02*
X411656D01*
G01X416256D02*
Y3060722D01*
X418256D01*
X419056Y3060322D01*
X419656Y3059789D01*
X420156Y3058989D01*
X420556Y3058055D01*
X420656Y3056722D01*
X420556Y3055389D01*
X420156Y3054455D01*
X419656Y3053655D01*
X419056Y3053122D01*
X418256Y3052722D01*
X416256D01*
G01X428456D02*
X424456D01*
Y3060722D01*
X428456D01*
G01X426856Y3056855D02*
X424456D01*
G01X432356Y3053788D02*
X433156Y3053122D01*
X434056Y3052722D01*
X434856D01*
X435656Y3053122D01*
X436256Y3053788D01*
X436556Y3054722D01*
X436356Y3055655D01*
X435856Y3056455D01*
X434956Y3056989D01*
X433756Y3057255D01*
X433056Y3057789D01*
X432756Y3058722D01*
X432956Y3059655D01*
X433456Y3060322D01*
X434156Y3060722D01*
X434856D01*
X435556Y3060455D01*
X436156Y3059789D01*
G01X450456Y3060722D02*
Y3052722D01*
G01X448156Y3060722D02*
X452756D01*
G01X458456Y3052722D02*
X457656Y3052855D01*
X456956Y3053389D01*
X456356Y3054189D01*
X455956Y3055122D01*
X455756Y3056189D01*
Y3057255D01*
X455956Y3058322D01*
X456356Y3059255D01*
X456956Y3060055D01*
X457656Y3060589D01*
X458456Y3060722D01*
X459256Y3060589D01*
X459956Y3060055D01*
X460556Y3059255D01*
X460956Y3058322D01*
X461156Y3057255D01*
Y3056189D01*
X460956Y3055122D01*
X460556Y3054189D01*
X459956Y3053389D01*
X459256Y3052855D01*
X458456Y3052722D01*
G01X475056Y3056722D02*
X477056D01*
Y3054322D01*
X476456Y3053522D01*
X475756Y3052989D01*
X474756Y3052722D01*
X473756Y3052989D01*
X473056Y3053522D01*
X472456Y3054322D01*
X472056Y3055255D01*
X471856Y3056322D01*
Y3057255D01*
X472056Y3058055D01*
X472456Y3058989D01*
X473056Y3059789D01*
X473656Y3060322D01*
X474456Y3060722D01*
X475156D01*
X475956Y3060455D01*
X476556Y3059922D01*
G01X484456Y3052722D02*
X480456D01*
Y3060722D01*
X484456D01*
G01X482856Y3056855D02*
X480456D01*
G01X488156Y3052722D02*
Y3060722D01*
X492756Y3052722D01*
Y3060722D01*
G01X500456Y3052722D02*
X496456D01*
Y3060722D01*
X500456D01*
G01X498856Y3056855D02*
X496456D01*
G01X504456Y3052722D02*
Y3060722D01*
X506956D01*
X507756Y3060322D01*
X508256Y3059789D01*
X508456Y3058722D01*
X508256Y3057655D01*
X507656Y3056989D01*
X506956Y3056589D01*
X504456D01*
G01X506956D02*
X508456Y3052722D01*
G01X511956D02*
X514456Y3060722D01*
X516956Y3052722D01*
G01X516056Y3055522D02*
X512856D01*
G01X522456Y3060722D02*
Y3052722D01*
G01X520156Y3060722D02*
X524756D01*
G01X532456Y3052722D02*
X528456D01*
Y3060722D01*
X532456D01*
G01X530856Y3056855D02*
X528456D01*
G01X546456Y3060722D02*
Y3052722D01*
G01X544156Y3060722D02*
X548756D01*
G01X552356Y3052722D02*
Y3060722D01*
G01X556556D02*
Y3052722D01*
G01Y3056722D02*
X552356D01*
G01X564456Y3052722D02*
X560456D01*
Y3060722D01*
X564456D01*
G01X562856Y3056855D02*
X560456D01*
G01X576456Y3052722D02*
Y3060722D01*
X578856D01*
X579656Y3060322D01*
X580256Y3059389D01*
X580456Y3058322D01*
X580256Y3057255D01*
X579756Y3056455D01*
X578856Y3056055D01*
X576456D01*
G01X583956Y3052722D02*
X586456Y3060722D01*
X588956Y3052722D01*
G01X588056Y3055522D02*
X584856D01*
G01X592256Y3052722D02*
Y3060722D01*
X594256D01*
X595056Y3060322D01*
X595656Y3059789D01*
X596156Y3058989D01*
X596556Y3058055D01*
X596656Y3056722D01*
X596556Y3055389D01*
X596156Y3054455D01*
X595656Y3053655D01*
X595056Y3053122D01*
X594256Y3052722D01*
X592256D01*
G01X600356Y3053788D02*
X601156Y3053122D01*
X602056Y3052722D01*
X602856D01*
X603656Y3053122D01*
X604256Y3053788D01*
X604556Y3054722D01*
X604356Y3055655D01*
X603856Y3056455D01*
X602956Y3056989D01*
X601756Y3057255D01*
X601056Y3057789D01*
X600756Y3058722D01*
X600956Y3059655D01*
X601456Y3060322D01*
X602156Y3060722D01*
X602856D01*
X603556Y3060455D01*
X604156Y3059789D01*
G01X615956Y3052722D02*
X618456Y3060722D01*
X620956Y3052722D01*
G01X620056Y3055522D02*
X616856D01*
G01X624156Y3052722D02*
Y3060722D01*
X628756Y3052722D01*
Y3060722D01*
G01X632256Y3052722D02*
Y3060722D01*
X634256D01*
X635056Y3060322D01*
X635656Y3059789D01*
X636156Y3058989D01*
X636556Y3058055D01*
X636656Y3056722D01*
X636556Y3055389D01*
X636156Y3054455D01*
X635656Y3053655D01*
X635056Y3053122D01*
X634256Y3052722D01*
X632256D01*
G01X647856D02*
Y3060722D01*
X650456Y3054055D01*
X653056Y3060722D01*
Y3052722D01*
G01X655956D02*
X658456Y3060722D01*
X660956Y3052722D01*
G01X660056Y3055522D02*
X656856D01*
G01X664356Y3053788D02*
X665156Y3053122D01*
X666056Y3052722D01*
X666856D01*
X667656Y3053122D01*
X668256Y3053788D01*
X668556Y3054722D01*
X668356Y3055655D01*
X667856Y3056455D01*
X666956Y3056989D01*
X665756Y3057255D01*
X665056Y3057789D01*
X664756Y3058722D01*
X664956Y3059655D01*
X665456Y3060322D01*
X666156Y3060722D01*
X666856D01*
X667556Y3060455D01*
X668156Y3059789D01*
G01X672256Y3052722D02*
Y3060722D01*
G01X676056D02*
X672256Y3055788D01*
G01X676656Y3052722D02*
X673956Y3058055D01*
G01X687956Y3052722D02*
X690456Y3060722D01*
X692956Y3052722D01*
G01X692056Y3055522D02*
X688856D01*
G01X696156Y3052722D02*
Y3060722D01*
X700756Y3052722D01*
Y3060722D01*
G01X704256Y3052722D02*
Y3060722D01*
X706256D01*
X707056Y3060322D01*
X707656Y3059789D01*
X708156Y3058989D01*
X708556Y3058055D01*
X708656Y3056722D01*
X708556Y3055389D01*
X708156Y3054455D01*
X707656Y3053655D01*
X707056Y3053122D01*
X706256Y3052722D01*
X704256D01*
G01X719956D02*
X722456Y3060722D01*
X724956Y3052722D01*
G01X724056Y3055522D02*
X720856D01*
G01X728256Y3052722D02*
Y3060722D01*
X730256D01*
X731056Y3060322D01*
X731656Y3059789D01*
X732156Y3058989D01*
X732556Y3058055D01*
X732656Y3056722D01*
X732556Y3055389D01*
X732156Y3054455D01*
X731656Y3053655D01*
X731056Y3053122D01*
X730256Y3052722D01*
X728256D01*
G01X736256D02*
Y3060722D01*
X738256D01*
X739056Y3060322D01*
X739656Y3059789D01*
X740156Y3058989D01*
X740556Y3058055D01*
X740656Y3056722D01*
X740556Y3055389D01*
X740156Y3054455D01*
X739656Y3053655D01*
X739056Y3053122D01*
X738256Y3052722D01*
X736256D01*
G01X754456Y3060722D02*
Y3052722D01*
G01X752156Y3060722D02*
X756756D01*
G01X760356Y3052722D02*
Y3060722D01*
G01X764556D02*
Y3052722D01*
G01Y3056722D02*
X760356D01*
G01X772456Y3052722D02*
X768456D01*
Y3060722D01*
X772456D01*
G01X770856Y3056855D02*
X768456D01*
G01X786456Y3060722D02*
Y3052722D01*
G01X784156Y3060722D02*
X788756D01*
G01X796456Y3052722D02*
X792456D01*
Y3060722D01*
X796456D01*
G01X794856Y3056855D02*
X792456D01*
G01X800356Y3053788D02*
X801156Y3053122D01*
X802056Y3052722D01*
X802856D01*
X803656Y3053122D01*
X804256Y3053788D01*
X804556Y3054722D01*
X804356Y3055655D01*
X803856Y3056455D01*
X802956Y3056989D01*
X801756Y3057255D01*
X801056Y3057789D01*
X800756Y3058722D01*
X800956Y3059655D01*
X801456Y3060322D01*
X802156Y3060722D01*
X802856D01*
X803556Y3060455D01*
X804156Y3059789D01*
G01X810456Y3060722D02*
Y3052722D01*
G01X808156Y3060722D02*
X812756D01*
G01X824456Y3052722D02*
Y3060722D01*
X826856D01*
X827656Y3060322D01*
X828256Y3059389D01*
X828456Y3058322D01*
X828256Y3057255D01*
X827756Y3056455D01*
X826856Y3056055D01*
X824456D01*
G01X831956Y3052722D02*
X834456Y3060722D01*
X836956Y3052722D01*
G01X836056Y3055522D02*
X832856D01*
G01X840256Y3052722D02*
Y3060722D01*
X842256D01*
X843056Y3060322D01*
X843656Y3059789D01*
X844156Y3058989D01*
X844556Y3058055D01*
X844656Y3056722D01*
X844556Y3055389D01*
X844156Y3054455D01*
X843656Y3053655D01*
X843056Y3053122D01*
X842256Y3052722D01*
X840256D01*
G01X848356Y3053788D02*
X849156Y3053122D01*
X850056Y3052722D01*
X850856D01*
X851656Y3053122D01*
X852256Y3053788D01*
X852556Y3054722D01*
X852356Y3055655D01*
X851856Y3056455D01*
X850956Y3056989D01*
X849756Y3057255D01*
X849056Y3057789D01*
X848756Y3058722D01*
X848956Y3059655D01*
X849456Y3060322D01*
X850156Y3060722D01*
X850856D01*
X851556Y3060455D01*
X852156Y3059789D01*
G01X247956Y3082722D02*
X250456Y3090722D01*
X252956Y3082722D01*
G01X252056Y3085522D02*
X248856D01*
G01X256156Y3082722D02*
Y3090722D01*
X260756Y3082722D01*
Y3090722D01*
G01X266456Y3082722D02*
Y3086322D01*
X264456Y3090722D01*
G01X268456D02*
X266456Y3086322D01*
G01X280456Y3082722D02*
Y3090722D01*
X282856D01*
X283656Y3090322D01*
X284256Y3089389D01*
X284456Y3088322D01*
X284256Y3087255D01*
X283756Y3086455D01*
X282856Y3086055D01*
X280456D01*
G01X288456Y3082722D02*
Y3090722D01*
X290956D01*
X291756Y3090322D01*
X292256Y3089789D01*
X292456Y3088722D01*
X292256Y3087655D01*
X291656Y3086989D01*
X290956Y3086589D01*
X288456D01*
G01X290956D02*
X292456Y3082722D01*
G01X298456D02*
X297656Y3082855D01*
X296956Y3083389D01*
X296356Y3084189D01*
X295956Y3085122D01*
X295756Y3086189D01*
Y3087255D01*
X295956Y3088322D01*
X296356Y3089255D01*
X296956Y3090055D01*
X297656Y3090589D01*
X298456Y3090722D01*
X299256Y3090589D01*
X299956Y3090055D01*
X300556Y3089255D01*
X300956Y3088322D01*
X301156Y3087255D01*
Y3086189D01*
X300956Y3085122D01*
X300556Y3084189D01*
X299956Y3083389D01*
X299256Y3082855D01*
X298456Y3082722D01*
G01X304456D02*
Y3090722D01*
X306856D01*
X307656Y3090322D01*
X308256Y3089389D01*
X308456Y3088322D01*
X308256Y3087255D01*
X307756Y3086455D01*
X306856Y3086055D01*
X304456D01*
G01X314456Y3082722D02*
X313656Y3082855D01*
X312956Y3083389D01*
X312356Y3084189D01*
X311956Y3085122D01*
X311756Y3086189D01*
Y3087255D01*
X311956Y3088322D01*
X312356Y3089255D01*
X312956Y3090055D01*
X313656Y3090589D01*
X314456Y3090722D01*
X315256Y3090589D01*
X315956Y3090055D01*
X316556Y3089255D01*
X316956Y3088322D01*
X317156Y3087255D01*
Y3086189D01*
X316956Y3085122D01*
X316556Y3084189D01*
X315956Y3083389D01*
X315256Y3082855D01*
X314456Y3082722D01*
G01X320356Y3083788D02*
X321156Y3083122D01*
X322056Y3082722D01*
X322856D01*
X323656Y3083122D01*
X324256Y3083788D01*
X324556Y3084722D01*
X324356Y3085655D01*
X323856Y3086455D01*
X322956Y3086989D01*
X321756Y3087255D01*
X321056Y3087789D01*
X320756Y3088722D01*
X320956Y3089655D01*
X321456Y3090322D01*
X322156Y3090722D01*
X322856D01*
X323556Y3090455D01*
X324156Y3089789D01*
G01X332456Y3082722D02*
X328456D01*
Y3090722D01*
X332456D01*
G01X330856Y3086855D02*
X328456D01*
G01X336256Y3082722D02*
Y3090722D01*
X338256D01*
X339056Y3090322D01*
X339656Y3089789D01*
X340156Y3088989D01*
X340556Y3088055D01*
X340656Y3086722D01*
X340556Y3085389D01*
X340156Y3084455D01*
X339656Y3083655D01*
X339056Y3083122D01*
X338256Y3082722D01*
X336256D01*
G01X356656Y3090055D02*
X356056Y3090455D01*
X355356Y3090722D01*
X354556D01*
X353656Y3090322D01*
X352956Y3089655D01*
X352456Y3088855D01*
X352056Y3087522D01*
X351956Y3086322D01*
X352156Y3085122D01*
X352456Y3084322D01*
X353056Y3083522D01*
X353756Y3082989D01*
X354456Y3082722D01*
X355156D01*
X355856Y3082989D01*
X356456Y3083389D01*
X356956Y3083922D01*
G01X360356Y3082722D02*
Y3090722D01*
G01X364556D02*
Y3082722D01*
G01Y3086722D02*
X360356D01*
G01X367956Y3082722D02*
X370456Y3090722D01*
X372956Y3082722D01*
G01X372056Y3085522D02*
X368856D01*
G01X376156Y3082722D02*
Y3090722D01*
X380756Y3082722D01*
Y3090722D01*
G01X387056Y3086722D02*
X389056D01*
Y3084322D01*
X388456Y3083522D01*
X387756Y3082989D01*
X386756Y3082722D01*
X385756Y3082989D01*
X385056Y3083522D01*
X384456Y3084322D01*
X384056Y3085255D01*
X383856Y3086322D01*
Y3087255D01*
X384056Y3088055D01*
X384456Y3088989D01*
X385056Y3089789D01*
X385656Y3090322D01*
X386456Y3090722D01*
X387156D01*
X387956Y3090455D01*
X388556Y3089922D01*
G01X396456Y3082722D02*
X392456D01*
Y3090722D01*
X396456D01*
G01X394856Y3086855D02*
X392456D01*
G01X408456Y3082722D02*
Y3090722D01*
X410956D01*
X411756Y3090322D01*
X412256Y3089789D01*
X412456Y3088722D01*
X412256Y3087655D01*
X411656Y3086989D01*
X410956Y3086589D01*
X408456D01*
G01X410956D02*
X412456Y3082722D01*
G01X420456D02*
X416456D01*
Y3090722D01*
X420456D01*
G01X418856Y3086855D02*
X416456D01*
G01X426456Y3082722D02*
X425656Y3082855D01*
X424956Y3083389D01*
X424356Y3084189D01*
X423956Y3085122D01*
X423756Y3086189D01*
Y3087255D01*
X423956Y3088322D01*
X424356Y3089255D01*
X424956Y3090055D01*
X425656Y3090589D01*
X426456Y3090722D01*
X427256Y3090589D01*
X427956Y3090055D01*
X428556Y3089255D01*
X428956Y3088322D01*
X429156Y3087255D01*
Y3086189D01*
X428956Y3085122D01*
X428556Y3084189D01*
X427956Y3083389D01*
X427256Y3082855D01*
X426456Y3082722D01*
G01X427256Y3084855D02*
X428456Y3082722D01*
G01X432256Y3090722D02*
Y3084989D01*
X432656Y3083788D01*
X433456Y3082989D01*
X434456Y3082722D01*
X435456Y3082989D01*
X436256Y3083788D01*
X436656Y3084989D01*
Y3090722D01*
G01X444456Y3082722D02*
X440456D01*
Y3090722D01*
X444456D01*
G01X442856Y3086855D02*
X440456D01*
G01X448356Y3083788D02*
X449156Y3083122D01*
X450056Y3082722D01*
X450856D01*
X451656Y3083122D01*
X452256Y3083788D01*
X452556Y3084722D01*
X452356Y3085655D01*
X451856Y3086455D01*
X450956Y3086989D01*
X449756Y3087255D01*
X449056Y3087789D01*
X448756Y3088722D01*
X448956Y3089655D01*
X449456Y3090322D01*
X450156Y3090722D01*
X450856D01*
X451556Y3090455D01*
X452156Y3089789D01*
G01X458456Y3090722D02*
Y3082722D01*
G01X456156Y3090722D02*
X460756D01*
G01X471856Y3082722D02*
Y3090722D01*
X474456Y3084055D01*
X477056Y3090722D01*
Y3082722D01*
G01X480256Y3090722D02*
Y3084989D01*
X480656Y3083788D01*
X481456Y3082989D01*
X482456Y3082722D01*
X483456Y3082989D01*
X484256Y3083788D01*
X484656Y3084989D01*
Y3090722D01*
G01X488356Y3083788D02*
X489156Y3083122D01*
X490056Y3082722D01*
X490856D01*
X491656Y3083122D01*
X492256Y3083788D01*
X492556Y3084722D01*
X492356Y3085655D01*
X491856Y3086455D01*
X490956Y3086989D01*
X489756Y3087255D01*
X489056Y3087789D01*
X488756Y3088722D01*
X488956Y3089655D01*
X489456Y3090322D01*
X490156Y3090722D01*
X490856D01*
X491556Y3090455D01*
X492156Y3089789D01*
G01X498456Y3090722D02*
Y3082722D01*
G01X496156Y3090722D02*
X500756D01*
G01X515256Y3086989D02*
X515656Y3087389D01*
X515956Y3088055D01*
X516156Y3088989D01*
X515956Y3089789D01*
X515556Y3090322D01*
X514856Y3090722D01*
X512156D01*
Y3082722D01*
X515456D01*
X516156Y3083255D01*
X516556Y3084055D01*
X516756Y3084989D01*
X516556Y3085922D01*
X515956Y3086722D01*
X515256Y3086989D01*
X512156D01*
G01X524456Y3082722D02*
X520456D01*
Y3090722D01*
X524456D01*
G01X522856Y3086855D02*
X520456D01*
G01X535956Y3082722D02*
X538456Y3090722D01*
X540956Y3082722D01*
G01X540056Y3085522D02*
X536856D01*
G01X544456Y3082722D02*
Y3090722D01*
X546856D01*
X547656Y3090322D01*
X548256Y3089389D01*
X548456Y3088322D01*
X548256Y3087255D01*
X547756Y3086455D01*
X546856Y3086055D01*
X544456D01*
G01X552456Y3082722D02*
Y3090722D01*
X554856D01*
X555656Y3090322D01*
X556256Y3089389D01*
X556456Y3088322D01*
X556256Y3087255D01*
X555756Y3086455D01*
X554856Y3086055D01*
X552456D01*
G01X560456Y3082722D02*
Y3090722D01*
X562956D01*
X563756Y3090322D01*
X564256Y3089789D01*
X564456Y3088722D01*
X564256Y3087655D01*
X563656Y3086989D01*
X562956Y3086589D01*
X560456D01*
G01X562956D02*
X564456Y3082722D01*
G01X570456D02*
X569656Y3082855D01*
X568956Y3083389D01*
X568356Y3084189D01*
X567956Y3085122D01*
X567756Y3086189D01*
Y3087255D01*
X567956Y3088322D01*
X568356Y3089255D01*
X568956Y3090055D01*
X569656Y3090589D01*
X570456Y3090722D01*
X571256Y3090589D01*
X571956Y3090055D01*
X572556Y3089255D01*
X572956Y3088322D01*
X573156Y3087255D01*
Y3086189D01*
X572956Y3085122D01*
X572556Y3084189D01*
X571956Y3083389D01*
X571256Y3082855D01*
X570456Y3082722D01*
G01X575956Y3090722D02*
X578456Y3082722D01*
X580956Y3090722D01*
G01X588456Y3082722D02*
X584456D01*
Y3090722D01*
X588456D01*
G01X586856Y3086855D02*
X584456D01*
G01X592256Y3082722D02*
Y3090722D01*
X594256D01*
X595056Y3090322D01*
X595656Y3089789D01*
X596156Y3088989D01*
X596556Y3088055D01*
X596656Y3086722D01*
X596556Y3085389D01*
X596156Y3084455D01*
X595656Y3083655D01*
X595056Y3083122D01*
X594256Y3082722D01*
X592256D01*
G01X611256Y3086989D02*
X611656Y3087389D01*
X611956Y3088055D01*
X612156Y3088989D01*
X611956Y3089789D01*
X611556Y3090322D01*
X610856Y3090722D01*
X608156D01*
Y3082722D01*
X611456D01*
X612156Y3083255D01*
X612556Y3084055D01*
X612756Y3084989D01*
X612556Y3085922D01*
X611956Y3086722D01*
X611256Y3086989D01*
X608156D01*
G01X618456Y3082722D02*
Y3086322D01*
X616456Y3090722D01*
G01X620456D02*
X618456Y3086322D01*
G01X634456Y3082722D02*
X633656Y3082855D01*
X632956Y3083389D01*
X632356Y3084189D01*
X631956Y3085122D01*
X631756Y3086189D01*
Y3087255D01*
X631956Y3088322D01*
X632356Y3089255D01*
X632956Y3090055D01*
X633656Y3090589D01*
X634456Y3090722D01*
X635256Y3090589D01*
X635956Y3090055D01*
X636556Y3089255D01*
X636956Y3088322D01*
X637156Y3087255D01*
Y3086189D01*
X636956Y3085122D01*
X636556Y3084189D01*
X635956Y3083389D01*
X635256Y3082855D01*
X634456Y3082722D01*
G01X635256Y3084855D02*
X636456Y3082722D01*
G01X640256Y3090722D02*
Y3084989D01*
X640656Y3083788D01*
X641456Y3082989D01*
X642456Y3082722D01*
X643456Y3082989D01*
X644256Y3083788D01*
X644656Y3084989D01*
Y3090722D01*
G01X647956Y3082722D02*
X650456Y3090722D01*
X652956Y3082722D01*
G01X652056Y3085522D02*
X648856D01*
G01X656156Y3082722D02*
Y3090722D01*
X660756Y3082722D01*
Y3090722D01*
G01X666456D02*
Y3082722D01*
G01X664156Y3090722D02*
X668756D01*
G01X671956Y3082722D02*
X674456Y3090722D01*
X676956Y3082722D01*
G01X676056Y3085522D02*
X672856D01*
G01X688456Y3082722D02*
Y3090722D01*
X690856D01*
X691656Y3090322D01*
X692256Y3089389D01*
X692456Y3088322D01*
X692256Y3087255D01*
X691756Y3086455D01*
X690856Y3086055D01*
X688456D01*
G01X696456Y3082722D02*
Y3090722D01*
X698956D01*
X699756Y3090322D01*
X700256Y3089789D01*
X700456Y3088722D01*
X700256Y3087655D01*
X699656Y3086989D01*
X698956Y3086589D01*
X696456D01*
G01X698956D02*
X700456Y3082722D01*
G01X705256Y3090722D02*
X707656D01*
G01X706456D02*
Y3082722D01*
G01X705256D02*
X707656D01*
G01X714456D02*
X713656Y3082855D01*
X712956Y3083389D01*
X712356Y3084189D01*
X711956Y3085122D01*
X711756Y3086189D01*
Y3087255D01*
X711956Y3088322D01*
X712356Y3089255D01*
X712956Y3090055D01*
X713656Y3090589D01*
X714456Y3090722D01*
X715256Y3090589D01*
X715956Y3090055D01*
X716556Y3089255D01*
X716956Y3088322D01*
X717156Y3087255D01*
Y3086189D01*
X716956Y3085122D01*
X716556Y3084189D01*
X715956Y3083389D01*
X715256Y3082855D01*
X714456Y3082722D01*
G01X720456D02*
Y3090722D01*
X722956D01*
X723756Y3090322D01*
X724256Y3089789D01*
X724456Y3088722D01*
X724256Y3087655D01*
X723656Y3086989D01*
X722956Y3086589D01*
X720456D01*
G01X722956D02*
X724456Y3082722D01*
G01X738456Y3090722D02*
Y3082722D01*
G01X736156Y3090722D02*
X740756D01*
G01X746456Y3082722D02*
X745656Y3082855D01*
X744956Y3083389D01*
X744356Y3084189D01*
X743956Y3085122D01*
X743756Y3086189D01*
Y3087255D01*
X743956Y3088322D01*
X744356Y3089255D01*
X744956Y3090055D01*
X745656Y3090589D01*
X746456Y3090722D01*
X747256Y3090589D01*
X747956Y3090055D01*
X748556Y3089255D01*
X748956Y3088322D01*
X749156Y3087255D01*
Y3086189D01*
X748956Y3085122D01*
X748556Y3084189D01*
X747956Y3083389D01*
X747256Y3082855D01*
X746456Y3082722D01*
G01X761256Y3090722D02*
X763656D01*
G01X762456D02*
Y3082722D01*
G01X761256D02*
X763656D01*
G01X770456Y3090722D02*
Y3082722D01*
G01X768156Y3090722D02*
X772756D01*
G01X776356Y3083788D02*
X777156Y3083122D01*
X778056Y3082722D01*
X778856D01*
X779656Y3083122D01*
X780256Y3083788D01*
X780556Y3084722D01*
X780356Y3085655D01*
X779856Y3086455D01*
X778956Y3086989D01*
X777756Y3087255D01*
X777056Y3087789D01*
X776756Y3088722D01*
X776956Y3089655D01*
X777456Y3090322D01*
X778156Y3090722D01*
X778856D01*
X779556Y3090455D01*
X780156Y3089789D01*
G01X793256Y3090722D02*
X795656D01*
G01X794456D02*
Y3082722D01*
G01X793256D02*
X795656D01*
G01X799856D02*
Y3090722D01*
X802456Y3084055D01*
X805056Y3090722D01*
Y3082722D01*
G01X808456D02*
Y3090722D01*
X810856D01*
X811656Y3090322D01*
X812256Y3089389D01*
X812456Y3088322D01*
X812256Y3087255D01*
X811756Y3086455D01*
X810856Y3086055D01*
X808456D01*
G01X816456Y3090722D02*
Y3082722D01*
X820456D01*
G01X828456D02*
X824456D01*
Y3090722D01*
X828456D01*
G01X826856Y3086855D02*
X824456D01*
G01X831856Y3082722D02*
Y3090722D01*
X834456Y3084055D01*
X837056Y3090722D01*
Y3082722D01*
G01X844456D02*
X840456D01*
Y3090722D01*
X844456D01*
G01X842856Y3086855D02*
X840456D01*
G01X848156Y3082722D02*
Y3090722D01*
X852756Y3082722D01*
Y3090722D01*
G01X858456D02*
Y3082722D01*
G01X856156Y3090722D02*
X860756D01*
G01X863956Y3082722D02*
X866456Y3090722D01*
X868956Y3082722D01*
G01X868056Y3085522D02*
X864856D01*
G01X874456Y3090722D02*
Y3082722D01*
G01X872156Y3090722D02*
X876756D01*
G01X881256D02*
X883656D01*
G01X882456D02*
Y3082722D01*
G01X881256D02*
X883656D01*
G01X890456D02*
X889656Y3082855D01*
X888956Y3083389D01*
X888356Y3084189D01*
X887956Y3085122D01*
X887756Y3086189D01*
Y3087255D01*
X887956Y3088322D01*
X888356Y3089255D01*
X888956Y3090055D01*
X889656Y3090589D01*
X890456Y3090722D01*
X891256Y3090589D01*
X891956Y3090055D01*
X892556Y3089255D01*
X892956Y3088322D01*
X893156Y3087255D01*
Y3086189D01*
X892956Y3085122D01*
X892556Y3084189D01*
X891956Y3083389D01*
X891256Y3082855D01*
X890456Y3082722D01*
G01X896156D02*
Y3090722D01*
X900756Y3082722D01*
Y3090722D01*
G01X906456Y3082455D02*
X906256Y3082589D01*
Y3082855D01*
X906456Y3082989D01*
X906656Y3082855D01*
Y3082589D01*
X906456Y3082455D01*
G01X249256Y3105722D02*
X251656D01*
G01X250456D02*
Y3097722D01*
G01X249256D02*
X251656D01*
G01X255856D02*
Y3105722D01*
X258456Y3099055D01*
X261056Y3105722D01*
Y3097722D01*
G01X264456D02*
Y3105722D01*
X266856D01*
X267656Y3105322D01*
X268256Y3104389D01*
X268456Y3103322D01*
X268256Y3102255D01*
X267756Y3101455D01*
X266856Y3101055D01*
X264456D01*
G01X276456Y3097722D02*
X272456D01*
Y3105722D01*
X276456D01*
G01X274856Y3101855D02*
X272456D01*
G01X280256Y3097722D02*
Y3105722D01*
X282256D01*
X283056Y3105322D01*
X283656Y3104789D01*
X284156Y3103989D01*
X284556Y3103055D01*
X284656Y3101722D01*
X284556Y3100389D01*
X284156Y3099455D01*
X283656Y3098655D01*
X283056Y3098122D01*
X282256Y3097722D01*
X280256D01*
G01X287956D02*
X290456Y3105722D01*
X292956Y3097722D01*
G01X292056Y3100522D02*
X288856D01*
G01X296156Y3097722D02*
Y3105722D01*
X300756Y3097722D01*
Y3105722D01*
G01X308656Y3105055D02*
X308056Y3105455D01*
X307356Y3105722D01*
X306556D01*
X305656Y3105322D01*
X304956Y3104655D01*
X304456Y3103855D01*
X304056Y3102522D01*
X303956Y3101322D01*
X304156Y3100122D01*
X304456Y3099322D01*
X305056Y3098522D01*
X305756Y3097989D01*
X306456Y3097722D01*
X307156D01*
X307856Y3097989D01*
X308456Y3098389D01*
X308956Y3098922D01*
G01X316456Y3097722D02*
X312456D01*
Y3105722D01*
X316456D01*
G01X314856Y3101855D02*
X312456D01*
G01X320356Y3098788D02*
X321156Y3098122D01*
X322056Y3097722D01*
X322856D01*
X323656Y3098122D01*
X324256Y3098788D01*
X324556Y3099722D01*
X324356Y3100655D01*
X323856Y3101455D01*
X322956Y3101989D01*
X321756Y3102255D01*
X321056Y3102789D01*
X320756Y3103722D01*
X320956Y3104655D01*
X321456Y3105322D01*
X322156Y3105722D01*
X322856D01*
X323556Y3105455D01*
X324156Y3104789D01*
G01X335956Y3097722D02*
X338456Y3105722D01*
X340956Y3097722D01*
G01X340056Y3100522D02*
X336856D01*
G01X344156Y3097722D02*
Y3105722D01*
X348756Y3097722D01*
Y3105722D01*
G01X352256Y3097722D02*
Y3105722D01*
X354256D01*
X355056Y3105322D01*
X355656Y3104789D01*
X356156Y3103989D01*
X356556Y3103055D01*
X356656Y3101722D01*
X356556Y3100389D01*
X356156Y3099455D01*
X355656Y3098655D01*
X355056Y3098122D01*
X354256Y3097722D01*
X352256D01*
G01X371256Y3101989D02*
X371656Y3102389D01*
X371956Y3103055D01*
X372156Y3103989D01*
X371956Y3104789D01*
X371556Y3105322D01*
X370856Y3105722D01*
X368156D01*
Y3097722D01*
X371456D01*
X372156Y3098255D01*
X372556Y3099055D01*
X372756Y3099989D01*
X372556Y3100922D01*
X371956Y3101722D01*
X371256Y3101989D01*
X368156D01*
G01X378456Y3097722D02*
X377656Y3097855D01*
X376956Y3098389D01*
X376356Y3099189D01*
X375956Y3100122D01*
X375756Y3101189D01*
Y3102255D01*
X375956Y3103322D01*
X376356Y3104255D01*
X376956Y3105055D01*
X377656Y3105589D01*
X378456Y3105722D01*
X379256Y3105589D01*
X379956Y3105055D01*
X380556Y3104255D01*
X380956Y3103322D01*
X381156Y3102255D01*
Y3101189D01*
X380956Y3100122D01*
X380556Y3099189D01*
X379956Y3098389D01*
X379256Y3097855D01*
X378456Y3097722D01*
G01X383956D02*
X386456Y3105722D01*
X388956Y3097722D01*
G01X388056Y3100522D02*
X384856D01*
G01X392456Y3097722D02*
Y3105722D01*
X394956D01*
X395756Y3105322D01*
X396256Y3104789D01*
X396456Y3103722D01*
X396256Y3102655D01*
X395656Y3101989D01*
X394956Y3101589D01*
X392456D01*
G01X394956D02*
X396456Y3097722D01*
G01X400256D02*
Y3105722D01*
X402256D01*
X403056Y3105322D01*
X403656Y3104789D01*
X404156Y3103989D01*
X404556Y3103055D01*
X404656Y3101722D01*
X404556Y3100389D01*
X404156Y3099455D01*
X403656Y3098655D01*
X403056Y3098122D01*
X402256Y3097722D01*
X400256D01*
G01X418456Y3105722D02*
Y3097722D01*
G01X416156Y3105722D02*
X420756D01*
G01X424356Y3097722D02*
Y3105722D01*
G01X428556D02*
Y3097722D01*
G01Y3101722D02*
X424356D01*
G01X433256Y3105722D02*
X435656D01*
G01X434456D02*
Y3097722D01*
G01X433256D02*
X435656D01*
G01X444656Y3105055D02*
X444056Y3105455D01*
X443356Y3105722D01*
X442556D01*
X441656Y3105322D01*
X440956Y3104655D01*
X440456Y3103855D01*
X440056Y3102522D01*
X439956Y3101322D01*
X440156Y3100122D01*
X440456Y3099322D01*
X441056Y3098522D01*
X441756Y3097989D01*
X442456Y3097722D01*
X443156D01*
X443856Y3097989D01*
X444456Y3098389D01*
X444956Y3098922D01*
G01X448256Y3097722D02*
Y3105722D01*
G01X452056D02*
X448256Y3100788D01*
G01X452656Y3097722D02*
X449956Y3103055D01*
G01X456156Y3097722D02*
Y3105722D01*
X460756Y3097722D01*
Y3105722D01*
G01X468456Y3097722D02*
X464456D01*
Y3105722D01*
X468456D01*
G01X466856Y3101855D02*
X464456D01*
G01X472356Y3098788D02*
X473156Y3098122D01*
X474056Y3097722D01*
X474856D01*
X475656Y3098122D01*
X476256Y3098788D01*
X476556Y3099722D01*
X476356Y3100655D01*
X475856Y3101455D01*
X474956Y3101989D01*
X473756Y3102255D01*
X473056Y3102789D01*
X472756Y3103722D01*
X472956Y3104655D01*
X473456Y3105322D01*
X474156Y3105722D01*
X474856D01*
X475556Y3105455D01*
X476156Y3104789D01*
G01X480356Y3098788D02*
X481156Y3098122D01*
X482056Y3097722D01*
X482856D01*
X483656Y3098122D01*
X484256Y3098788D01*
X484556Y3099722D01*
X484356Y3100655D01*
X483856Y3101455D01*
X482956Y3101989D01*
X481756Y3102255D01*
X481056Y3102789D01*
X480756Y3103722D01*
X480956Y3104655D01*
X481456Y3105322D01*
X482156Y3105722D01*
X482856D01*
X483556Y3105455D01*
X484156Y3104789D01*
G01X490456Y3097455D02*
X490256Y3097589D01*
Y3097855D01*
X490456Y3097989D01*
X490656Y3097855D01*
Y3097589D01*
X490456Y3097455D01*
G01X248356Y3113788D02*
X249156Y3113122D01*
X250056Y3112722D01*
X250856D01*
X251656Y3113122D01*
X252256Y3113788D01*
X252556Y3114722D01*
X252356Y3115655D01*
X251856Y3116455D01*
X250956Y3116989D01*
X249756Y3117255D01*
X249056Y3117789D01*
X248756Y3118722D01*
X248956Y3119655D01*
X249456Y3120322D01*
X250156Y3120722D01*
X250856D01*
X251556Y3120455D01*
X252156Y3119789D01*
G01X256456Y3112722D02*
Y3120722D01*
X258856D01*
X259656Y3120322D01*
X260256Y3119389D01*
X260456Y3118322D01*
X260256Y3117255D01*
X259756Y3116455D01*
X258856Y3116055D01*
X256456D01*
G01X263956Y3112722D02*
X266456Y3120722D01*
X268956Y3112722D01*
G01X268056Y3115522D02*
X264856D01*
G01X276656Y3120055D02*
X276056Y3120455D01*
X275356Y3120722D01*
X274556D01*
X273656Y3120322D01*
X272956Y3119655D01*
X272456Y3118855D01*
X272056Y3117522D01*
X271956Y3116322D01*
X272156Y3115122D01*
X272456Y3114322D01*
X273056Y3113522D01*
X273756Y3112989D01*
X274456Y3112722D01*
X275156D01*
X275856Y3112989D01*
X276456Y3113389D01*
X276956Y3113922D01*
G01X281256Y3120722D02*
X283656D01*
G01X282456D02*
Y3112722D01*
G01X281256D02*
X283656D01*
G01X288156D02*
Y3120722D01*
X292756Y3112722D01*
Y3120722D01*
G01X299056Y3116722D02*
X301056D01*
Y3114322D01*
X300456Y3113522D01*
X299756Y3112989D01*
X298756Y3112722D01*
X297756Y3112989D01*
X297056Y3113522D01*
X296456Y3114322D01*
X296056Y3115255D01*
X295856Y3116322D01*
Y3117255D01*
X296056Y3118055D01*
X296456Y3118989D01*
X297056Y3119789D01*
X297656Y3120322D01*
X298456Y3120722D01*
X299156D01*
X299956Y3120455D01*
X300556Y3119922D01*
G01X311956Y3112722D02*
X314456Y3120722D01*
X316956Y3112722D01*
G01X316056Y3115522D02*
X312856D01*
G01X320156Y3112722D02*
Y3120722D01*
X324756Y3112722D01*
Y3120722D01*
G01X328256Y3112722D02*
Y3120722D01*
X330256D01*
X331056Y3120322D01*
X331656Y3119789D01*
X332156Y3118989D01*
X332556Y3118055D01*
X332656Y3116722D01*
X332556Y3115389D01*
X332156Y3114455D01*
X331656Y3113655D01*
X331056Y3113122D01*
X330256Y3112722D01*
X328256D01*
G01X343856D02*
Y3120722D01*
X346456Y3114055D01*
X349056Y3120722D01*
Y3112722D01*
G01X351956D02*
X354456Y3120722D01*
X356956Y3112722D01*
G01X356056Y3115522D02*
X352856D01*
G01X362456Y3120722D02*
Y3112722D01*
G01X360156Y3120722D02*
X364756D01*
G01X372456Y3112722D02*
X368456D01*
Y3120722D01*
X372456D01*
G01X370856Y3116855D02*
X368456D01*
G01X376456Y3112722D02*
Y3120722D01*
X378956D01*
X379756Y3120322D01*
X380256Y3119789D01*
X380456Y3118722D01*
X380256Y3117655D01*
X379656Y3116989D01*
X378956Y3116589D01*
X376456D01*
G01X378956D02*
X380456Y3112722D01*
G01X385256Y3120722D02*
X387656D01*
G01X386456D02*
Y3112722D01*
G01X385256D02*
X387656D01*
G01X391956D02*
X394456Y3120722D01*
X396956Y3112722D01*
G01X396056Y3115522D02*
X392856D01*
G01X400456Y3120722D02*
Y3112722D01*
X404456D01*
G01X416256D02*
Y3120722D01*
X418256D01*
X419056Y3120322D01*
X419656Y3119789D01*
X420156Y3118989D01*
X420556Y3118055D01*
X420656Y3116722D01*
X420556Y3115389D01*
X420156Y3114455D01*
X419656Y3113655D01*
X419056Y3113122D01*
X418256Y3112722D01*
X416256D01*
G01X425256Y3120722D02*
X427656D01*
G01X426456D02*
Y3112722D01*
G01X425256D02*
X427656D01*
G01X436456D02*
X432456D01*
Y3120722D01*
X436456D01*
G01X434856Y3116855D02*
X432456D01*
G01X440456Y3120722D02*
Y3112722D01*
X444456D01*
G01X452456D02*
X448456D01*
Y3120722D01*
X452456D01*
G01X450856Y3116855D02*
X448456D01*
G01X460656Y3120055D02*
X460056Y3120455D01*
X459356Y3120722D01*
X458556D01*
X457656Y3120322D01*
X456956Y3119655D01*
X456456Y3118855D01*
X456056Y3117522D01*
X455956Y3116322D01*
X456156Y3115122D01*
X456456Y3114322D01*
X457056Y3113522D01*
X457756Y3112989D01*
X458456Y3112722D01*
X459156D01*
X459856Y3112989D01*
X460456Y3113389D01*
X460956Y3113922D01*
G01X466456Y3120722D02*
Y3112722D01*
G01X464156Y3120722D02*
X468756D01*
G01X472456Y3112722D02*
Y3120722D01*
X474956D01*
X475756Y3120322D01*
X476256Y3119789D01*
X476456Y3118722D01*
X476256Y3117655D01*
X475656Y3116989D01*
X474956Y3116589D01*
X472456D01*
G01X474956D02*
X476456Y3112722D01*
G01X481256Y3120722D02*
X483656D01*
G01X482456D02*
Y3112722D01*
G01X481256D02*
X483656D01*
G01X492656Y3120055D02*
X492056Y3120455D01*
X491356Y3120722D01*
X490556D01*
X489656Y3120322D01*
X488956Y3119655D01*
X488456Y3118855D01*
X488056Y3117522D01*
X487956Y3116322D01*
X488156Y3115122D01*
X488456Y3114322D01*
X489056Y3113522D01*
X489756Y3112989D01*
X490456Y3112722D01*
X491156D01*
X491856Y3112989D01*
X492456Y3113389D01*
X492956Y3113922D01*
G01X508656Y3120055D02*
X508056Y3120455D01*
X507356Y3120722D01*
X506556D01*
X505656Y3120322D01*
X504956Y3119655D01*
X504456Y3118855D01*
X504056Y3117522D01*
X503956Y3116322D01*
X504156Y3115122D01*
X504456Y3114322D01*
X505056Y3113522D01*
X505756Y3112989D01*
X506456Y3112722D01*
X507156D01*
X507856Y3112989D01*
X508456Y3113389D01*
X508956Y3113922D01*
G01X514456Y3112722D02*
X513656Y3112855D01*
X512956Y3113389D01*
X512356Y3114189D01*
X511956Y3115122D01*
X511756Y3116189D01*
Y3117255D01*
X511956Y3118322D01*
X512356Y3119255D01*
X512956Y3120055D01*
X513656Y3120589D01*
X514456Y3120722D01*
X515256Y3120589D01*
X515956Y3120055D01*
X516556Y3119255D01*
X516956Y3118322D01*
X517156Y3117255D01*
Y3116189D01*
X516956Y3115122D01*
X516556Y3114189D01*
X515956Y3113389D01*
X515256Y3112855D01*
X514456Y3112722D01*
G01X520156D02*
Y3120722D01*
X524756Y3112722D01*
Y3120722D01*
G01X528356Y3113788D02*
X529156Y3113122D01*
X530056Y3112722D01*
X530856D01*
X531656Y3113122D01*
X532256Y3113788D01*
X532556Y3114722D01*
X532356Y3115655D01*
X531856Y3116455D01*
X530956Y3116989D01*
X529756Y3117255D01*
X529056Y3117789D01*
X528756Y3118722D01*
X528956Y3119655D01*
X529456Y3120322D01*
X530156Y3120722D01*
X530856D01*
X531556Y3120455D01*
X532156Y3119789D01*
G01X538456Y3120722D02*
Y3112722D01*
G01X536156Y3120722D02*
X540756D01*
G01X543956Y3112722D02*
X546456Y3120722D01*
X548956Y3112722D01*
G01X548056Y3115522D02*
X544856D01*
G01X552156Y3112722D02*
Y3120722D01*
X556756Y3112722D01*
Y3120722D01*
G01X562456D02*
Y3112722D01*
G01X560156Y3120722D02*
X564756D01*
G01X578456D02*
Y3112722D01*
G01X576156Y3120722D02*
X580756D01*
G01X586456Y3112722D02*
X585656Y3112855D01*
X584956Y3113389D01*
X584356Y3114189D01*
X583956Y3115122D01*
X583756Y3116189D01*
Y3117255D01*
X583956Y3118322D01*
X584356Y3119255D01*
X584956Y3120055D01*
X585656Y3120589D01*
X586456Y3120722D01*
X587256Y3120589D01*
X587956Y3120055D01*
X588556Y3119255D01*
X588956Y3118322D01*
X589156Y3117255D01*
Y3116189D01*
X588956Y3115122D01*
X588556Y3114189D01*
X587956Y3113389D01*
X587256Y3112855D01*
X586456Y3112722D01*
G01X599956D02*
X602456Y3120722D01*
X604956Y3112722D01*
G01X604056Y3115522D02*
X600856D01*
G01X612656Y3120055D02*
X612056Y3120455D01*
X611356Y3120722D01*
X610556D01*
X609656Y3120322D01*
X608956Y3119655D01*
X608456Y3118855D01*
X608056Y3117522D01*
X607956Y3116322D01*
X608156Y3115122D01*
X608456Y3114322D01*
X609056Y3113522D01*
X609756Y3112989D01*
X610456Y3112722D01*
X611156D01*
X611856Y3112989D01*
X612456Y3113389D01*
X612956Y3113922D01*
G01X616356Y3112722D02*
Y3120722D01*
G01X620556D02*
Y3112722D01*
G01Y3116722D02*
X616356D01*
G01X625256Y3120722D02*
X627656D01*
G01X626456D02*
Y3112722D01*
G01X625256D02*
X627656D01*
G01X636456D02*
X632456D01*
Y3120722D01*
X636456D01*
G01X634856Y3116855D02*
X632456D01*
G01X639956Y3120722D02*
X642456Y3112722D01*
X644956Y3120722D01*
G01X652456Y3112722D02*
X648456D01*
Y3120722D01*
X652456D01*
G01X650856Y3116855D02*
X648456D01*
G01X664456Y3112722D02*
Y3120722D01*
X666956D01*
X667756Y3120322D01*
X668256Y3119789D01*
X668456Y3118722D01*
X668256Y3117655D01*
X667656Y3116989D01*
X666956Y3116589D01*
X664456D01*
G01X666956D02*
X668456Y3112722D01*
G01X676456D02*
X672456D01*
Y3120722D01*
X676456D01*
G01X674856Y3116855D02*
X672456D01*
G01X682456Y3112722D02*
X681656Y3112855D01*
X680956Y3113389D01*
X680356Y3114189D01*
X679956Y3115122D01*
X679756Y3116189D01*
Y3117255D01*
X679956Y3118322D01*
X680356Y3119255D01*
X680956Y3120055D01*
X681656Y3120589D01*
X682456Y3120722D01*
X683256Y3120589D01*
X683956Y3120055D01*
X684556Y3119255D01*
X684956Y3118322D01*
X685156Y3117255D01*
Y3116189D01*
X684956Y3115122D01*
X684556Y3114189D01*
X683956Y3113389D01*
X683256Y3112855D01*
X682456Y3112722D01*
G01X683256Y3114855D02*
X684456Y3112722D01*
G01X688256Y3120722D02*
Y3114989D01*
X688656Y3113788D01*
X689456Y3112989D01*
X690456Y3112722D01*
X691456Y3112989D01*
X692256Y3113788D01*
X692656Y3114989D01*
Y3120722D01*
G01X697256D02*
X699656D01*
G01X698456D02*
Y3112722D01*
G01X697256D02*
X699656D01*
G01X704456D02*
Y3120722D01*
X706956D01*
X707756Y3120322D01*
X708256Y3119789D01*
X708456Y3118722D01*
X708256Y3117655D01*
X707656Y3116989D01*
X706956Y3116589D01*
X704456D01*
G01X706956D02*
X708456Y3112722D01*
G01X716456D02*
X712456D01*
Y3120722D01*
X716456D01*
G01X714856Y3116855D02*
X712456D01*
G01X720256Y3112722D02*
Y3120722D01*
X722256D01*
X723056Y3120322D01*
X723656Y3119789D01*
X724156Y3118989D01*
X724556Y3118055D01*
X724656Y3116722D01*
X724556Y3115389D01*
X724156Y3114455D01*
X723656Y3113655D01*
X723056Y3113122D01*
X722256Y3112722D01*
X720256D01*
G01X252656Y3135055D02*
X252056Y3135455D01*
X251356Y3135722D01*
X250556D01*
X249656Y3135322D01*
X248956Y3134655D01*
X248456Y3133855D01*
X248056Y3132522D01*
X247956Y3131322D01*
X248156Y3130122D01*
X248456Y3129322D01*
X249056Y3128522D01*
X249756Y3127989D01*
X250456Y3127722D01*
X251156D01*
X251856Y3127989D01*
X252456Y3128389D01*
X252956Y3128922D01*
G01X256356Y3127722D02*
Y3135722D01*
G01X260556D02*
Y3127722D01*
G01Y3131722D02*
X256356D01*
G01X263956Y3127722D02*
X266456Y3135722D01*
X268956Y3127722D01*
G01X268056Y3130522D02*
X264856D01*
G01X272456Y3127722D02*
Y3135722D01*
X274956D01*
X275756Y3135322D01*
X276256Y3134789D01*
X276456Y3133722D01*
X276256Y3132655D01*
X275656Y3131989D01*
X274956Y3131589D01*
X272456D01*
G01X274956D02*
X276456Y3127722D01*
G01X282456Y3135722D02*
Y3127722D01*
G01X280156Y3135722D02*
X284756D01*
G01X290456Y3127455D02*
X290256Y3127589D01*
Y3127855D01*
X290456Y3127989D01*
X290656Y3127855D01*
Y3127589D01*
X290456Y3127455D01*
G01X303856Y3127722D02*
Y3135722D01*
X306456Y3129055D01*
X309056Y3135722D01*
Y3127722D01*
G01X311956D02*
X314456Y3135722D01*
X316956Y3127722D01*
G01X316056Y3130522D02*
X312856D01*
G01X320156Y3127722D02*
Y3135722D01*
X324756Y3127722D01*
Y3135722D01*
G01X328256D02*
Y3129989D01*
X328656Y3128788D01*
X329456Y3127989D01*
X330456Y3127722D01*
X331456Y3127989D01*
X332256Y3128788D01*
X332656Y3129989D01*
Y3135722D01*
G01X336556Y3127722D02*
Y3135722D01*
X340356D01*
G01X338956Y3131855D02*
X336556D01*
G01X343956Y3127722D02*
X346456Y3135722D01*
X348956Y3127722D01*
G01X348056Y3130522D02*
X344856D01*
G01X356656Y3135055D02*
X356056Y3135455D01*
X355356Y3135722D01*
X354556D01*
X353656Y3135322D01*
X352956Y3134655D01*
X352456Y3133855D01*
X352056Y3132522D01*
X351956Y3131322D01*
X352156Y3130122D01*
X352456Y3129322D01*
X353056Y3128522D01*
X353756Y3127989D01*
X354456Y3127722D01*
X355156D01*
X355856Y3127989D01*
X356456Y3128389D01*
X356956Y3128922D01*
G01X362456Y3135722D02*
Y3127722D01*
G01X360156Y3135722D02*
X364756D01*
G01X368256D02*
Y3129989D01*
X368656Y3128788D01*
X369456Y3127989D01*
X370456Y3127722D01*
X371456Y3127989D01*
X372256Y3128788D01*
X372656Y3129989D01*
Y3135722D01*
G01X376456Y3127722D02*
Y3135722D01*
X378956D01*
X379756Y3135322D01*
X380256Y3134789D01*
X380456Y3133722D01*
X380256Y3132655D01*
X379656Y3131989D01*
X378956Y3131589D01*
X376456D01*
G01X378956D02*
X380456Y3127722D01*
G01X388456D02*
X384456D01*
Y3135722D01*
X388456D01*
G01X386856Y3131855D02*
X384456D01*
G01X392456Y3127722D02*
Y3135722D01*
X394956D01*
X395756Y3135322D01*
X396256Y3134789D01*
X396456Y3133722D01*
X396256Y3132655D01*
X395656Y3131989D01*
X394956Y3131589D01*
X392456D01*
G01X394956D02*
X396456Y3127722D01*
G01X409256Y3135722D02*
X411656D01*
G01X410456D02*
Y3127722D01*
G01X409256D02*
X411656D01*
G01X416356Y3128788D02*
X417156Y3128122D01*
X418056Y3127722D01*
X418856D01*
X419656Y3128122D01*
X420256Y3128788D01*
X420556Y3129722D01*
X420356Y3130655D01*
X419856Y3131455D01*
X418956Y3131989D01*
X417756Y3132255D01*
X417056Y3132789D01*
X416756Y3133722D01*
X416956Y3134655D01*
X417456Y3135322D01*
X418156Y3135722D01*
X418856D01*
X419556Y3135455D01*
X420156Y3134789D01*
G01X432556Y3127722D02*
Y3135722D01*
X436356D01*
G01X434956Y3131855D02*
X432556D01*
G01X440456Y3127722D02*
Y3135722D01*
X442956D01*
X443756Y3135322D01*
X444256Y3134789D01*
X444456Y3133722D01*
X444256Y3132655D01*
X443656Y3131989D01*
X442956Y3131589D01*
X440456D01*
G01X442956D02*
X444456Y3127722D01*
G01X452456D02*
X448456D01*
Y3135722D01*
X452456D01*
G01X450856Y3131855D02*
X448456D01*
G01X460456Y3127722D02*
X456456D01*
Y3135722D01*
X460456D01*
G01X458856Y3131855D02*
X456456D01*
G01X474456Y3135722D02*
Y3127722D01*
G01X472156Y3135722D02*
X476756D01*
G01X482456Y3127722D02*
X481656Y3127855D01*
X480956Y3128389D01*
X480356Y3129189D01*
X479956Y3130122D01*
X479756Y3131189D01*
Y3132255D01*
X479956Y3133322D01*
X480356Y3134255D01*
X480956Y3135055D01*
X481656Y3135589D01*
X482456Y3135722D01*
X483256Y3135589D01*
X483956Y3135055D01*
X484556Y3134255D01*
X484956Y3133322D01*
X485156Y3132255D01*
Y3131189D01*
X484956Y3130122D01*
X484556Y3129189D01*
X483956Y3128389D01*
X483256Y3127855D01*
X482456Y3127722D01*
G01X495956D02*
X498456Y3135722D01*
X500956Y3127722D01*
G01X500056Y3130522D02*
X496856D01*
G01X504256Y3127722D02*
Y3135722D01*
X506256D01*
X507056Y3135322D01*
X507656Y3134789D01*
X508156Y3133989D01*
X508556Y3133055D01*
X508656Y3131722D01*
X508556Y3130389D01*
X508156Y3129455D01*
X507656Y3128655D01*
X507056Y3128122D01*
X506256Y3127722D01*
X504256D01*
G01X512456Y3129322D02*
X512956Y3128522D01*
X513556Y3127989D01*
X514256Y3127722D01*
X515056Y3127989D01*
X515656Y3128522D01*
X516256Y3129322D01*
X516456Y3130389D01*
Y3135722D01*
G01X520256D02*
Y3129989D01*
X520656Y3128788D01*
X521456Y3127989D01*
X522456Y3127722D01*
X523456Y3127989D01*
X524256Y3128788D01*
X524656Y3129989D01*
Y3135722D01*
G01X528356Y3128788D02*
X529156Y3128122D01*
X530056Y3127722D01*
X530856D01*
X531656Y3128122D01*
X532256Y3128788D01*
X532556Y3129722D01*
X532356Y3130655D01*
X531856Y3131455D01*
X530956Y3131989D01*
X529756Y3132255D01*
X529056Y3132789D01*
X528756Y3133722D01*
X528956Y3134655D01*
X529456Y3135322D01*
X530156Y3135722D01*
X530856D01*
X531556Y3135455D01*
X532156Y3134789D01*
G01X538456Y3135722D02*
Y3127722D01*
G01X536156Y3135722D02*
X540756D01*
G01X554456D02*
Y3127722D01*
G01X552156Y3135722D02*
X556756D01*
G01X560456Y3127722D02*
Y3135722D01*
X562956D01*
X563756Y3135322D01*
X564256Y3134789D01*
X564456Y3133722D01*
X564256Y3132655D01*
X563656Y3131989D01*
X562956Y3131589D01*
X560456D01*
G01X562956D02*
X564456Y3127722D01*
G01X567956D02*
X570456Y3135722D01*
X572956Y3127722D01*
G01X572056Y3130522D02*
X568856D01*
G01X580656Y3135055D02*
X580056Y3135455D01*
X579356Y3135722D01*
X578556D01*
X577656Y3135322D01*
X576956Y3134655D01*
X576456Y3133855D01*
X576056Y3132522D01*
X575956Y3131322D01*
X576156Y3130122D01*
X576456Y3129322D01*
X577056Y3128522D01*
X577756Y3127989D01*
X578456Y3127722D01*
X579156D01*
X579856Y3127989D01*
X580456Y3128389D01*
X580956Y3128922D01*
G01X588456Y3127722D02*
X584456D01*
Y3135722D01*
X588456D01*
G01X586856Y3131855D02*
X584456D01*
G01X599456Y3135722D02*
X600856Y3127722D01*
X602456Y3135722D01*
X604056Y3127722D01*
X605456Y3135722D01*
G01X609256D02*
X611656D01*
G01X610456D02*
Y3127722D01*
G01X609256D02*
X611656D01*
G01X616256D02*
Y3135722D01*
X618256D01*
X619056Y3135322D01*
X619656Y3134789D01*
X620156Y3133989D01*
X620556Y3133055D01*
X620656Y3131722D01*
X620556Y3130389D01*
X620156Y3129455D01*
X619656Y3128655D01*
X619056Y3128122D01*
X618256Y3127722D01*
X616256D01*
G01X626456Y3135722D02*
Y3127722D01*
G01X624156Y3135722D02*
X628756D01*
G01X632356Y3127722D02*
Y3135722D01*
G01X636556D02*
Y3127722D01*
G01Y3131722D02*
X632356D01*
G01X640356Y3128788D02*
X641156Y3128122D01*
X642056Y3127722D01*
X642856D01*
X643656Y3128122D01*
X644256Y3128788D01*
X644556Y3129722D01*
X644356Y3130655D01*
X643856Y3131455D01*
X642956Y3131989D01*
X641756Y3132255D01*
X641056Y3132789D01*
X640756Y3133722D01*
X640956Y3134655D01*
X641456Y3135322D01*
X642156Y3135722D01*
X642856D01*
X643556Y3135455D01*
X644156Y3134789D01*
G01X650256Y3126255D02*
X650656Y3127989D01*
G01X672256Y3127722D02*
Y3135722D01*
X674256D01*
X675056Y3135322D01*
X675656Y3134789D01*
X676156Y3133989D01*
X676556Y3133055D01*
X676656Y3131722D01*
X676556Y3130389D01*
X676156Y3129455D01*
X675656Y3128655D01*
X675056Y3128122D01*
X674256Y3127722D01*
X672256D01*
G01X681256Y3135722D02*
X683656D01*
G01X682456D02*
Y3127722D01*
G01X681256D02*
X683656D01*
G01X692456D02*
X688456D01*
Y3135722D01*
X692456D01*
G01X690856Y3131855D02*
X688456D01*
G01X696456Y3135722D02*
Y3127722D01*
X700456D01*
G01X708456D02*
X704456D01*
Y3135722D01*
X708456D01*
G01X706856Y3131855D02*
X704456D01*
G01X716656Y3135055D02*
X716056Y3135455D01*
X715356Y3135722D01*
X714556D01*
X713656Y3135322D01*
X712956Y3134655D01*
X712456Y3133855D01*
X712056Y3132522D01*
X711956Y3131322D01*
X712156Y3130122D01*
X712456Y3129322D01*
X713056Y3128522D01*
X713756Y3127989D01*
X714456Y3127722D01*
X715156D01*
X715856Y3127989D01*
X716456Y3128389D01*
X716956Y3128922D01*
G01X722456Y3135722D02*
Y3127722D01*
G01X720156Y3135722D02*
X724756D01*
G01X728456Y3127722D02*
Y3135722D01*
X730956D01*
X731756Y3135322D01*
X732256Y3134789D01*
X732456Y3133722D01*
X732256Y3132655D01*
X731656Y3131989D01*
X730956Y3131589D01*
X728456D01*
G01X730956D02*
X732456Y3127722D01*
G01X737256Y3135722D02*
X739656D01*
G01X738456D02*
Y3127722D01*
G01X737256D02*
X739656D01*
G01X748656Y3135055D02*
X748056Y3135455D01*
X747356Y3135722D01*
X746556D01*
X745656Y3135322D01*
X744956Y3134655D01*
X744456Y3133855D01*
X744056Y3132522D01*
X743956Y3131322D01*
X744156Y3130122D01*
X744456Y3129322D01*
X745056Y3128522D01*
X745756Y3127989D01*
X746456Y3127722D01*
X747156D01*
X747856Y3127989D01*
X748456Y3128389D01*
X748956Y3128922D01*
G01X277398Y-468335D02*
Y-543335D01*
G01X274094Y61614D02*
G02X281969I3938J0D01*
G02X274094I-3937J0D01*
G01X278005Y1700335D02*
X299817Y1624055D01*
X298136Y1626060D01*
X299912Y1626633D01*
X299779Y1624017D01*
G01X309078Y2741229D02*
X265771D01*
G01X273645D02*
Y2794379D01*
G01X309078Y2756978D02*
X265771D01*
G01X279398Y-468335D02*
Y-543335D01*
G01X284905Y-528335D02*
Y-523335D01*
X286171D01*
X286678Y-523585D01*
X287058Y-523918D01*
X287375Y-524418D01*
X287628Y-525002D01*
X287691Y-525835D01*
X287628Y-526668D01*
X287375Y-527252D01*
X287058Y-527752D01*
X286678Y-528085D01*
X286171Y-528335D01*
X284905D01*
G01X289815D02*
X291398Y-523335D01*
X292981Y-528335D01*
G01X292411Y-526585D02*
X290385D01*
G01X296498Y-523335D02*
Y-528335D01*
G01X295041Y-523335D02*
X297955D01*
G01X302865Y-528335D02*
X300331D01*
Y-523335D01*
X302865D01*
G01X301851Y-525752D02*
X300331D01*
G01X306698Y-528502D02*
X306571Y-528418D01*
Y-528252D01*
X306698Y-528168D01*
X306825Y-528252D01*
Y-528418D01*
X306698Y-528502D01*
G01Y-526252D02*
X306571Y-526168D01*
Y-526002D01*
X306698Y-525918D01*
X306825Y-526002D01*
Y-526168D01*
X306698Y-526252D01*
G01X279398Y-518335D02*
X479398D01*
G01X285031Y-503335D02*
Y-498335D01*
X286551D01*
X287058Y-498585D01*
X287438Y-499168D01*
X287565Y-499835D01*
X287438Y-500502D01*
X287121Y-501002D01*
X286551Y-501252D01*
X285031D01*
G01X290258Y-503502D02*
X292538Y-498335D01*
G01X295041Y-503335D02*
Y-498335D01*
X297955Y-503335D01*
Y-498335D01*
G01X301598Y-503502D02*
X301471Y-503418D01*
Y-503252D01*
X301598Y-503168D01*
X301725Y-503252D01*
Y-503418D01*
X301598Y-503502D01*
G01Y-501252D02*
X301471Y-501168D01*
Y-501002D01*
X301598Y-500918D01*
X301725Y-501002D01*
Y-501168D01*
X301598Y-501252D01*
G01X279398Y-493335D02*
X479398D01*
G01X285031Y-478335D02*
Y-473335D01*
X286551D01*
X287058Y-473585D01*
X287438Y-474168D01*
X287565Y-474835D01*
X287438Y-475502D01*
X287121Y-476002D01*
X286551Y-476252D01*
X285031D01*
G01X290131Y-478335D02*
Y-473335D01*
X291715D01*
X292221Y-473585D01*
X292538Y-473918D01*
X292665Y-474585D01*
X292538Y-475252D01*
X292158Y-475668D01*
X291715Y-475918D01*
X290131D01*
G01X291715D02*
X292665Y-478335D01*
G01X296498D02*
X295991Y-478252D01*
X295548Y-477918D01*
X295168Y-477418D01*
X294915Y-476835D01*
X294788Y-476168D01*
Y-475502D01*
X294915Y-474835D01*
X295168Y-474252D01*
X295548Y-473752D01*
X295991Y-473418D01*
X296498Y-473335D01*
X297005Y-473418D01*
X297448Y-473752D01*
X297828Y-474252D01*
X298081Y-474835D01*
X298208Y-475502D01*
Y-476168D01*
X298081Y-476835D01*
X297828Y-477418D01*
X297448Y-477918D01*
X297005Y-478252D01*
X296498Y-478335D01*
G01X300331Y-477335D02*
X300648Y-477835D01*
X301028Y-478168D01*
X301471Y-478335D01*
X301978Y-478168D01*
X302358Y-477835D01*
X302738Y-477335D01*
X302865Y-476668D01*
Y-473335D01*
G01X307965Y-478335D02*
X305431D01*
Y-473335D01*
X307965D01*
G01X306951Y-475752D02*
X305431D01*
G01X313191Y-473752D02*
X312811Y-473502D01*
X312368Y-473335D01*
X311861D01*
X311291Y-473585D01*
X310848Y-474002D01*
X310531Y-474502D01*
X310278Y-475335D01*
X310215Y-476085D01*
X310341Y-476835D01*
X310531Y-477335D01*
X310911Y-477835D01*
X311355Y-478168D01*
X311798Y-478335D01*
X312241D01*
X312685Y-478168D01*
X313065Y-477918D01*
X313381Y-477585D01*
G01X316898Y-473335D02*
Y-478335D01*
G01X315441Y-473335D02*
X318355D01*
G01X321998Y-478502D02*
X321871Y-478418D01*
Y-478252D01*
X321998Y-478168D01*
X322125Y-478252D01*
Y-478418D01*
X321998Y-478502D01*
G01Y-476252D02*
X321871Y-476168D01*
Y-476002D01*
X321998Y-475918D01*
X322125Y-476002D01*
Y-476168D01*
X321998Y-476252D01*
G01X280310Y1617502D02*
Y1626602D01*
X364010D01*
Y1449502D01*
X280310D01*
Y1617502D01*
G01X292903Y1701405D02*
X308526Y1624971D01*
X306846Y1627301D01*
X308985Y1627836D01*
X308565Y1624933D01*
G01X358290Y2589655D02*
X326794D01*
G01D02*
X368133D01*
G01X318920Y2659537D02*
G03I-2953J0D01*
G01Y2679222D02*
G03I-2953J0D01*
G01X313015Y2721544D02*
X887818D01*
G01X313015Y2737292D02*
Y2721544D01*
G01Y2741229D02*
X887818D01*
G01Y2737292D02*
X313015D01*
G01Y2756978D02*
Y2741229D01*
G01X887818Y2756978D02*
X313015D01*
G01Y2760915D02*
Y2831781D01*
G01Y2823907D02*
X608290D01*
G01X331969Y81575D02*
G02X339843I3937J0D01*
G02X331969I-3937J0D01*
G01X338605Y2659537D02*
G03I-2953J0D01*
G01Y2679222D02*
G03I-2953J0D01*
G01X359202Y-317174D02*
Y-321824D01*
X346702D01*
Y-317174D01*
G01X359202Y-248974D02*
Y-244324D01*
X346702D01*
Y-248974D01*
G01X352952Y1253386D02*
Y-234949D01*
G01X344094Y1066535D02*
G02X361811I8858J0D01*
G02X344094I-8859J0D01*
G01Y1263386D02*
G02X361811I8858J0D01*
G02X344094I-8859J0D01*
G01X350646Y2570897D02*
X351576Y2569855D01*
X352661Y2569230D01*
X354056Y2569022D01*
X355451Y2569439D01*
X356536Y2570272D01*
X357311Y2571730D01*
X357466Y2573397D01*
X357156Y2575064D01*
X356381Y2576105D01*
X355296Y2576939D01*
X354211Y2577147D01*
X353126Y2576939D01*
X351731Y2576105D01*
X352196Y2581522D01*
X356381D01*
G01X362426Y2569022D02*
Y2581522D01*
X366456Y2571105D01*
X370486Y2581522D01*
Y2569022D01*
G01X374826D02*
Y2581522D01*
X378856Y2571105D01*
X382886Y2581522D01*
Y2569022D01*
G01X358290Y2652035D02*
Y2581781D01*
G01Y2659537D02*
G03I-2953J0D01*
G01Y2679222D02*
G03I-2953J0D01*
G01X409471Y2589655D02*
X368133D01*
G01X376457Y61614D02*
G02X384331I3937J0D01*
G02X376457I-3937J0D01*
G01X384055Y1141024D02*
G02X396654I6299J0D01*
G02X384055I-6299J0D01*
G01X409471Y2562096D02*
X377975D01*
G01D02*
X419314D01*
G01X377975Y2652385D02*
Y2581781D01*
G01Y2589655D02*
X409471D01*
G01X377975Y2662489D02*
X383881D01*
G01Y2656584D02*
X377975D01*
G01X383881Y2662489D02*
Y2656584D01*
G01X377975D02*
Y2662489D01*
G01Y2682174D02*
X383881D01*
G01Y2676269D02*
X377975D01*
G01X383881Y2682174D02*
Y2676269D01*
G01X377975D02*
Y2682174D01*
G01X394258Y-543563D02*
Y-518563D01*
G01X397031Y-520835D02*
Y-525835D01*
X399565D01*
G01X402638Y-520835D02*
X404158D01*
G01X403398D02*
Y-525835D01*
G01X402638D02*
X404158D01*
G01X409005Y-523168D02*
X409258Y-522918D01*
X409448Y-522502D01*
X409575Y-521918D01*
X409448Y-521418D01*
X409195Y-521085D01*
X408751Y-520835D01*
X407041D01*
Y-525835D01*
X409131D01*
X409575Y-525502D01*
X409828Y-525002D01*
X409955Y-524418D01*
X409828Y-523835D01*
X409448Y-523335D01*
X409005Y-523168D01*
X407041D01*
G01X413598Y-526002D02*
X413471Y-525918D01*
Y-525752D01*
X413598Y-525668D01*
X413725Y-525752D01*
Y-525918D01*
X413598Y-526002D01*
G01Y-523752D02*
X413471Y-523668D01*
Y-523502D01*
X413598Y-523418D01*
X413725Y-523502D01*
Y-523668D01*
X413598Y-523752D01*
G01X398465Y1604724D02*
G02X420512I11024J0D01*
G02X398465I-11023J0D01*
G01X403646Y2539497D02*
X404576Y2538455D01*
X405661Y2537830D01*
X407056Y2537622D01*
X408451Y2538039D01*
X409536Y2538872D01*
X410311Y2540330D01*
X410466Y2541997D01*
X410156Y2543664D01*
X409381Y2544705D01*
X408296Y2545539D01*
X407211Y2545747D01*
X406126Y2545539D01*
X404731Y2544705D01*
X405196Y2550122D01*
X409381D01*
G01X415426Y2537622D02*
Y2550122D01*
X419456Y2539705D01*
X423486Y2550122D01*
Y2537622D01*
G01X427826D02*
Y2550122D01*
X431856Y2539705D01*
X435886Y2550122D01*
Y2537622D01*
G01X429156Y2613797D02*
X397660D01*
G01D02*
X432109D01*
G01X403566Y2662489D02*
X409471D01*
G01Y2656584D02*
X403566D01*
G01D02*
Y2662489D01*
G01Y2682174D02*
X409471D01*
G01Y2676269D02*
X403566D01*
G01D02*
Y2682174D01*
G01X422106Y70866D02*
G02X444154I11024J0D01*
G02X422106I-11024J0D01*
G01X460652Y2562096D02*
X419314D01*
G01X409471Y2652647D02*
Y2554222D01*
G01Y2662489D02*
Y2656584D01*
G01Y2682174D02*
Y2676269D01*
G01X437258Y-518563D02*
Y-543563D01*
G01X437398Y-518335D02*
Y-543335D01*
G01X441298Y-520835D02*
Y-525835D01*
G01X439841Y-520835D02*
X442755D01*
G01X446398Y-525835D02*
X446018Y-525752D01*
X445638Y-525418D01*
X445385Y-524835D01*
X445258Y-524168D01*
X445385Y-523502D01*
X445638Y-522918D01*
X446018Y-522585D01*
X446398Y-522502D01*
X446778Y-522585D01*
X447158Y-522918D01*
X447411Y-523502D01*
X447475Y-524168D01*
X447411Y-524835D01*
X447158Y-525418D01*
X446778Y-525752D01*
X446398Y-525835D01*
G01X451498D02*
X451118Y-525752D01*
X450738Y-525418D01*
X450485Y-524835D01*
X450358Y-524168D01*
X450485Y-523502D01*
X450738Y-522918D01*
X451118Y-522585D01*
X451498Y-522502D01*
X451878Y-522585D01*
X452258Y-522918D01*
X452511Y-523502D01*
X452575Y-524168D01*
X452511Y-524835D01*
X452258Y-525418D01*
X451878Y-525752D01*
X451498Y-525835D01*
G01X456598D02*
Y-520835D01*
G01X461698Y-526002D02*
X461571Y-525918D01*
Y-525752D01*
X461698Y-525668D01*
X461825Y-525752D01*
Y-525918D01*
X461698Y-526002D01*
G01Y-523752D02*
X461571Y-523668D01*
Y-523502D01*
X461698Y-523418D01*
X461825Y-523502D01*
Y-523668D01*
X461698Y-523752D01*
G01X437398Y-493335D02*
Y-518335D01*
G01X440031Y-500835D02*
Y-495835D01*
X441615D01*
X442121Y-496085D01*
X442438Y-496418D01*
X442565Y-497085D01*
X442438Y-497752D01*
X442058Y-498168D01*
X441615Y-498418D01*
X440031D01*
G01X441615D02*
X442565Y-500835D01*
G01X447665D02*
X445131D01*
Y-495835D01*
X447665D01*
G01X446651Y-498252D02*
X445131D01*
G01X449915Y-495835D02*
X451498Y-500835D01*
X453081Y-495835D01*
G01X456598Y-501002D02*
X456471Y-500918D01*
Y-500752D01*
X456598Y-500668D01*
X456725Y-500752D01*
Y-500918D01*
X456598Y-501002D01*
G01Y-498752D02*
X456471Y-498668D01*
Y-498502D01*
X456598Y-498418D01*
X456725Y-498502D01*
Y-498668D01*
X456598Y-498752D01*
G01X429156Y2652647D02*
Y2554222D01*
G01Y2562096D02*
X460652D01*
G01X435062Y2651962D02*
Y2605923D01*
G01X429156Y2648463D02*
Y2605923D01*
G01X435062Y2613797D02*
X501588D01*
G01D02*
X432109D01*
G01X429156Y2662489D02*
X435062D01*
G01Y2656584D02*
X429156D01*
G01X435062Y2662489D02*
Y2656584D01*
G01X429156D02*
Y2662489D01*
G01Y2682174D02*
X435062D01*
G01Y2676269D02*
X429156D01*
G01X435062Y2682174D02*
Y2676269D01*
G01X429156D02*
Y2682174D01*
G01X438999Y2676269D02*
X558729D01*
G01X438999Y2682174D02*
X558729D01*
G01X445411Y-546502D02*
X445518Y-546377D01*
X445598Y-546168D01*
X445651Y-545877D01*
X445598Y-545627D01*
X445491Y-545460D01*
X445305Y-545335D01*
X444585D01*
Y-547835D01*
X445465D01*
X445651Y-547668D01*
X445758Y-547418D01*
X445811Y-547127D01*
X445758Y-546835D01*
X445598Y-546585D01*
X445411Y-546502D01*
X444585D01*
G01X447878Y-547835D02*
Y-546168D01*
G01Y-546460D02*
X447771Y-546293D01*
X447611Y-546210D01*
X447425Y-546168D01*
X447238Y-546252D01*
X447078Y-546418D01*
X446971Y-546668D01*
X446918Y-547002D01*
X446971Y-547335D01*
X447078Y-547585D01*
X447238Y-547752D01*
X447425Y-547835D01*
X447611Y-547793D01*
X447771Y-547668D01*
X447878Y-547502D01*
G01X449198Y-547543D02*
X449331Y-547710D01*
X449518Y-547835D01*
X449678D01*
X449838Y-547752D01*
X449945Y-547627D01*
X449998Y-547460D01*
X449971Y-547210D01*
X449865Y-547085D01*
X449385Y-546835D01*
X449278Y-546543D01*
X449331Y-546335D01*
X449438Y-546210D01*
X449598Y-546168D01*
X449758Y-546210D01*
X449918Y-546335D01*
G01X451398Y-546710D02*
X452251D01*
X452171Y-546418D01*
X452038Y-546252D01*
X451851Y-546168D01*
X451665Y-546210D01*
X451505Y-546335D01*
X451398Y-546627D01*
X451345Y-546877D01*
Y-547127D01*
X451398Y-547377D01*
X451531Y-547627D01*
X451691Y-547793D01*
X451878Y-547835D01*
X452065Y-547752D01*
X452251Y-547502D01*
G01X453518Y-547835D02*
Y-545335D01*
G01Y-546585D02*
X453651Y-546335D01*
X453811Y-546210D01*
X453971Y-546168D01*
X454211Y-546252D01*
X454371Y-546418D01*
X454478Y-546710D01*
Y-547043D01*
X454425Y-547377D01*
X454318Y-547627D01*
X454131Y-547793D01*
X453971Y-547835D01*
X453811Y-547793D01*
X453651Y-547668D01*
X453518Y-547460D01*
G01X456198Y-547835D02*
X456038Y-547793D01*
X455878Y-547627D01*
X455771Y-547335D01*
X455718Y-547002D01*
X455771Y-546668D01*
X455878Y-546377D01*
X456038Y-546210D01*
X456198Y-546168D01*
X456358Y-546210D01*
X456518Y-546377D01*
X456625Y-546668D01*
X456651Y-547002D01*
X456625Y-547335D01*
X456518Y-547627D01*
X456358Y-547793D01*
X456198Y-547835D01*
G01X458878D02*
Y-546168D01*
G01Y-546460D02*
X458771Y-546293D01*
X458611Y-546210D01*
X458425Y-546168D01*
X458238Y-546252D01*
X458078Y-546418D01*
X457971Y-546668D01*
X457918Y-547002D01*
X457971Y-547335D01*
X458078Y-547585D01*
X458238Y-547752D01*
X458425Y-547835D01*
X458611Y-547793D01*
X458771Y-547668D01*
X458878Y-547502D01*
G01X460225Y-547835D02*
Y-546168D01*
G01Y-546502D02*
X460358Y-546335D01*
X460491Y-546210D01*
X460678Y-546168D01*
X460811Y-546210D01*
X460971Y-546335D01*
G01X463278Y-545335D02*
Y-547835D01*
G01Y-547460D02*
X463171Y-547668D01*
X463011Y-547793D01*
X462825Y-547835D01*
X462611Y-547752D01*
X462451Y-547543D01*
X462345Y-547293D01*
X462318Y-547002D01*
X462345Y-546710D01*
X462451Y-546460D01*
X462611Y-546252D01*
X462825Y-546168D01*
X463011Y-546210D01*
X463145Y-546293D01*
X463278Y-546460D01*
G01X466665Y-547835D02*
Y-545335D01*
X467331D01*
X467545Y-545460D01*
X467678Y-545627D01*
X467731Y-545960D01*
X467678Y-546293D01*
X467518Y-546502D01*
X467331Y-546627D01*
X466665D01*
G01X467331D02*
X467731Y-547835D01*
G01X468998Y-546710D02*
X469851D01*
X469771Y-546418D01*
X469638Y-546252D01*
X469451Y-546168D01*
X469265Y-546210D01*
X469105Y-546335D01*
X468998Y-546627D01*
X468945Y-546877D01*
Y-547127D01*
X468998Y-547377D01*
X469131Y-547627D01*
X469291Y-547793D01*
X469478Y-547835D01*
X469665Y-547752D01*
X469851Y-547502D01*
G01X471118Y-546168D02*
X471598Y-547835D01*
X472078Y-546168D01*
G01X473798Y-547918D02*
X473745Y-547877D01*
Y-547793D01*
X473798Y-547752D01*
X473851Y-547793D01*
Y-547877D01*
X473798Y-547918D01*
G01X475545Y-547543D02*
X475731Y-547752D01*
X475945Y-547835D01*
X476158Y-547752D01*
X476345Y-547502D01*
X476478Y-547127D01*
X476531Y-546752D01*
Y-546293D01*
X476478Y-545918D01*
X476345Y-545585D01*
X476185Y-545418D01*
X475998Y-545335D01*
X475785Y-545418D01*
X475625Y-545585D01*
X475518Y-545835D01*
X475465Y-546168D01*
X475518Y-546460D01*
X475651Y-546752D01*
X475811Y-546918D01*
X475998Y-546960D01*
X476211Y-546877D01*
X476371Y-546668D01*
X476531Y-546293D01*
G01X478411Y-546502D02*
X478518Y-546377D01*
X478598Y-546168D01*
X478651Y-545877D01*
X478598Y-545627D01*
X478491Y-545460D01*
X478305Y-545335D01*
X477585D01*
Y-547835D01*
X478465D01*
X478651Y-547668D01*
X478758Y-547418D01*
X478811Y-547127D01*
X478758Y-546835D01*
X478598Y-546585D01*
X478411Y-546502D01*
X477585D01*
G01X452362Y286220D02*
G02X474409I11023J0D01*
G02X452362I-11024J0D01*
G01Y765197D02*
G02X474409I11023J0D01*
G02X452362I-11024J0D01*
G01X453539Y1617502D02*
Y1626602D01*
X537239D01*
Y1449502D01*
X453539D01*
Y1617502D01*
G01X459071Y2616750D02*
Y2629250D01*
X457211Y2626750D01*
G01Y2616750D02*
X460931D01*
G01X471471Y2616333D02*
X471161Y2616542D01*
Y2616958D01*
X471471Y2617167D01*
X471781Y2616958D01*
Y2616542D01*
X471471Y2616333D01*
G01X480461Y2618625D02*
X481391Y2617583D01*
X482476Y2616958D01*
X483871Y2616750D01*
X485266Y2617167D01*
X486351Y2618000D01*
X487126Y2619458D01*
X487281Y2621125D01*
X486971Y2622792D01*
X486196Y2623833D01*
X485111Y2624667D01*
X484026Y2624875D01*
X482941Y2624667D01*
X481546Y2623833D01*
X482011Y2629250D01*
X486196D01*
G01X492241Y2616750D02*
Y2629250D01*
X496271Y2618833D01*
X500301Y2629250D01*
Y2616750D01*
G01X504641D02*
Y2629250D01*
X508671Y2618833D01*
X512701Y2629250D01*
Y2616750D01*
G01X518748Y-83731D02*
X459693D01*
Y-52235D01*
X518748D01*
Y-83731D01*
G01X481969Y81575D02*
G02X489843I3937J0D01*
G02X481969I-3937J0D01*
G01X499167Y1697631D02*
X474215Y1624222D01*
X475940Y1626301D01*
X474146Y1626823D01*
X474215Y1624222D01*
G01X509339Y1696402D02*
X484387Y1622993D01*
X486112Y1625072D01*
X484318Y1625594D01*
X484387Y1622993D01*
G01X488356Y3233788D02*
X489156Y3233122D01*
X490056Y3232722D01*
X490856D01*
X491656Y3233122D01*
X492256Y3233788D01*
X492556Y3234722D01*
X492356Y3235655D01*
X491856Y3236455D01*
X490956Y3236989D01*
X489756Y3237255D01*
X489056Y3237789D01*
X488756Y3238722D01*
X488956Y3239655D01*
X489456Y3240322D01*
X490156Y3240722D01*
X490856D01*
X491556Y3240455D01*
X492156Y3239789D01*
G01X498456Y3232722D02*
X497656Y3232855D01*
X496956Y3233389D01*
X496356Y3234189D01*
X495956Y3235122D01*
X495756Y3236189D01*
Y3237255D01*
X495956Y3238322D01*
X496356Y3239255D01*
X496956Y3240055D01*
X497656Y3240589D01*
X498456Y3240722D01*
X499256Y3240589D01*
X499956Y3240055D01*
X500556Y3239255D01*
X500956Y3238322D01*
X501156Y3237255D01*
Y3236189D01*
X500956Y3235122D01*
X500556Y3234189D01*
X499956Y3233389D01*
X499256Y3232855D01*
X498456Y3232722D01*
G01X504456Y3240722D02*
Y3232722D01*
X508456D01*
G01X512256D02*
Y3240722D01*
X514256D01*
X515056Y3240322D01*
X515656Y3239789D01*
X516156Y3238989D01*
X516556Y3238055D01*
X516656Y3236722D01*
X516556Y3235389D01*
X516156Y3234455D01*
X515656Y3233655D01*
X515056Y3233122D01*
X514256Y3232722D01*
X512256D01*
G01X524456D02*
X520456D01*
Y3240722D01*
X524456D01*
G01X522856Y3236855D02*
X520456D01*
G01X528456Y3232722D02*
Y3240722D01*
X530956D01*
X531756Y3240322D01*
X532256Y3239789D01*
X532456Y3238722D01*
X532256Y3237655D01*
X531656Y3236989D01*
X530956Y3236589D01*
X528456D01*
G01X530956D02*
X532456Y3232722D01*
G01X535856D02*
Y3240722D01*
X538456Y3234055D01*
X541056Y3240722D01*
Y3232722D01*
G01X543956D02*
X546456Y3240722D01*
X548956Y3232722D01*
G01X548056Y3235522D02*
X544856D01*
G01X552356Y3233788D02*
X553156Y3233122D01*
X554056Y3232722D01*
X554856D01*
X555656Y3233122D01*
X556256Y3233788D01*
X556556Y3234722D01*
X556356Y3235655D01*
X555856Y3236455D01*
X554956Y3236989D01*
X553756Y3237255D01*
X553056Y3237789D01*
X552756Y3238722D01*
X552956Y3239655D01*
X553456Y3240322D01*
X554156Y3240722D01*
X554856D01*
X555556Y3240455D01*
X556156Y3239789D01*
G01X560256Y3232722D02*
Y3240722D01*
G01X564056D02*
X560256Y3235788D01*
G01X564656Y3232722D02*
X561956Y3238055D01*
G01X578456Y3232722D02*
X577656Y3232855D01*
X576956Y3233389D01*
X576356Y3234189D01*
X575956Y3235122D01*
X575756Y3236189D01*
Y3237255D01*
X575956Y3238322D01*
X576356Y3239255D01*
X576956Y3240055D01*
X577656Y3240589D01*
X578456Y3240722D01*
X579256Y3240589D01*
X579956Y3240055D01*
X580556Y3239255D01*
X580956Y3238322D01*
X581156Y3237255D01*
Y3236189D01*
X580956Y3235122D01*
X580556Y3234189D01*
X579956Y3233389D01*
X579256Y3232855D01*
X578456Y3232722D01*
G01X584456D02*
Y3240722D01*
X586856D01*
X587656Y3240322D01*
X588256Y3239389D01*
X588456Y3238322D01*
X588256Y3237255D01*
X587756Y3236455D01*
X586856Y3236055D01*
X584456D01*
G01X596456Y3232722D02*
X592456D01*
Y3240722D01*
X596456D01*
G01X594856Y3236855D02*
X592456D01*
G01X600156Y3232722D02*
Y3240722D01*
X604756Y3232722D01*
Y3240722D01*
G01X618456Y3232722D02*
X617656Y3232855D01*
X616956Y3233389D01*
X616356Y3234189D01*
X615956Y3235122D01*
X615756Y3236189D01*
Y3237255D01*
X615956Y3238322D01*
X616356Y3239255D01*
X616956Y3240055D01*
X617656Y3240589D01*
X618456Y3240722D01*
X619256Y3240589D01*
X619956Y3240055D01*
X620556Y3239255D01*
X620956Y3238322D01*
X621156Y3237255D01*
Y3236189D01*
X620956Y3235122D01*
X620556Y3234189D01*
X619956Y3233389D01*
X619256Y3232855D01*
X618456Y3232722D01*
G01X624156D02*
Y3240722D01*
X628756Y3232722D01*
Y3240722D01*
G01X643256Y3236989D02*
X643656Y3237389D01*
X643956Y3238055D01*
X644156Y3238989D01*
X643956Y3239789D01*
X643556Y3240322D01*
X642856Y3240722D01*
X640156D01*
Y3232722D01*
X643456D01*
X644156Y3233255D01*
X644556Y3234055D01*
X644756Y3234989D01*
X644556Y3235922D01*
X643956Y3236722D01*
X643256Y3236989D01*
X640156D01*
G01X650456Y3232722D02*
X649656Y3232855D01*
X648956Y3233389D01*
X648356Y3234189D01*
X647956Y3235122D01*
X647756Y3236189D01*
Y3237255D01*
X647956Y3238322D01*
X648356Y3239255D01*
X648956Y3240055D01*
X649656Y3240589D01*
X650456Y3240722D01*
X651256Y3240589D01*
X651956Y3240055D01*
X652556Y3239255D01*
X652956Y3238322D01*
X653156Y3237255D01*
Y3236189D01*
X652956Y3235122D01*
X652556Y3234189D01*
X651956Y3233389D01*
X651256Y3232855D01*
X650456Y3232722D01*
G01X658456Y3240722D02*
Y3232722D01*
G01X656156Y3240722D02*
X660756D01*
G01X664356Y3232722D02*
Y3240722D01*
G01X668556D02*
Y3232722D01*
G01Y3236722D02*
X664356D01*
G01X680356Y3233788D02*
X681156Y3233122D01*
X682056Y3232722D01*
X682856D01*
X683656Y3233122D01*
X684256Y3233788D01*
X684556Y3234722D01*
X684356Y3235655D01*
X683856Y3236455D01*
X682956Y3236989D01*
X681756Y3237255D01*
X681056Y3237789D01*
X680756Y3238722D01*
X680956Y3239655D01*
X681456Y3240322D01*
X682156Y3240722D01*
X682856D01*
X683556Y3240455D01*
X684156Y3239789D01*
G01X689256Y3240722D02*
X691656D01*
G01X690456D02*
Y3232722D01*
G01X689256D02*
X691656D01*
G01X696256D02*
Y3240722D01*
X698256D01*
X699056Y3240322D01*
X699656Y3239789D01*
X700156Y3238989D01*
X700556Y3238055D01*
X700656Y3236722D01*
X700556Y3235389D01*
X700156Y3234455D01*
X699656Y3233655D01*
X699056Y3233122D01*
X698256Y3232722D01*
X696256D01*
G01X708456D02*
X704456D01*
Y3240722D01*
X708456D01*
G01X706856Y3236855D02*
X704456D01*
G01X714456Y3232455D02*
X714256Y3232589D01*
Y3232855D01*
X714456Y3232989D01*
X714656Y3232855D01*
Y3232589D01*
X714456Y3232455D01*
G01X526457Y61614D02*
G02X534331I3937J0D01*
G02X526457I-3937J0D01*
G01X530118Y1086654D02*
G02X542717I6299J0D01*
G02X530118I-6299J0D01*
G01X541997Y2567461D02*
X529497D01*
X531997Y2565601D01*
G01X541997D02*
Y2569321D01*
G01X542414Y2579861D02*
X542205Y2579551D01*
X541789D01*
X541580Y2579861D01*
X541789Y2580171D01*
X542205D01*
X542414Y2579861D01*
G01X540122Y2588851D02*
X541164Y2589781D01*
X541789Y2590866D01*
X541997Y2592261D01*
X541580Y2593656D01*
X540747Y2594741D01*
X539289Y2595516D01*
X537622Y2595671D01*
X535955Y2595361D01*
X534914Y2594586D01*
X534080Y2593501D01*
X533872Y2592416D01*
X534080Y2591331D01*
X534914Y2589936D01*
X529497Y2590401D01*
Y2594586D01*
G01X541997Y2600631D02*
X529497D01*
X539914Y2604661D01*
X529497Y2608691D01*
X541997D01*
G01Y2613031D02*
X529497D01*
X539914Y2617061D01*
X529497Y2621091D01*
X541997D01*
G01X550855Y2676269D02*
Y2580450D01*
G01D02*
Y2679222D01*
G01Y2682174D02*
Y2713670D01*
G01D02*
Y2679222D01*
G01X558690Y2826859D02*
Y2839359D01*
X556830Y2836859D01*
G01Y2826859D02*
X560550D01*
G01X571090Y2839359D02*
X569850Y2838942D01*
X568920Y2837901D01*
X568300Y2836651D01*
X567835Y2834984D01*
X567680Y2833109D01*
X567835Y2831234D01*
X568300Y2829567D01*
X568920Y2828317D01*
X569850Y2827276D01*
X571090Y2826859D01*
X572330Y2827276D01*
X573260Y2828317D01*
X573880Y2829567D01*
X574345Y2831234D01*
X574500Y2833109D01*
X574345Y2834984D01*
X573880Y2836651D01*
X573260Y2837901D01*
X572330Y2838942D01*
X571090Y2839359D01*
G01X583490D02*
X582250Y2838942D01*
X581320Y2837901D01*
X580700Y2836651D01*
X580235Y2834984D01*
X580080Y2833109D01*
X580235Y2831234D01*
X580700Y2829567D01*
X581320Y2828317D01*
X582250Y2827276D01*
X583490Y2826859D01*
X584730Y2827276D01*
X585660Y2828317D01*
X586280Y2829567D01*
X586745Y2831234D01*
X586900Y2833109D01*
X586745Y2834984D01*
X586280Y2836651D01*
X585660Y2837901D01*
X584730Y2838942D01*
X583490Y2839359D01*
G01X593875Y2831026D02*
X597905D01*
G01X608290Y2826859D02*
Y2839359D01*
X606430Y2836859D01*
G01Y2826859D02*
X610150D01*
G01X617280Y2828734D02*
X618210Y2827692D01*
X619295Y2827067D01*
X620690Y2826859D01*
X622085Y2827276D01*
X623170Y2828109D01*
X623945Y2829567D01*
X624100Y2831234D01*
X623790Y2832901D01*
X623015Y2833942D01*
X621930Y2834776D01*
X620845Y2834984D01*
X619760Y2834776D01*
X618365Y2833942D01*
X618830Y2839359D01*
X623015D01*
G01X633090D02*
X631850Y2838942D01*
X630920Y2837901D01*
X630300Y2836651D01*
X629835Y2834984D01*
X629680Y2833109D01*
X629835Y2831234D01*
X630300Y2829567D01*
X630920Y2828317D01*
X631850Y2827276D01*
X633090Y2826859D01*
X634330Y2827276D01*
X635260Y2828317D01*
X635880Y2829567D01*
X636345Y2831234D01*
X636500Y2833109D01*
X636345Y2834984D01*
X635880Y2836651D01*
X635260Y2837901D01*
X634330Y2838942D01*
X633090Y2839359D01*
G01X641460Y2826859D02*
Y2839359D01*
X645490Y2828942D01*
X649520Y2839359D01*
Y2826859D01*
G01X653860D02*
Y2839359D01*
X657890Y2828942D01*
X661920Y2839359D01*
Y2826859D01*
G01X580068Y-334902D02*
Y-339552D01*
X567568D01*
Y-334902D01*
G01X580068Y-254302D02*
Y-249652D01*
X567568D01*
Y-254302D01*
G01X564961Y1066535D02*
G02X582677I8858J0D01*
G02X564961I-8858J0D01*
G01Y1263386D02*
G02X582677I8858J0D01*
G02X564961I-8858J0D01*
G01X573818Y1253386D02*
Y-240277D01*
G01X584331Y81575D02*
G02X592205I3937J0D01*
G02X584331I-3937J0D01*
G01X588140Y1580079D02*
G02X575640I-6250J0D01*
G02X588140I6250J0D01*
G01Y1606142D02*
G02X575640I-6250J0D01*
G02X588140I6250J0D01*
G01Y1626339D02*
G02X575640I-6250J0D01*
G02X588140I6250J0D01*
G01X611456Y2669522D02*
X613456D01*
Y2667122D01*
X612856Y2666322D01*
X612156Y2665789D01*
X611156Y2665522D01*
X610156Y2665789D01*
X609456Y2666322D01*
X608856Y2667122D01*
X608456Y2668055D01*
X608256Y2669122D01*
Y2670055D01*
X608456Y2670855D01*
X608856Y2671789D01*
X609456Y2672589D01*
X610056Y2673122D01*
X610856Y2673522D01*
X611556D01*
X612356Y2673255D01*
X612956Y2672722D01*
G01X616856Y2665522D02*
Y2673522D01*
X619356D01*
X620156Y2673122D01*
X620656Y2672589D01*
X620856Y2671522D01*
X620656Y2670455D01*
X620056Y2669789D01*
X619356Y2669389D01*
X616856D01*
G01X619356D02*
X620856Y2665522D01*
G01X626856D02*
X626056Y2665655D01*
X625356Y2666189D01*
X624756Y2666989D01*
X624356Y2667922D01*
X624156Y2668989D01*
Y2670055D01*
X624356Y2671122D01*
X624756Y2672055D01*
X625356Y2672855D01*
X626056Y2673389D01*
X626856Y2673522D01*
X627656Y2673389D01*
X628356Y2672855D01*
X628956Y2672055D01*
X629356Y2671122D01*
X629556Y2670055D01*
Y2668989D01*
X629356Y2667922D01*
X628956Y2666989D01*
X628356Y2666189D01*
X627656Y2665655D01*
X626856Y2665522D01*
G01X632656Y2673522D02*
Y2667789D01*
X633056Y2666588D01*
X633856Y2665789D01*
X634856Y2665522D01*
X635856Y2665789D01*
X636656Y2666588D01*
X637056Y2667789D01*
Y2673522D01*
G01X640856Y2665522D02*
Y2673522D01*
X643256D01*
X644056Y2673122D01*
X644656Y2672189D01*
X644856Y2671122D01*
X644656Y2670055D01*
X644156Y2669255D01*
X643256Y2668855D01*
X640856D01*
G01X648756Y2666588D02*
X649556Y2665922D01*
X650456Y2665522D01*
X651256D01*
X652056Y2665922D01*
X652656Y2666588D01*
X652956Y2667522D01*
X652756Y2668455D01*
X652256Y2669255D01*
X651356Y2669789D01*
X650156Y2670055D01*
X649456Y2670589D01*
X649156Y2671522D01*
X649356Y2672455D01*
X649856Y2673122D01*
X650556Y2673522D01*
X651256D01*
X651956Y2673255D01*
X652556Y2672589D01*
G01X667656Y2669789D02*
X668056Y2670189D01*
X668356Y2670855D01*
X668556Y2671789D01*
X668356Y2672589D01*
X667956Y2673122D01*
X667256Y2673522D01*
X664556D01*
Y2665522D01*
X667856D01*
X668556Y2666055D01*
X668956Y2666855D01*
X669156Y2667789D01*
X668956Y2668722D01*
X668356Y2669522D01*
X667656Y2669789D01*
X664556D01*
G01X903566Y2823907D02*
X608290D01*
G01X628819Y61614D02*
G02X636693I3937J0D01*
G02X628819I-3937J0D01*
G01X626767Y1617502D02*
Y1626602D01*
X710467D01*
Y1449502D01*
X626767D01*
Y1617502D01*
G01X650650Y23622D02*
G02X672697I11023J0D01*
G02X650650I-11024J0D01*
G01X680954Y1698134D02*
X656002Y1624725D01*
X657727Y1626804D01*
X655933Y1627326D01*
X656002Y1624725D01*
G01X691126Y1696905D02*
X666174Y1623496D01*
X667899Y1625575D01*
X666105Y1626097D01*
X666174Y1623496D01*
G01X686693Y81575D02*
G02X694567I3937J0D01*
G02X686693I-3937J0D01*
G01X731181Y61614D02*
G02X739055I3937J0D01*
G02X731181I-3937J0D01*
G01X763780Y1490945D02*
G02X777165I6693J0D01*
G02X763780I-6692J0D01*
G01X766523Y1829242D02*
X761873D01*
Y1841742D01*
X766523D01*
G01X774016Y1547638D02*
G02X796063I11024J0D01*
G02X774016I-11023J0D01*
G01X789055Y81575D02*
G02X796929I3937J0D01*
G02X789055I-3937J0D01*
G01X811566Y-336828D02*
Y-341478D01*
X799066D01*
Y-336828D01*
G01X826329Y-331057D02*
Y-335707D01*
X813829D01*
Y-331057D01*
G01X826329Y-262857D02*
Y-258207D01*
X813829D01*
Y-262857D01*
G01X810038Y1253386D02*
Y-220196D01*
X805797Y-249016D01*
G01X811566Y-256228D02*
Y-251578D01*
X799066D01*
Y-256228D01*
G01X813386Y388583D02*
G02X826772I6693J0D01*
G02X813386I-6693J0D01*
G01X801181Y1066535D02*
G02X818898I8859J0D01*
G02X801181I-8858J0D01*
G01Y1263386D02*
G02X818898I8859J0D01*
G02X801181I-8858J0D01*
G01X820079Y378583D02*
Y-248832D01*
G01X830079Y388583D02*
X2156949D01*
G01X833543Y61614D02*
G02X841417I3937J0D01*
G02X833543I-3937J0D01*
G01X841173Y1367717D02*
G02X857709I8268J0D01*
G02X841173I-8268J0D01*
G01X1033812Y1628287D02*
Y1587987D01*
X837612D01*
Y1628287D01*
X1033812D01*
G01X846523Y1669321D02*
X841873D01*
Y1681821D01*
X846523D01*
G01X846389Y1669321D02*
X841739D01*
Y1681821D01*
X846389D01*
G01X834723Y1829242D02*
X839373D01*
Y1841742D01*
X834723D01*
G01X850916Y2802722D02*
Y2815222D01*
X845181Y2806264D01*
X852931D01*
G01X857426Y2802722D02*
Y2815222D01*
X861456Y2804805D01*
X865486Y2815222D01*
Y2802722D01*
G01X869826D02*
Y2815222D01*
X873856Y2804805D01*
X877886Y2815222D01*
Y2802722D01*
G01X847992Y1225118D02*
G02X860591I6300J0D01*
G02X847992I-6299J0D01*
G01X858198Y1847992D02*
X1840945D01*
G01X887818Y2796348D02*
X856322D01*
G01D02*
X895692D01*
G01X879193Y23622D02*
G02X901240I11024J0D01*
G02X879193I-11023J0D01*
G01X887818Y2721544D02*
X903566Y2729418D01*
G01X938999Y2741229D02*
X895692D01*
G01X938999Y2737292D02*
X895692D01*
G01X903566Y2729418D02*
X887818Y2737292D01*
G01Y2741229D02*
X903566Y2749104D01*
G01X887818Y2760915D02*
Y2804222D01*
G01X903566Y2749104D02*
X887818Y2756978D01*
G01X935062Y2796348D02*
X895692D01*
G01X909449Y765197D02*
G02X931496I11023J0D01*
G02X909449I-11023J0D01*
G01X903566Y2753040D02*
Y2804222D01*
G01Y2753040D02*
Y2831781D01*
G01Y2796348D02*
X935062D01*
G01X919618Y2698115D02*
Y2741422D01*
G01X939055Y81575D02*
G02X946929I3937J0D01*
G02X939055I-3937J0D01*
G01X938198Y1688071D02*
X1840945D01*
G01X938064D02*
X1840945D01*
G01X943556Y2703522D02*
X931056D01*
X933556Y2701662D01*
G01X943556D02*
Y2705382D01*
G01Y2711892D02*
X931056D01*
X941473Y2715922D01*
X931056Y2719952D01*
X943556D01*
G01Y2724292D02*
X931056D01*
X941473Y2728322D01*
X931056Y2732352D01*
X943556D01*
G01X963556Y2739322D02*
X965556D01*
Y2736922D01*
X964956Y2736122D01*
X964256Y2735589D01*
X963256Y2735322D01*
X962256Y2735589D01*
X961556Y2736122D01*
X960956Y2736922D01*
X960556Y2737855D01*
X960356Y2738922D01*
Y2739855D01*
X960556Y2740655D01*
X960956Y2741589D01*
X961556Y2742389D01*
X962156Y2742922D01*
X962956Y2743322D01*
X963656D01*
X964456Y2743055D01*
X965056Y2742522D01*
G01X968956Y2735322D02*
Y2743322D01*
X971456D01*
X972256Y2742922D01*
X972756Y2742389D01*
X972956Y2741322D01*
X972756Y2740255D01*
X972156Y2739589D01*
X971456Y2739189D01*
X968956D01*
G01X971456D02*
X972956Y2735322D01*
G01X978956D02*
X978156Y2735455D01*
X977456Y2735989D01*
X976856Y2736789D01*
X976456Y2737722D01*
X976256Y2738789D01*
Y2739855D01*
X976456Y2740922D01*
X976856Y2741855D01*
X977456Y2742655D01*
X978156Y2743189D01*
X978956Y2743322D01*
X979756Y2743189D01*
X980456Y2742655D01*
X981056Y2741855D01*
X981456Y2740922D01*
X981656Y2739855D01*
Y2738789D01*
X981456Y2737722D01*
X981056Y2736789D01*
X980456Y2735989D01*
X979756Y2735455D01*
X978956Y2735322D01*
G01X984756Y2743322D02*
Y2737589D01*
X985156Y2736388D01*
X985956Y2735589D01*
X986956Y2735322D01*
X987956Y2735589D01*
X988756Y2736388D01*
X989156Y2737589D01*
Y2743322D01*
G01X992956Y2735322D02*
Y2743322D01*
X995356D01*
X996156Y2742922D01*
X996756Y2741989D01*
X996956Y2740922D01*
X996756Y2739855D01*
X996256Y2739055D01*
X995356Y2738655D01*
X992956D01*
G01X1000856Y2736388D02*
X1001656Y2735722D01*
X1002556Y2735322D01*
X1003356D01*
X1004156Y2735722D01*
X1004756Y2736388D01*
X1005056Y2737322D01*
X1004856Y2738255D01*
X1004356Y2739055D01*
X1003456Y2739589D01*
X1002256Y2739855D01*
X1001556Y2740389D01*
X1001256Y2741322D01*
X1001456Y2742255D01*
X1001956Y2742922D01*
X1002656Y2743322D01*
X1003356D01*
X1004056Y2743055D01*
X1004656Y2742389D01*
G01X1016456Y2735322D02*
X1018956Y2743322D01*
X1021456Y2735322D01*
G01X1020556Y2738122D02*
X1017356D01*
G01X983543Y61614D02*
G02X991417I3937J0D01*
G02X983543I-3937J0D01*
G01X987205Y1170748D02*
G02X999803I6299J0D01*
G02X987205I-6299J0D01*
G01X1004203Y1634271D02*
X1003703Y1636571D01*
X1002403Y1635871D01*
X1004203Y1634271D01*
X997603Y1646171D01*
G01X1027116Y-323641D02*
Y-328291D01*
X1014616D01*
Y-323641D01*
G01X1020866Y378583D02*
Y-241416D01*
G01X1027116Y-255441D02*
Y-250791D01*
X1014616D01*
Y-255441D01*
G01X1014173Y388583D02*
G02X1027559I6693J0D01*
G02X1014173I-6693J0D01*
G01X1022047Y1066535D02*
G02X1039764I8859J0D01*
G02X1022047I-8858J0D01*
G01Y1263386D02*
G02X1039764I8859J0D01*
G02X1022047I-8858J0D01*
G01X1044764Y-334711D02*
Y-339361D01*
X1032264D01*
Y-334711D01*
G01X1044764Y-254111D02*
Y-249461D01*
X1032264D01*
Y-254111D01*
G01X1030905Y1253386D02*
Y-224999D01*
X1037079Y-236527D01*
X1037124Y-240086D01*
G01X1041417Y81575D02*
G02X1049291I3937J0D01*
G02X1041417I-3937J0D01*
G01X1044882Y1547638D02*
G02X1066929I11024J0D01*
G02X1044882I-11024J0D01*
G01X1063780Y1490945D02*
G02X1077165I6692J0D01*
G02X1063780I-6692J0D01*
G01X1085906Y61614D02*
G02X1093780I3937J0D01*
G02X1085906I-3937J0D01*
G01X1107736Y23622D02*
G02X1129783I11023J0D01*
G02X1107736I-11023J0D01*
G01X1129050Y1617502D02*
Y1626602D01*
X1212750D01*
Y1449502D01*
X1129050D01*
Y1617502D01*
G01X1133954Y1700504D02*
X1149005Y1624207D01*
X1147477Y1626557D01*
X1149348Y1626939D01*
X1149024Y1624265D01*
G01X1143780Y81575D02*
G02X1151654I3937J0D01*
G02X1143780I-3937J0D01*
G01X1147438Y1700946D02*
X1157331Y1625353D01*
X1155612Y1627683D01*
X1158019Y1628141D01*
X1157293Y1625315D01*
G01X1188268Y61614D02*
G02X1196142I3937J0D01*
G02X1188268I-3937J0D01*
G01X1246142Y81575D02*
G02X1254016I3937J0D01*
G02X1246142I-3937J0D01*
G01X1265305Y1580079D02*
G02X1252805I-6250J0D01*
G02X1265305I6250J0D01*
G01Y1606142D02*
G02X1252805I-6250J0D01*
G02X1265305I6250J0D01*
G01Y1626339D02*
G02X1252805I-6250J0D01*
G02X1265305I6250J0D01*
G01X1273375Y-330624D02*
Y-335274D01*
X1260875D01*
Y-330624D01*
G01X1273375Y-250024D02*
Y-245374D01*
X1260875D01*
Y-250024D01*
G01X1267125Y1253386D02*
Y-235999D01*
G01X1258268Y1066535D02*
G02X1275984I8858J0D01*
G02X1258268I-8858J0D01*
G01Y1263386D02*
G02X1275984I8858J0D01*
G02X1258268I-8858J0D01*
G01X1290630Y61614D02*
G02X1298504I3937J0D01*
G02X1290630I-3937J0D01*
G01X1298228Y1141024D02*
G02X1310827I6299J0D01*
G02X1298228I-6300J0D01*
G01X1302279Y1617502D02*
Y1626602D01*
X1385979D01*
Y1449502D01*
X1302279D01*
Y1617502D01*
G01X1336280Y70866D02*
G02X1358327I11023J0D01*
G02X1336280I-11024J0D01*
G01X1366535Y286220D02*
G02X1388583I11024J0D01*
G02X1366535I-11024J0D01*
G01Y765197D02*
G02X1388583I11024J0D01*
G02X1366535I-11024J0D01*
G01X1396142Y81575D02*
G02X1404016I3937J0D01*
G02X1396142I-3937J0D01*
G01X1420433Y1604724D02*
G02X1442480I11023J0D01*
G02X1420433I-11023J0D01*
G01X1440630Y61614D02*
G02X1448504I3937J0D01*
G02X1440630I-3937J0D01*
G01X1444291Y1086654D02*
G02X1456890I6300J0D01*
G02X1444291I-6299J0D01*
G01X1479134Y1066535D02*
G02X1496850I8858J0D01*
G02X1479134I-8858J0D01*
G01Y1263386D02*
G02X1496850I8858J0D01*
G02X1479134I-8858J0D01*
G01X1475507Y1617502D02*
Y1626602D01*
X1559207D01*
Y1449502D01*
X1475507D01*
Y1617502D01*
G01X1494241Y-330624D02*
Y-335274D01*
X1481741D01*
Y-330624D01*
G01X1494241Y-250024D02*
Y-245374D01*
X1481741D01*
Y-250024D01*
G01X1487991Y1253386D02*
Y-235999D01*
G01X1521135Y1697631D02*
X1496183Y1624222D01*
X1497908Y1626301D01*
X1496114Y1626823D01*
X1496183Y1624222D01*
G01X1498504Y81575D02*
G02X1506378I3937J0D01*
G02X1498504I-3937J0D01*
G01X1531307Y1696402D02*
X1506355Y1622993D01*
X1508080Y1625072D01*
X1506286Y1625594D01*
X1506355Y1622993D01*
G01X1542992Y61614D02*
G02X1550866I3937J0D01*
G02X1542992I-3937J0D01*
G01X1564823Y23622D02*
G02X1586870I11024J0D01*
G02X1564823I-11023J0D01*
G01X1600866Y81575D02*
G02X1608740I3937J0D01*
G02X1600866I-3937J0D01*
G01X1611801Y1580079D02*
G02X1599301I-6250J0D01*
G02X1611801I6250J0D01*
G01X1611762Y1606142D02*
G02X1599262I-6250J0D01*
G02X1611762I6250J0D01*
G01X1611801Y1626339D02*
G02X1599301I-6250J0D01*
G02X1611801I6250J0D01*
G01X1645354Y61614D02*
G02X1653228I3937J0D01*
G02X1645354I-3937J0D01*
G01X1648735Y1617502D02*
Y1626602D01*
X1732435D01*
Y1449502D01*
X1648735D01*
Y1617502D01*
G01X1694363Y1697631D02*
X1669411Y1624222D01*
X1671136Y1626301D01*
X1669342Y1626823D01*
X1669411Y1624222D01*
G01X1704535Y1696402D02*
X1679583Y1622993D01*
X1681308Y1625072D01*
X1679514Y1625594D01*
X1679583Y1622993D01*
G01X1703228Y81575D02*
G02X1711102I3937J0D01*
G02X1703228I-3937J0D01*
G01X1730462Y-332545D02*
Y-337195D01*
X1717962D01*
Y-332545D01*
G01X1730462Y-251945D02*
Y-247295D01*
X1717962D01*
Y-251945D01*
G01X1724212Y1253386D02*
Y-237920D01*
G01X1715354Y1066535D02*
G02X1733071I8859J0D01*
G02X1715354I-8858J0D01*
G01Y1263386D02*
G02X1733071I8859J0D01*
G02X1715354I-8858J0D01*
G01X1747717Y61614D02*
G02X1755591I3937J0D01*
G02X1747717I-3937J0D01*
G01X1755906Y333465D02*
G02X1777953I11023J0D01*
G02X1755906I-11023J0D01*
G01X1755315Y1215000D02*
G02X1767913I6299J0D01*
G02X1755315I-6299J0D01*
G01X1767717Y765197D02*
G02X1789764I11023J0D01*
G02X1767717I-11023J0D01*
G01X1781890Y-71487D02*
X1840945D01*
Y-102983D01*
X1781890D01*
Y-71487D01*
G01X1782728Y-78037D02*
Y-74937D01*
X1783648D01*
X1783955Y-75092D01*
X1784185Y-75454D01*
X1784262Y-75867D01*
X1784185Y-76280D01*
X1783993Y-76590D01*
X1783648Y-76745D01*
X1782728D01*
G01X1787438Y-75195D02*
X1787208Y-75040D01*
X1786940Y-74937D01*
X1786633D01*
X1786288Y-75092D01*
X1786020Y-75350D01*
X1785828Y-75660D01*
X1785675Y-76177D01*
X1785637Y-76642D01*
X1785713Y-77107D01*
X1785828Y-77417D01*
X1786058Y-77727D01*
X1786327Y-77934D01*
X1786595Y-78037D01*
X1786863D01*
X1787132Y-77934D01*
X1787362Y-77779D01*
X1787553Y-77572D01*
G01X1790002Y-76384D02*
X1790155Y-76229D01*
X1790270Y-75970D01*
X1790347Y-75609D01*
X1790270Y-75299D01*
X1790117Y-75092D01*
X1789848Y-74937D01*
X1788813D01*
Y-78037D01*
X1790078D01*
X1790347Y-77830D01*
X1790500Y-77520D01*
X1790577Y-77159D01*
X1790500Y-76797D01*
X1790270Y-76487D01*
X1790002Y-76384D01*
X1788813D01*
G01X1794937Y-74937D02*
X1795895Y-78037D01*
X1796853Y-74937D01*
G01X1799762Y-78037D02*
X1798228D01*
Y-74937D01*
X1799762D01*
G01X1799148Y-76435D02*
X1798228D01*
G01X1801213Y-78037D02*
Y-74937D01*
X1802977Y-78037D01*
Y-74937D01*
G01X1804352Y-78037D02*
Y-74937D01*
X1805118D01*
X1805425Y-75092D01*
X1805655Y-75299D01*
X1805847Y-75609D01*
X1806000Y-75970D01*
X1806038Y-76487D01*
X1806000Y-77004D01*
X1805847Y-77365D01*
X1805655Y-77675D01*
X1805425Y-77882D01*
X1805118Y-78037D01*
X1804352D01*
G01X1808295D02*
X1807988Y-77985D01*
X1807720Y-77779D01*
X1807490Y-77469D01*
X1807337Y-77107D01*
X1807260Y-76694D01*
Y-76280D01*
X1807337Y-75867D01*
X1807490Y-75505D01*
X1807720Y-75195D01*
X1807988Y-74989D01*
X1808295Y-74937D01*
X1808602Y-74989D01*
X1808870Y-75195D01*
X1809100Y-75505D01*
X1809253Y-75867D01*
X1809330Y-76280D01*
Y-76694D01*
X1809253Y-77107D01*
X1809100Y-77469D01*
X1808870Y-77779D01*
X1808602Y-77985D01*
X1808295Y-78037D01*
G01X1810628D02*
Y-74937D01*
X1811587D01*
X1811893Y-75092D01*
X1812085Y-75299D01*
X1812162Y-75712D01*
X1812085Y-76125D01*
X1811855Y-76384D01*
X1811587Y-76539D01*
X1810628D01*
G01X1811587D02*
X1812162Y-78037D01*
G01X1783986Y23622D02*
G02X1806033I11023J0D01*
G02X1783986I-11023J0D01*
G01X1790028Y-79937D02*
Y-83037D01*
X1791562D01*
G01X1793895D02*
X1793588Y-82985D01*
X1793320Y-82779D01*
X1793090Y-82469D01*
X1792937Y-82107D01*
X1792860Y-81694D01*
Y-81280D01*
X1792937Y-80867D01*
X1793090Y-80505D01*
X1793320Y-80195D01*
X1793588Y-79989D01*
X1793895Y-79937D01*
X1794202Y-79989D01*
X1794470Y-80195D01*
X1794700Y-80505D01*
X1794853Y-80867D01*
X1794930Y-81280D01*
Y-81694D01*
X1794853Y-82107D01*
X1794700Y-82469D01*
X1794470Y-82779D01*
X1794202Y-82985D01*
X1793895Y-83037D01*
G01X1797225Y-81487D02*
X1797992D01*
Y-82417D01*
X1797762Y-82727D01*
X1797493Y-82934D01*
X1797110Y-83037D01*
X1796727Y-82934D01*
X1796458Y-82727D01*
X1796228Y-82417D01*
X1796075Y-82055D01*
X1795998Y-81642D01*
Y-81280D01*
X1796075Y-80970D01*
X1796228Y-80609D01*
X1796458Y-80299D01*
X1796688Y-80092D01*
X1796995Y-79937D01*
X1797263D01*
X1797570Y-80040D01*
X1797800Y-80247D01*
G01X1800095Y-83037D02*
X1799788Y-82985D01*
X1799520Y-82779D01*
X1799290Y-82469D01*
X1799137Y-82107D01*
X1799060Y-81694D01*
Y-81280D01*
X1799137Y-80867D01*
X1799290Y-80505D01*
X1799520Y-80195D01*
X1799788Y-79989D01*
X1800095Y-79937D01*
X1800402Y-79989D01*
X1800670Y-80195D01*
X1800900Y-80505D01*
X1801053Y-80867D01*
X1801130Y-81280D01*
Y-81694D01*
X1801053Y-82107D01*
X1800900Y-82469D01*
X1800670Y-82779D01*
X1800402Y-82985D01*
X1800095Y-83037D01*
G01X1823425Y59843D02*
Y53543D01*
G02X1811220I-6103J0D01*
G01Y59843D01*
G02X1823425I6102J0D01*
G01X1824318Y55062D02*
X1817322Y53543D01*
X1824326Y52062D01*
X1824318Y55062D01*
G01X1817322Y53543D02*
X1847788Y53626D01*
G01X1820866Y1235630D02*
G02X1833465I6299J0D01*
G02X1820866I-6300J0D01*
G01X1811220Y1567323D02*
G02X1823425I6102J0D01*
G02X1811220I-6103J0D01*
G01X1806299Y1604724D02*
G02X1828346I11023J0D01*
G02X1806299I-11023J0D01*
G01X1833945Y1686571D02*
X1840945Y1688071D01*
X1833945Y1689571D01*
Y1686571D01*
G01D02*
X1840945Y1688071D01*
X1833945Y1689571D01*
Y1686571D01*
G01Y1846492D02*
X1840945Y1847992D01*
X1833945Y1849492D01*
Y1846492D01*
G01X1850945Y0D02*
X1890945D01*
G01X1850945Y1648071D02*
X1890945D01*
G01X1850945D02*
X1890945D01*
G01X1840945Y1657992D02*
Y1857992D01*
G01X1850945Y1647992D02*
X1890945D01*
G01X1880945Y706271D02*
Y0D01*
G01X1879445Y7000D02*
X1880945Y0D01*
X1882445Y7000D01*
X1879445D01*
G01X1880945Y821721D02*
Y1647992D01*
G01X1882445Y1640992D02*
X1880945Y1647992D01*
X1879445Y1640992D01*
X1882445D01*
G01X1899695Y723846D02*
Y719196D01*
X1887195D01*
Y723846D01*
G01X1899695Y804446D02*
Y809096D01*
X1887195D01*
Y804446D01*
G01X2209818Y1060285D02*
X2205168D01*
Y1072785D01*
X2209818D01*
G01X2219425Y1257136D02*
X2214775D01*
Y1269636D01*
X2219425D01*
G01X2270974Y382333D02*
X2266324D01*
Y394833D01*
X2270974D01*
G01X2278018Y1060285D02*
X2282668D01*
Y1072785D01*
X2278018D01*
G01X2287625Y1257136D02*
X2292275D01*
Y1269636D01*
X2287625D01*
G01X2326774Y382333D02*
X2331424D01*
Y394833D01*
X2326774D01*
G01X2530614Y2345901D02*
Y2495901D01*
X3280814D01*
Y2345901D01*
X2530614D01*
G01Y2370901D02*
X3280814D01*
G01X2530614Y2395901D02*
X3280814D01*
G01X2530614Y2420901D02*
X3280814D01*
G01X2530614Y2445901D02*
X3280814D01*
G01X2530614Y2470901D02*
X3280814D01*
G01X2544341Y2706213D02*
Y2856213D01*
X3294541D01*
Y2706213D01*
X2544341D01*
G01Y2731213D02*
X3294541D01*
G01X2544341Y2756213D02*
X3294541D01*
G01X2544341Y2781213D02*
X3294541D01*
G01X2544341Y2806213D02*
X3294541D01*
G01X2544341Y2831213D02*
X3294541D01*
G01X2564930Y1961566D02*
Y2111566D01*
X3315130D01*
Y1961566D01*
X2564930D01*
G01Y1986566D02*
X3315130D01*
G01X2564930Y2011566D02*
X3315130D01*
G01X2564930Y2036566D02*
X3315130D01*
G01X2564930Y2061566D02*
X3315130D01*
G01X2564930Y2086566D02*
X3315130D01*
G01X2599246Y1247803D02*
Y1397803D01*
X3349446D01*
Y1247803D01*
X2599246D01*
G01Y1272803D02*
X3349446D01*
G01X2599246Y1297803D02*
X3349446D01*
G01X2599246Y1322803D02*
X3349446D01*
G01X2599246Y1347803D02*
X3349446D01*
G01X2599246Y1372803D02*
X3349446D01*
G01X2599246Y1597821D02*
Y1747821D01*
X3349446D01*
Y1597821D01*
X2599246D01*
G01Y1622821D02*
X3349446D01*
G01X2599246Y1647821D02*
X3349446D01*
G01X2599246Y1672821D02*
X3349446D01*
G01X2599246Y1697821D02*
X3349446D01*
G01X2599246Y1722821D02*
X3349446D01*
G01X2620514Y2445901D02*
Y2345901D01*
G01X2634241Y2806213D02*
Y2706213D01*
G01X2654830Y2061566D02*
Y1961566D01*
G01X2689146Y1347803D02*
Y1247803D01*
G01Y1697821D02*
Y1597821D01*
G01X2740218Y-45962D02*
Y1056688D01*
X3766318D01*
Y-45962D01*
X2740218D01*
G01Y-12812D02*
X3766318D01*
G01X2740218Y20338D02*
X3766318D01*
G01X2740218Y53488D02*
X3766318D01*
G01X2740218Y86638D02*
X3766318D01*
G01X2740218Y119788D02*
X3766318D01*
G01X2740218Y152938D02*
X3766318D01*
G01X2740218Y186088D02*
X3766318D01*
G01X2740218Y219238D02*
X3766318D01*
G01X2740218Y252388D02*
X3766318D01*
G01X2740218Y285538D02*
X3766318D01*
G01X2740218Y318688D02*
X3766318D01*
G01X2740218Y351838D02*
X3766318D01*
G01X2740218Y384988D02*
X3766318D01*
G01X2740218Y418138D02*
X3766318D01*
G01X2740218Y451288D02*
X3766318D01*
G01X2740218Y484438D02*
X3766318D01*
G01X2740218Y517588D02*
X3766318D01*
G01X2740218Y550738D02*
X3766318D01*
G01X2740218Y583888D02*
X3766318D01*
G01X2740218Y617038D02*
X3766318D01*
G01X2740218Y650188D02*
X3766318D01*
G01X2740218Y683338D02*
X3766318D01*
G01X2740218Y716488D02*
X3766318D01*
G01X2740218Y749638D02*
X3766318D01*
G01X2740218Y782788D02*
X3766318D01*
G01X2740218Y815938D02*
X3766318D01*
G01X2740218Y849088D02*
X3766318D01*
G01X2740218Y882238D02*
X3766318D01*
G01X2740218Y915388D02*
X3766318D01*
G01X2740218Y948538D02*
X3766318D01*
G01X2740218Y981688D02*
X3766318D01*
G01X2740218Y1006688D02*
X3766318D01*
G01X2740218Y1031688D02*
X3766318D01*
G01X2747614Y2445901D02*
Y2345901D01*
G01X2761341Y2806213D02*
Y2706213D01*
G01X2781930Y2061566D02*
Y1961566D01*
G01X2816246Y1347803D02*
Y1247803D01*
G01Y1697821D02*
Y1597821D01*
G01X2830118Y1006688D02*
Y-45962D01*
G01X2949114Y2445901D02*
Y2345901D01*
G01X2962841Y2806213D02*
Y2706213D01*
G01X2983430Y2061566D02*
Y1961566D01*
G01X3017746Y1347803D02*
Y1247803D01*
G01Y1697821D02*
Y1597821D01*
G01X3031618Y1006688D02*
Y-45962D01*
G01X3076214Y2445901D02*
Y2345901D01*
G01X3089941Y2806213D02*
Y2706213D01*
G01X3110530Y2061566D02*
Y1961566D01*
G01X3144846Y1347803D02*
Y1247803D01*
G01Y1697821D02*
Y1597821D01*
G01X3158718Y1006688D02*
Y-45962D01*
G01X3203314Y2445901D02*
Y2345901D01*
G01X3217041Y2806213D02*
Y2706213D01*
G01X3237630Y2061566D02*
Y1961566D01*
G01X3271946Y1347803D02*
Y1247803D01*
G01Y1697821D02*
Y1597821D01*
G01X3360218Y1006688D02*
Y-45962D01*
G01X3413435Y2365416D02*
Y2465416D01*
X4163635D01*
Y2365416D01*
X3413435D01*
G01Y2390416D02*
X4163635D01*
G01X3413435Y2415416D02*
X4163635D01*
G01X3413435Y2440416D02*
X4163635D01*
G01X3418514Y1994736D02*
Y2094736D01*
X4168714D01*
Y1994736D01*
X3418514D01*
G01Y2019736D02*
X4168714D01*
G01X3418514Y2044736D02*
X4168714D01*
G01X3418514Y2069736D02*
X4168714D01*
G01X3436546Y2737098D02*
Y2887098D01*
X4186746D01*
Y2737098D01*
X3436546D01*
G01Y2762098D02*
X4186746D01*
G01X3436546Y2787098D02*
X4186746D01*
G01X3436546Y2812098D02*
X4186746D01*
G01X3436546Y2837098D02*
X4186746D01*
G01X3436546Y2862098D02*
X4186746D01*
G01X3448981Y1634212D02*
Y1734212D01*
X4199181D01*
Y1634212D01*
X3448981D01*
G01Y1659212D02*
X4199181D01*
G01X3448981Y1684212D02*
X4199181D01*
G01X3448981Y1709212D02*
X4199181D01*
G01X3508414Y2044736D02*
Y1994736D01*
G01X3503335Y2415416D02*
Y2365416D01*
G01X3526446Y2837098D02*
Y2737098D01*
G01X3538881Y1684212D02*
Y1634212D01*
G01X3561718Y1006688D02*
Y-45962D01*
G01X3635514Y2044736D02*
Y1994736D01*
G01X3630435Y2415416D02*
Y2365416D01*
G01X3653546Y2837098D02*
Y2737098D01*
G01X3665981Y1684212D02*
Y1634212D01*
G01X3688818Y1006688D02*
Y-45962D01*
G01X3831935Y2415416D02*
Y2365416D01*
G01X3837014Y2044736D02*
Y1994736D01*
G01X3867481Y1684212D02*
Y1634212D01*
G01X3855046Y2837098D02*
Y2737098D01*
G01X3964114Y2044736D02*
Y1994736D01*
G01X3959035Y2415416D02*
Y2365416D01*
G01X3982146Y2837098D02*
Y2737098D01*
G01X3994581Y1684212D02*
Y1634212D01*
G01X4091214Y2044736D02*
Y1994736D01*
G01X4086135Y2415416D02*
Y2365416D01*
G01X4109246Y2837098D02*
Y2737098D01*
G01X4121681Y1684212D02*
Y1634212D01*
G01X-1490433Y-1677216D02*
Y3837819D01*
X4496476D01*
Y-1677216D01*
X-1490433D01*
G01X-92529Y6250D02*
X-93769Y5833D01*
X-94699Y4792D01*
X-95319Y3542D01*
X-95784Y1875D01*
X-95939Y0D01*
X-95784Y-1875D01*
X-95319Y-3542D01*
X-94699Y-4792D01*
X-93769Y-5833D01*
X-92529Y-6250D01*
X-91289Y-5833D01*
X-90359Y-4792D01*
X-89739Y-3542D01*
X-89274Y-1875D01*
X-89119Y0D01*
X-89274Y1875D01*
X-89739Y3542D01*
X-90359Y4792D01*
X-91289Y5833D01*
X-92529Y6250D01*
G01X-57929D02*
X-59169Y5833D01*
X-60099Y4792D01*
X-60719Y3542D01*
X-61184Y1875D01*
X-61339Y0D01*
X-61184Y-1875D01*
X-60719Y-3542D01*
X-60099Y-4792D01*
X-59169Y-5833D01*
X-57929Y-6250D01*
X-56689Y-5833D01*
X-55759Y-4792D01*
X-55139Y-3542D01*
X-54674Y-1875D01*
X-54519Y0D01*
X-54674Y1875D01*
X-55139Y3542D01*
X-55759Y4792D01*
X-56689Y5833D01*
X-57929Y6250D01*
G01X-15913Y1541624D02*
X-23913D01*
X-15913Y1546224D01*
X-23913D01*
G01X-15913Y1549924D02*
X-23913D01*
Y1552324D01*
X-23513Y1553124D01*
X-22580Y1553724D01*
X-21513Y1553924D01*
X-20446Y1553724D01*
X-19646Y1553224D01*
X-19246Y1552324D01*
Y1549924D01*
G01X-23913Y1559924D02*
X-15913D01*
G01X-23913Y1557624D02*
Y1562224D01*
G01X-15913Y1565824D02*
X-23913D01*
G01Y1570024D02*
X-15913D01*
G01X-19913D02*
Y1565824D01*
G01X-23913Y1583924D02*
X-15913D01*
G01X-23913Y1581624D02*
Y1586224D01*
G01X-15913Y1591924D02*
X-16046Y1591124D01*
X-16580Y1590424D01*
X-17380Y1589824D01*
X-18313Y1589424D01*
X-19380Y1589224D01*
X-20446D01*
X-21513Y1589424D01*
X-22446Y1589824D01*
X-23246Y1590424D01*
X-23780Y1591124D01*
X-23913Y1591924D01*
X-23780Y1592724D01*
X-23246Y1593424D01*
X-22446Y1594024D01*
X-21513Y1594424D01*
X-20446Y1594624D01*
X-19380D01*
X-18313Y1594424D01*
X-17380Y1594024D01*
X-16580Y1593424D01*
X-16046Y1592724D01*
X-15913Y1591924D01*
G01X-23913Y1597924D02*
X-15913D01*
Y1601924D01*
G01Y1609924D02*
Y1605924D01*
X-23913D01*
Y1609924D01*
G01X-20046Y1608324D02*
Y1605924D01*
G01X-15913Y1613624D02*
X-23913D01*
X-15913Y1618224D01*
X-23913D01*
G01X-15913Y1621424D02*
X-23913Y1623924D01*
X-15913Y1626424D01*
G01X-18713Y1625524D02*
Y1622324D01*
G01X-15913Y1629624D02*
X-23913D01*
X-15913Y1634224D01*
X-23913D01*
G01X-23246Y1642124D02*
X-23646Y1641524D01*
X-23913Y1640824D01*
Y1640024D01*
X-23513Y1639124D01*
X-22846Y1638424D01*
X-22046Y1637924D01*
X-20713Y1637524D01*
X-19513Y1637424D01*
X-18313Y1637624D01*
X-17513Y1637924D01*
X-16713Y1638524D01*
X-16180Y1639224D01*
X-15913Y1639924D01*
Y1640624D01*
X-16180Y1641324D01*
X-16580Y1641924D01*
X-17113Y1642424D01*
G01X-15913Y1649924D02*
Y1645924D01*
X-23913D01*
Y1649924D01*
G01X-20046Y1648324D02*
Y1645924D01*
G01X-15646Y1655924D02*
X-15780Y1655724D01*
X-16046D01*
X-16180Y1655924D01*
X-16046Y1656124D01*
X-15780D01*
X-15646Y1655924D01*
G01X-19246D02*
X-19380Y1655724D01*
X-19646D01*
X-19780Y1655924D01*
X-19646Y1656124D01*
X-19380D01*
X-19246Y1655924D01*
G01X-18580Y1662824D02*
Y1665224D01*
G01X-20313Y1663924D02*
X-16846D01*
G01X-22580Y1670024D02*
X-23380Y1670624D01*
X-23780Y1671324D01*
X-23913Y1672124D01*
X-23646Y1673124D01*
X-22980Y1673824D01*
X-22180Y1674024D01*
X-21379Y1673924D01*
X-20713Y1673524D01*
X-19380Y1671524D01*
X-18446Y1670624D01*
X-17113Y1670024D01*
X-15913Y1669824D01*
Y1674024D01*
G01X-15646Y1678124D02*
X-23913Y1681724D01*
G01X-18580Y1686624D02*
Y1689224D01*
G01X-22580Y1694024D02*
X-23380Y1694624D01*
X-23780Y1695324D01*
X-23913Y1696124D01*
X-23646Y1697124D01*
X-22980Y1697824D01*
X-22180Y1698024D01*
X-21379Y1697924D01*
X-20713Y1697524D01*
X-19380Y1695524D01*
X-18446Y1694624D01*
X-17113Y1694024D01*
X-15913Y1693824D01*
Y1698024D01*
G01Y1708924D02*
X-21246D01*
G01X-19780D02*
X-20446Y1709224D01*
X-20980Y1709724D01*
X-21246Y1710424D01*
X-20980Y1711124D01*
X-20446Y1711624D01*
X-19780Y1711924D01*
X-15913D01*
G01X-19780D02*
X-20446Y1712224D01*
X-20980Y1712724D01*
X-21246Y1713424D01*
X-20980Y1714124D01*
X-20446Y1714624D01*
X-19646Y1714924D01*
X-15913D01*
G01X-21246Y1719924D02*
X-15913D01*
G01X-23380D02*
X-23513Y1719724D01*
X-23780D01*
X-23913Y1719924D01*
X-23780Y1720124D01*
X-23513D01*
X-23380Y1719924D01*
G01X-15913Y1727924D02*
X-23913D01*
G01X-7782Y-515685D02*
X-6215D01*
Y-517575D01*
X-6685Y-518205D01*
X-7234Y-518625D01*
X-8017Y-518835D01*
X-8800Y-518625D01*
X-9349Y-518205D01*
X-9819Y-517575D01*
X-10132Y-516840D01*
X-10289Y-516000D01*
Y-515265D01*
X-10132Y-514635D01*
X-9819Y-513900D01*
X-9349Y-513270D01*
X-8879Y-512850D01*
X-8252Y-512535D01*
X-7704D01*
X-7077Y-512745D01*
X-6607Y-513165D01*
G01X-3675Y-512535D02*
Y-517050D01*
X-3362Y-517995D01*
X-2735Y-518625D01*
X-1952Y-518835D01*
X-1169Y-518625D01*
X-542Y-517995D01*
X-229Y-517050D01*
Y-512535D01*
G01X3408D02*
X5288D01*
G01X4348D02*
Y-518835D01*
G01X3408D02*
X5288D01*
G01X9003Y-517995D02*
X9630Y-518520D01*
X10335Y-518835D01*
X10961D01*
X11588Y-518520D01*
X12058Y-517995D01*
X12293Y-517260D01*
X12136Y-516525D01*
X11745Y-515895D01*
X11040Y-515475D01*
X10100Y-515265D01*
X9551Y-514845D01*
X9316Y-514110D01*
X9473Y-513375D01*
X9865Y-512850D01*
X10413Y-512535D01*
X10961D01*
X11510Y-512745D01*
X11980Y-513270D01*
G01X15303Y-518835D02*
Y-512535D01*
G01X18593D02*
Y-518835D01*
G01Y-515685D02*
X15303D01*
G01X21290Y-518835D02*
X23248Y-512535D01*
X25206Y-518835D01*
G01X24501Y-516630D02*
X21995D01*
G01X27746Y-518835D02*
Y-512535D01*
X31350Y-518835D01*
Y-512535D01*
G01X40425Y-518835D02*
Y-512535D01*
X41991D01*
X42618Y-512850D01*
X43088Y-513270D01*
X43480Y-513900D01*
X43793Y-514635D01*
X43871Y-515685D01*
X43793Y-516735D01*
X43480Y-517470D01*
X43088Y-518100D01*
X42618Y-518520D01*
X41991Y-518835D01*
X40425D01*
G01X47508Y-512535D02*
X49388D01*
G01X48448D02*
Y-518835D01*
G01X47508D02*
X49388D01*
G01X53103Y-517995D02*
X53730Y-518520D01*
X54435Y-518835D01*
X55061D01*
X55688Y-518520D01*
X56158Y-517995D01*
X56393Y-517260D01*
X56236Y-516525D01*
X55845Y-515895D01*
X55140Y-515475D01*
X54200Y-515265D01*
X53651Y-514845D01*
X53416Y-514110D01*
X53573Y-513375D01*
X53965Y-512850D01*
X54513Y-512535D01*
X55061D01*
X55610Y-512745D01*
X56080Y-513270D01*
G01X61048Y-512535D02*
Y-518835D01*
G01X59246Y-512535D02*
X62850D01*
G01X67348Y-519045D02*
X67191Y-518940D01*
Y-518730D01*
X67348Y-518625D01*
X67505Y-518730D01*
Y-518940D01*
X67348Y-519045D01*
G01X73491Y-519990D02*
X73805Y-518625D01*
G01X79948Y-512535D02*
Y-518835D01*
G01X78146Y-512535D02*
X81750D01*
G01X84290Y-518835D02*
X86248Y-512535D01*
X88206Y-518835D01*
G01X87501Y-516630D02*
X84995D01*
G01X92548Y-518835D02*
X91921Y-518730D01*
X91373Y-518310D01*
X90903Y-517680D01*
X90590Y-516945D01*
X90433Y-516105D01*
Y-515265D01*
X90590Y-514425D01*
X90903Y-513690D01*
X91373Y-513060D01*
X91921Y-512640D01*
X92548Y-512535D01*
X93175Y-512640D01*
X93723Y-513060D01*
X94193Y-513690D01*
X94506Y-514425D01*
X94663Y-515265D01*
Y-516105D01*
X94506Y-516945D01*
X94193Y-517680D01*
X93723Y-518310D01*
X93175Y-518730D01*
X92548Y-518835D01*
G01X98848D02*
Y-516000D01*
X97281Y-512535D01*
G01X100415D02*
X98848Y-516000D01*
G01X103425Y-512535D02*
Y-517050D01*
X103738Y-517995D01*
X104365Y-518625D01*
X105148Y-518835D01*
X105931Y-518625D01*
X106558Y-517995D01*
X106871Y-517050D01*
Y-512535D01*
G01X109490Y-518835D02*
X111448Y-512535D01*
X113406Y-518835D01*
G01X112701Y-516630D02*
X110195D01*
G01X115946Y-518835D02*
Y-512535D01*
X119550Y-518835D01*
Y-512535D01*
G01X-6529Y-523060D02*
X-6999Y-522745D01*
X-7547Y-522535D01*
X-8174D01*
X-8879Y-522850D01*
X-9427Y-523375D01*
X-9819Y-524005D01*
X-10132Y-525055D01*
X-10210Y-526000D01*
X-10054Y-526945D01*
X-9819Y-527575D01*
X-9349Y-528205D01*
X-8800Y-528625D01*
X-8252Y-528835D01*
X-7704D01*
X-7155Y-528625D01*
X-6685Y-528310D01*
X-6294Y-527890D01*
G01X-2892Y-522535D02*
X-1012D01*
G01X-1952D02*
Y-528835D01*
G01X-2892D02*
X-1012D01*
G01X4348Y-522535D02*
Y-528835D01*
G01X2546Y-522535D02*
X6150D01*
G01X10648Y-528835D02*
Y-526000D01*
X9081Y-522535D01*
G01X12215D02*
X10648Y-526000D01*
G01X21525Y-527575D02*
X21995Y-528310D01*
X22621Y-528730D01*
X23326Y-528835D01*
X23953Y-528730D01*
X24580Y-528205D01*
X24971Y-527575D01*
X25050Y-526945D01*
X24893Y-526210D01*
X24345Y-525685D01*
X23796Y-525475D01*
X23091D01*
G01X23796D02*
X24266Y-525160D01*
X24658Y-524635D01*
X24815Y-524005D01*
X24658Y-523375D01*
X24266Y-522850D01*
X23561Y-522535D01*
X22856Y-522640D01*
X22151Y-523060D01*
G01X27825Y-527575D02*
X28295Y-528310D01*
X28921Y-528730D01*
X29626Y-528835D01*
X30253Y-528730D01*
X30880Y-528205D01*
X31271Y-527575D01*
X31350Y-526945D01*
X31193Y-526210D01*
X30645Y-525685D01*
X30096Y-525475D01*
X29391D01*
G01X30096D02*
X30566Y-525160D01*
X30958Y-524635D01*
X31115Y-524005D01*
X30958Y-523375D01*
X30566Y-522850D01*
X29861Y-522535D01*
X29156Y-522640D01*
X28451Y-523060D01*
G01X34125Y-527575D02*
X34595Y-528310D01*
X35221Y-528730D01*
X35926Y-528835D01*
X36553Y-528730D01*
X37180Y-528205D01*
X37571Y-527575D01*
X37650Y-526945D01*
X37493Y-526210D01*
X36945Y-525685D01*
X36396Y-525475D01*
X35691D01*
G01X36396D02*
X36866Y-525160D01*
X37258Y-524635D01*
X37415Y-524005D01*
X37258Y-523375D01*
X36866Y-522850D01*
X36161Y-522535D01*
X35456Y-522640D01*
X34751Y-523060D01*
G01X41991Y-528835D02*
X42148Y-527470D01*
X42383Y-526315D01*
X42696Y-525265D01*
X43088Y-524110D01*
X43715Y-522535D01*
X40581D01*
G01X48291Y-528835D02*
X48448Y-527470D01*
X48683Y-526315D01*
X48996Y-525265D01*
X49388Y-524110D01*
X50015Y-522535D01*
X46881D01*
G01X54591Y-529990D02*
X54905Y-528625D01*
G01X61048Y-522535D02*
Y-528835D01*
G01X59246Y-522535D02*
X62850D01*
G01X65390Y-528835D02*
X67348Y-522535D01*
X69306Y-528835D01*
G01X68601Y-526630D02*
X66095D01*
G01X72708Y-522535D02*
X74588D01*
G01X73648D02*
Y-528835D01*
G01X72708D02*
X74588D01*
G01X77598Y-522535D02*
X78695Y-528835D01*
X79948Y-522535D01*
X81201Y-528835D01*
X82298Y-522535D01*
G01X84290Y-528835D02*
X86248Y-522535D01*
X88206Y-528835D01*
G01X87501Y-526630D02*
X84995D01*
G01X90746Y-528835D02*
Y-522535D01*
X94350Y-528835D01*
Y-522535D01*
G01X104756Y-530935D02*
X103973Y-529885D01*
X103581Y-528835D01*
Y-524635D01*
X103973Y-523585D01*
X104756Y-522535D01*
G01X116181Y-528835D02*
Y-522535D01*
X118140D01*
X118766Y-522850D01*
X119158Y-523270D01*
X119315Y-524110D01*
X119158Y-524950D01*
X118688Y-525475D01*
X118140Y-525790D01*
X116181D01*
G01X118140D02*
X119315Y-528835D01*
G01X124048Y-529045D02*
X123891Y-528940D01*
Y-528730D01*
X124048Y-528625D01*
X124205Y-528730D01*
Y-528940D01*
X124048Y-529045D01*
G01X130348Y-528835D02*
X129721Y-528730D01*
X129173Y-528310D01*
X128703Y-527680D01*
X128390Y-526945D01*
X128233Y-526105D01*
Y-525265D01*
X128390Y-524425D01*
X128703Y-523690D01*
X129173Y-523060D01*
X129721Y-522640D01*
X130348Y-522535D01*
X130975Y-522640D01*
X131523Y-523060D01*
X131993Y-523690D01*
X132306Y-524425D01*
X132463Y-525265D01*
Y-526105D01*
X132306Y-526945D01*
X131993Y-527680D01*
X131523Y-528310D01*
X130975Y-528730D01*
X130348Y-528835D01*
G01X136648Y-529045D02*
X136491Y-528940D01*
Y-528730D01*
X136648Y-528625D01*
X136805Y-528730D01*
Y-528940D01*
X136648Y-529045D01*
G01X144671Y-523060D02*
X144201Y-522745D01*
X143653Y-522535D01*
X143026D01*
X142321Y-522850D01*
X141773Y-523375D01*
X141381Y-524005D01*
X141068Y-525055D01*
X140990Y-526000D01*
X141146Y-526945D01*
X141381Y-527575D01*
X141851Y-528205D01*
X142400Y-528625D01*
X142948Y-528835D01*
X143496D01*
X144045Y-528625D01*
X144515Y-528310D01*
X144906Y-527890D01*
G01X149248Y-529045D02*
X149091Y-528940D01*
Y-528730D01*
X149248Y-528625D01*
X149405Y-528730D01*
Y-528940D01*
X149248Y-529045D01*
G01X155940Y-530935D02*
X156723Y-529885D01*
X157115Y-528835D01*
Y-524635D01*
X156723Y-523585D01*
X155940Y-522535D01*
G01X-10054Y-508835D02*
Y-502535D01*
X-6450Y-508835D01*
Y-502535D01*
G01X-1952Y-508835D02*
X-2579Y-508730D01*
X-3127Y-508310D01*
X-3597Y-507680D01*
X-3910Y-506945D01*
X-4067Y-506105D01*
Y-505265D01*
X-3910Y-504425D01*
X-3597Y-503690D01*
X-3127Y-503060D01*
X-2579Y-502640D01*
X-1952Y-502535D01*
X-1325Y-502640D01*
X-777Y-503060D01*
X-307Y-503690D01*
X6Y-504425D01*
X163Y-505265D01*
Y-506105D01*
X6Y-506945D01*
X-307Y-507680D01*
X-777Y-508310D01*
X-1325Y-508730D01*
X-1952Y-508835D01*
G01X4348Y-509045D02*
X4191Y-508940D01*
Y-508730D01*
X4348Y-508625D01*
X4505Y-508730D01*
Y-508940D01*
X4348Y-509045D01*
G01X9160Y-503585D02*
X9630Y-502955D01*
X10178Y-502640D01*
X10805Y-502535D01*
X11588Y-502745D01*
X12136Y-503270D01*
X12293Y-503900D01*
X12215Y-504530D01*
X11901Y-505055D01*
X10335Y-506105D01*
X9630Y-506840D01*
X9160Y-507890D01*
X9003Y-508835D01*
X12293D01*
G01X16948D02*
Y-502535D01*
X16008Y-503795D01*
G01Y-508835D02*
X17888D01*
G01X23248D02*
Y-502535D01*
X22308Y-503795D01*
G01Y-508835D02*
X24188D01*
G01X29391Y-509990D02*
X29705Y-508625D01*
G01X33498Y-502535D02*
X34595Y-508835D01*
X35848Y-502535D01*
X37101Y-508835D01*
X38198Y-502535D01*
G01X43715Y-508835D02*
X40581D01*
Y-502535D01*
X43715D01*
G01X42461Y-505580D02*
X40581D01*
G01X46646Y-508835D02*
Y-502535D01*
X50250Y-508835D01*
Y-502535D01*
G01X53103Y-508835D02*
Y-502535D01*
G01X56393D02*
Y-508835D01*
G01Y-505685D02*
X53103D01*
G01X59325Y-502535D02*
Y-507050D01*
X59638Y-507995D01*
X60265Y-508625D01*
X61048Y-508835D01*
X61831Y-508625D01*
X62458Y-507995D01*
X62771Y-507050D01*
Y-502535D01*
G01X65390Y-508835D02*
X67348Y-502535D01*
X69306Y-508835D01*
G01X68601Y-506630D02*
X66095D01*
G01X78460Y-503585D02*
X78930Y-502955D01*
X79478Y-502640D01*
X80105Y-502535D01*
X80888Y-502745D01*
X81436Y-503270D01*
X81593Y-503900D01*
X81515Y-504530D01*
X81201Y-505055D01*
X79635Y-506105D01*
X78930Y-506840D01*
X78460Y-507890D01*
X78303Y-508835D01*
X81593D01*
G01X84446D02*
Y-502535D01*
X88050Y-508835D01*
Y-502535D01*
G01X90825Y-508835D02*
Y-502535D01*
X92391D01*
X93018Y-502850D01*
X93488Y-503270D01*
X93880Y-503900D01*
X94193Y-504635D01*
X94271Y-505685D01*
X94193Y-506735D01*
X93880Y-507470D01*
X93488Y-508100D01*
X93018Y-508520D01*
X92391Y-508835D01*
X90825D01*
G01X103581D02*
Y-502535D01*
X105540D01*
X106166Y-502850D01*
X106558Y-503270D01*
X106715Y-504110D01*
X106558Y-504950D01*
X106088Y-505475D01*
X105540Y-505790D01*
X103581D01*
G01X105540D02*
X106715Y-508835D01*
G01X109725D02*
Y-502535D01*
X111291D01*
X111918Y-502850D01*
X112388Y-503270D01*
X112780Y-503900D01*
X113093Y-504635D01*
X113171Y-505685D01*
X113093Y-506735D01*
X112780Y-507470D01*
X112388Y-508100D01*
X111918Y-508520D01*
X111291Y-508835D01*
X109725D01*
G01X117748Y-509045D02*
X117591Y-508940D01*
Y-508730D01*
X117748Y-508625D01*
X117905Y-508730D01*
Y-508940D01*
X117748Y-509045D01*
G01X-6250Y-93532D02*
X-5833Y-94772D01*
X-4792Y-95702D01*
X-3542Y-96322D01*
X-1875Y-96787D01*
X0Y-96942D01*
X1875Y-96787D01*
X3542Y-96322D01*
X4792Y-95702D01*
X5833Y-94772D01*
X6250Y-93532D01*
X5833Y-92292D01*
X4792Y-91362D01*
X3542Y-90742D01*
X1875Y-90277D01*
X0Y-90122D01*
X-1875Y-90277D01*
X-3542Y-90742D01*
X-4792Y-91362D01*
X-5833Y-92292D01*
X-6250Y-93532D01*
G01Y-58932D02*
X-5833Y-60172D01*
X-4792Y-61102D01*
X-3542Y-61722D01*
X-1875Y-62187D01*
X0Y-62342D01*
X1875Y-62187D01*
X3542Y-61722D01*
X4792Y-61102D01*
X5833Y-60172D01*
X6250Y-58932D01*
X5833Y-57692D01*
X4792Y-56762D01*
X3542Y-56142D01*
X1875Y-55677D01*
X0Y-55522D01*
X-1875Y-55677D01*
X-3542Y-56142D01*
X-4792Y-56762D01*
X-5833Y-57692D01*
X-6250Y-58932D01*
G01X14048Y-498135D02*
X11528Y-497718D01*
X9323Y-496052D01*
X7433Y-493552D01*
X6173Y-490635D01*
X5543Y-487302D01*
Y-483968D01*
X6173Y-480635D01*
X7433Y-477718D01*
X9323Y-475219D01*
X11528Y-473552D01*
X14048Y-473135D01*
X16568Y-473552D01*
X18773Y-475219D01*
X20663Y-477718D01*
X21923Y-480635D01*
X22553Y-483968D01*
Y-487302D01*
X21923Y-490635D01*
X20663Y-493552D01*
X18773Y-496052D01*
X16568Y-497718D01*
X14048Y-498135D01*
G01X16568Y-491468D02*
X20348Y-498135D01*
G01X33893Y-481469D02*
Y-493135D01*
X35153Y-496052D01*
X37043Y-497718D01*
X39248Y-498135D01*
X41453Y-497718D01*
X43343Y-496052D01*
X44603Y-493135D01*
G01Y-498135D02*
Y-481469D01*
G01X70118Y-498135D02*
Y-481469D01*
G01Y-484385D02*
X68858Y-482719D01*
X66968Y-481885D01*
X64763Y-481469D01*
X62558Y-482302D01*
X60668Y-483968D01*
X59408Y-486469D01*
X58778Y-489802D01*
X59408Y-493135D01*
X60668Y-495636D01*
X62558Y-497302D01*
X64763Y-498135D01*
X66968Y-497718D01*
X68858Y-496469D01*
X70118Y-494802D01*
G01X84293Y-498135D02*
Y-481469D01*
G01Y-485635D02*
X85553Y-483552D01*
X87443Y-481885D01*
X89963Y-481469D01*
X92168Y-481885D01*
X94058Y-483552D01*
X95003Y-486469D01*
Y-498135D01*
G01X114848Y-473135D02*
Y-498135D01*
G01X110438Y-481469D02*
X119258D01*
G01X145718Y-498135D02*
Y-481469D01*
G01Y-484385D02*
X144458Y-482719D01*
X142568Y-481885D01*
X140363Y-481469D01*
X138158Y-482302D01*
X136268Y-483968D01*
X135008Y-486469D01*
X134378Y-489802D01*
X135008Y-493135D01*
X136268Y-495636D01*
X138158Y-497302D01*
X140363Y-498135D01*
X142568Y-497718D01*
X144458Y-496469D01*
X145718Y-494802D01*
G01X93213Y957081D02*
Y964581D01*
X95453D01*
X96200Y964206D01*
X96760Y963331D01*
X96947Y962331D01*
X96760Y961331D01*
X96293Y960581D01*
X95453Y960206D01*
X93213D01*
G01X104633Y963956D02*
X104073Y964331D01*
X103420Y964581D01*
X102673D01*
X101833Y964206D01*
X101180Y963581D01*
X100713Y962831D01*
X100340Y961581D01*
X100247Y960456D01*
X100433Y959331D01*
X100713Y958581D01*
X101273Y957831D01*
X101927Y957331D01*
X102580Y957081D01*
X103233D01*
X103887Y957331D01*
X104447Y957706D01*
X104913Y958206D01*
G01X110827Y961081D02*
X111200Y961456D01*
X111480Y962081D01*
X111667Y962956D01*
X111480Y963706D01*
X111107Y964206D01*
X110453Y964581D01*
X107933D01*
Y957081D01*
X111013D01*
X111667Y957581D01*
X112040Y958331D01*
X112227Y959206D01*
X112040Y960081D01*
X111480Y960831D01*
X110827Y961081D01*
X107933D01*
G01X122747Y964581D02*
X125080Y957081D01*
X127413Y964581D01*
G01X134447Y957081D02*
X130713D01*
Y964581D01*
X134447D01*
G01X132953Y960956D02*
X130713D01*
G01X137933Y957081D02*
Y964581D01*
X142227Y957081D01*
Y964581D01*
G01X145527Y957081D02*
Y964581D01*
X147393D01*
X148140Y964206D01*
X148700Y963706D01*
X149167Y962956D01*
X149540Y962081D01*
X149633Y960831D01*
X149540Y959581D01*
X149167Y958706D01*
X148700Y957956D01*
X148140Y957456D01*
X147393Y957081D01*
X145527D01*
G01X155080D02*
X154333Y957206D01*
X153680Y957706D01*
X153120Y958456D01*
X152747Y959331D01*
X152560Y960331D01*
Y961331D01*
X152747Y962331D01*
X153120Y963206D01*
X153680Y963956D01*
X154333Y964456D01*
X155080Y964581D01*
X155827Y964456D01*
X156480Y963956D01*
X157040Y963206D01*
X157413Y962331D01*
X157600Y961331D01*
Y960331D01*
X157413Y959331D01*
X157040Y958456D01*
X156480Y957706D01*
X155827Y957206D01*
X155080Y957081D01*
G01X160713D02*
Y964581D01*
X163047D01*
X163793Y964206D01*
X164260Y963706D01*
X164447Y962706D01*
X164260Y961706D01*
X163700Y961081D01*
X163047Y960706D01*
X160713D01*
G01X163047D02*
X164447Y957081D01*
G01X115713Y948833D02*
Y941333D01*
X119447D01*
G01X125080D02*
X124333Y941458D01*
X123680Y941958D01*
X123120Y942708D01*
X122747Y943583D01*
X122560Y944583D01*
Y945583D01*
X122747Y946583D01*
X123120Y947458D01*
X123680Y948208D01*
X124333Y948708D01*
X125080Y948833D01*
X125827Y948708D01*
X126480Y948208D01*
X127040Y947458D01*
X127413Y946583D01*
X127600Y945583D01*
Y944583D01*
X127413Y943583D01*
X127040Y942708D01*
X126480Y941958D01*
X125827Y941458D01*
X125080Y941333D01*
G01X133140Y945083D02*
X135007D01*
Y942833D01*
X134447Y942083D01*
X133793Y941583D01*
X132860Y941333D01*
X131927Y941583D01*
X131273Y942083D01*
X130713Y942833D01*
X130340Y943708D01*
X130153Y944708D01*
Y945583D01*
X130340Y946333D01*
X130713Y947208D01*
X131273Y947958D01*
X131833Y948458D01*
X132580Y948833D01*
X133233D01*
X133980Y948583D01*
X134540Y948083D01*
G01X140080Y941333D02*
X139333Y941458D01*
X138680Y941958D01*
X138120Y942708D01*
X137747Y943583D01*
X137560Y944583D01*
Y945583D01*
X137747Y946583D01*
X138120Y947458D01*
X138680Y948208D01*
X139333Y948708D01*
X140080Y948833D01*
X140827Y948708D01*
X141480Y948208D01*
X142040Y947458D01*
X142413Y946583D01*
X142600Y945583D01*
Y944583D01*
X142413Y943583D01*
X142040Y942708D01*
X141480Y941958D01*
X140827Y941458D01*
X140080Y941333D01*
G01X120995Y1457835D02*
G03I-2452J0D01*
G01X112333Y1453504D02*
G03I-2451J0D01*
G01X120995Y1473189D02*
G03I-2452J0D01*
G01X112334Y1468859D02*
G03I-2452J0D01*
G01X112333Y1499567D02*
G03I-2451J0D01*
G01X120995Y1488544D02*
G03I-2452J0D01*
G01X112334Y1484213D02*
G03I-2452J0D01*
G01Y1514922D02*
G03I-2452J0D01*
G01X120995Y1503898D02*
G03I-2452J0D01*
G01Y1519252D02*
G03I-2452J0D01*
G01X112334Y1555867D02*
G03I-2452J0D01*
G01X120995Y1560197D02*
G03I-2452J0D01*
G01Y1575552D02*
G03I-2452J0D01*
G01X112334Y1571221D02*
G03I-2452J0D01*
G01X120995Y1590906D02*
G03I-2452J0D01*
G01X112334Y1586575D02*
G03I-2452J0D01*
G01X120995Y1606260D02*
G03I-2452J0D01*
G01X112334Y1601930D02*
G03I-2452J0D01*
G01X120995Y1621615D02*
G03I-2452J0D01*
G01X112334Y1617284D02*
G03I-2452J0D01*
G01X129493Y-422157D02*
X116993D01*
X119493Y-424017D01*
G01X129493D02*
Y-420297D01*
G01Y-409757D02*
X116993D01*
X119493Y-411617D01*
G01X129493D02*
Y-407897D01*
G01X124285Y-400302D02*
X122826Y-399217D01*
X121993Y-398287D01*
X121576Y-397047D01*
X121993Y-395962D01*
X122826Y-395187D01*
X124076Y-394567D01*
X125535Y-394412D01*
X126785Y-394567D01*
X128035Y-395187D01*
X129076Y-396117D01*
X129493Y-397202D01*
X129076Y-398442D01*
X127827Y-399527D01*
X125951Y-400147D01*
X123868Y-400302D01*
X121160Y-399992D01*
X119701Y-399527D01*
X118243Y-398752D01*
X117201Y-397667D01*
X116993Y-396582D01*
X117410Y-395497D01*
X118451Y-394722D01*
G01X129493Y-385267D02*
X126785Y-384957D01*
X124493Y-384492D01*
X122410Y-383872D01*
X120118Y-383097D01*
X116993Y-381857D01*
Y-388057D01*
G01X129910Y-372557D02*
X129701Y-372867D01*
X129285D01*
X129076Y-372557D01*
X129285Y-372247D01*
X129701D01*
X129910Y-372557D01*
G01X126993Y-363567D02*
X128452Y-362637D01*
X129285Y-361397D01*
X129493Y-360002D01*
X129285Y-358762D01*
X128243Y-357522D01*
X126993Y-356747D01*
X125743Y-356592D01*
X124285Y-356902D01*
X123243Y-357987D01*
X122826Y-359072D01*
Y-360467D01*
G01Y-359072D02*
X122201Y-358142D01*
X121160Y-357367D01*
X119910Y-357057D01*
X118660Y-357367D01*
X117618Y-358142D01*
X116993Y-359537D01*
X117201Y-360932D01*
X118035Y-362327D01*
G01X129493Y-347757D02*
X116993D01*
X119493Y-349617D01*
G01X129493D02*
Y-345897D01*
G01X119076Y-316102D02*
X117827Y-315172D01*
X117201Y-314087D01*
X116993Y-312847D01*
X117410Y-311297D01*
X118451Y-310212D01*
X119701Y-309902D01*
X120952Y-310057D01*
X121993Y-310677D01*
X124076Y-313777D01*
X125535Y-315172D01*
X127618Y-316102D01*
X129493Y-316412D01*
Y-309902D01*
G01X128035Y-303392D02*
X129076Y-302307D01*
X129493Y-301067D01*
X129076Y-299827D01*
X127827Y-298742D01*
X125951Y-297967D01*
X124076Y-297657D01*
X121785D01*
X119910Y-297967D01*
X118243Y-298742D01*
X117410Y-299672D01*
X116993Y-300757D01*
X117410Y-301997D01*
X118243Y-302927D01*
X119493Y-303547D01*
X121160Y-303857D01*
X122618Y-303547D01*
X124076Y-302772D01*
X124910Y-301842D01*
X125118Y-300757D01*
X124702Y-299517D01*
X123660Y-298587D01*
X121785Y-297657D01*
G01X129910Y-288357D02*
X129701Y-288667D01*
X129285D01*
X129076Y-288357D01*
X129285Y-288047D01*
X129701D01*
X129910Y-288357D01*
G01X124285Y-278902D02*
X122826Y-277817D01*
X121993Y-276887D01*
X121576Y-275647D01*
X121993Y-274562D01*
X122826Y-273787D01*
X124076Y-273167D01*
X125535Y-273012D01*
X126785Y-273167D01*
X128035Y-273787D01*
X129076Y-274717D01*
X129493Y-275802D01*
X129076Y-277042D01*
X127827Y-278127D01*
X125951Y-278747D01*
X123868Y-278902D01*
X121160Y-278592D01*
X119701Y-278127D01*
X118243Y-277352D01*
X117201Y-276267D01*
X116993Y-275182D01*
X117410Y-274097D01*
X118451Y-273322D01*
G01X127618Y-266967D02*
X128660Y-266037D01*
X129285Y-264952D01*
X129493Y-263557D01*
X129076Y-262162D01*
X128243Y-261077D01*
X126785Y-260302D01*
X125118Y-260147D01*
X123451Y-260457D01*
X122410Y-261232D01*
X121576Y-262317D01*
X121368Y-263402D01*
X121576Y-264487D01*
X122410Y-265882D01*
X116993Y-265417D01*
Y-261232D01*
G01X129656Y1453504D02*
G03I-2451J0D01*
G01X129657Y1468859D02*
G03I-2452J0D01*
G01X129656Y1499567D02*
G03I-2451J0D01*
G01X129657Y1484213D02*
G03I-2452J0D01*
G01Y1514922D02*
G03I-2452J0D01*
G01Y1555867D02*
G03I-2452J0D01*
G01Y1571221D02*
G03I-2452J0D01*
G01Y1586575D02*
G03I-2452J0D01*
G01Y1601930D02*
G03I-2452J0D01*
G01Y1617284D02*
G03I-2452J0D01*
G01X146979Y1453504D02*
G03I-2451J0D01*
G01X138318Y1457835D02*
G03I-2452J0D01*
G01X146980Y1468859D02*
G03I-2452J0D01*
G01X138318Y1473189D02*
G03I-2452J0D01*
G01X146979Y1499567D02*
G03I-2451J0D01*
G01X146980Y1484213D02*
G03I-2452J0D01*
G01X138318Y1488544D02*
G03I-2452J0D01*
G01X146980Y1514922D02*
G03I-2452J0D01*
G01X138318Y1503898D02*
G03I-2452J0D01*
G01Y1519252D02*
G03I-2452J0D01*
G01X146980Y1555867D02*
G03I-2452J0D01*
G01X138318Y1560197D02*
G03I-2452J0D01*
G01X146980Y1571221D02*
G03I-2452J0D01*
G01X138318Y1575552D02*
G03I-2452J0D01*
G01X146979Y1586575D02*
G03I-2451J0D01*
G01X138318Y1590906D02*
G03I-2452J0D01*
G01X146980Y1601930D02*
G03I-2452J0D01*
G01X138318Y1606260D02*
G03I-2452J0D01*
G01X146980Y1617284D02*
G03I-2452J0D01*
G01X138318Y1621615D02*
G03I-2452J0D01*
G01X156208Y1699724D02*
X148708D01*
X156208Y1704018D01*
X148708D01*
G01X156208Y1709371D02*
X156083Y1708624D01*
X155583Y1707971D01*
X154833Y1707411D01*
X153958Y1707038D01*
X152958Y1706851D01*
X151958D01*
X150958Y1707038D01*
X150083Y1707411D01*
X149333Y1707971D01*
X148833Y1708624D01*
X148708Y1709371D01*
X148833Y1710118D01*
X149333Y1710771D01*
X150083Y1711331D01*
X150958Y1711704D01*
X151958Y1711891D01*
X152958D01*
X153958Y1711704D01*
X154833Y1711331D01*
X155583Y1710771D01*
X156083Y1710118D01*
X156208Y1709371D01*
G01Y1714724D02*
X148708D01*
X156208Y1719018D01*
X148708D01*
G01X153708Y1723158D02*
Y1725584D01*
G01X156208Y1729444D02*
X148708D01*
X154958Y1731871D01*
X148708Y1734298D01*
X156208D01*
G01Y1737038D02*
X148708Y1739371D01*
X156208Y1741704D01*
G01X153583Y1740864D02*
Y1737878D01*
G01X156208Y1745004D02*
X148708D01*
Y1747338D01*
X149083Y1748084D01*
X149583Y1748551D01*
X150583Y1748738D01*
X151583Y1748551D01*
X152208Y1747991D01*
X152583Y1747338D01*
Y1745004D01*
G01Y1747338D02*
X156208Y1748738D01*
G01Y1752318D02*
X148708D01*
G01Y1755864D02*
X153333Y1752318D01*
G01X156208Y1756424D02*
X151208Y1753904D01*
G01X156458Y1761871D02*
X156333Y1761684D01*
X156083D01*
X155958Y1761871D01*
X156083Y1762058D01*
X156333D01*
X156458Y1761871D01*
G01X153083D02*
X152958Y1761684D01*
X152708D01*
X152583Y1761871D01*
X152708Y1762058D01*
X152958D01*
X153083Y1761871D01*
G01X156208Y1767504D02*
X148708D01*
Y1769838D01*
X149083Y1770584D01*
X149583Y1771051D01*
X150583Y1771238D01*
X151583Y1771051D01*
X152208Y1770491D01*
X152583Y1769838D01*
Y1767504D01*
G01Y1769838D02*
X156208Y1771238D01*
G01Y1778738D02*
Y1775004D01*
X148708D01*
Y1778738D01*
G01X152333Y1777244D02*
Y1775004D01*
G01X149333Y1786424D02*
X148958Y1785864D01*
X148708Y1785211D01*
Y1784464D01*
X149083Y1783624D01*
X149708Y1782971D01*
X150458Y1782504D01*
X151708Y1782131D01*
X152833Y1782038D01*
X153958Y1782224D01*
X154708Y1782504D01*
X155458Y1783064D01*
X155958Y1783718D01*
X156208Y1784371D01*
Y1785024D01*
X155958Y1785678D01*
X155583Y1786238D01*
X155083Y1786704D01*
G01X156208Y1791871D02*
X156083Y1791124D01*
X155583Y1790471D01*
X154833Y1789911D01*
X153958Y1789538D01*
X152958Y1789351D01*
X151958D01*
X150958Y1789538D01*
X150083Y1789911D01*
X149333Y1790471D01*
X148833Y1791124D01*
X148708Y1791871D01*
X148833Y1792618D01*
X149333Y1793271D01*
X150083Y1793831D01*
X150958Y1794204D01*
X151958Y1794391D01*
X152958D01*
X153958Y1794204D01*
X154833Y1793831D01*
X155583Y1793271D01*
X156083Y1792618D01*
X156208Y1791871D01*
G01Y1796944D02*
X148708D01*
X154958Y1799371D01*
X148708Y1801798D01*
X156208D01*
G01Y1804444D02*
X148708D01*
X154958Y1806871D01*
X148708Y1809298D01*
X156208D01*
G01Y1816238D02*
Y1812504D01*
X148708D01*
Y1816238D01*
G01X152333Y1814744D02*
Y1812504D01*
G01X156208Y1819724D02*
X148708D01*
X156208Y1824018D01*
X148708D01*
G01X156208Y1827318D02*
X148708D01*
Y1829184D01*
X149083Y1829931D01*
X149583Y1830491D01*
X150333Y1830958D01*
X151208Y1831331D01*
X152458Y1831424D01*
X153708Y1831331D01*
X154583Y1830958D01*
X155333Y1830491D01*
X155833Y1829931D01*
X156208Y1829184D01*
Y1827318D01*
G01Y1838738D02*
Y1835004D01*
X148708D01*
Y1838738D01*
G01X152333Y1837244D02*
Y1835004D01*
G01X156208Y1842318D02*
X148708D01*
Y1844184D01*
X149083Y1844931D01*
X149583Y1845491D01*
X150333Y1845958D01*
X151208Y1846331D01*
X152458Y1846424D01*
X153708Y1846331D01*
X154583Y1845958D01*
X155333Y1845491D01*
X155833Y1844931D01*
X156208Y1844184D01*
Y1842318D01*
G01Y1857318D02*
X148708D01*
Y1859184D01*
X149083Y1859931D01*
X149583Y1860491D01*
X150333Y1860958D01*
X151208Y1861331D01*
X152458Y1861424D01*
X153708Y1861331D01*
X154583Y1860958D01*
X155333Y1860491D01*
X155833Y1859931D01*
X156208Y1859184D01*
Y1857318D01*
G01Y1865004D02*
X148708D01*
Y1867338D01*
X149083Y1868084D01*
X149583Y1868551D01*
X150583Y1868738D01*
X151583Y1868551D01*
X152208Y1867991D01*
X152583Y1867338D01*
Y1865004D01*
G01Y1867338D02*
X156208Y1868738D01*
G01X148708Y1873251D02*
Y1875491D01*
G01Y1874371D02*
X156208D01*
G01Y1873251D02*
Y1875491D01*
G01X148708Y1880004D02*
X156208D01*
Y1883738D01*
G01X148708Y1887504D02*
X156208D01*
Y1891238D01*
G01X155208Y1902411D02*
X155833Y1903158D01*
X156208Y1903998D01*
Y1904744D01*
X155833Y1905491D01*
X155208Y1906051D01*
X154333Y1906331D01*
X153458Y1906144D01*
X152708Y1905678D01*
X152208Y1904838D01*
X151958Y1903718D01*
X151458Y1903064D01*
X150583Y1902784D01*
X149708Y1902971D01*
X149083Y1903438D01*
X148708Y1904091D01*
Y1904744D01*
X148958Y1905398D01*
X149583Y1905958D01*
G01X148708Y1910751D02*
Y1912991D01*
G01Y1911871D02*
X156208D01*
G01Y1910751D02*
Y1912991D01*
G01X148708Y1917598D02*
Y1921144D01*
X156208Y1917598D01*
Y1921144D01*
G01Y1928738D02*
Y1925004D01*
X148708D01*
Y1928738D01*
G01X152333Y1927244D02*
Y1925004D01*
G01X156208Y1940098D02*
X148708D01*
Y1943644D01*
G01X152333Y1942338D02*
Y1940098D01*
G01X156208Y1949371D02*
X156083Y1948624D01*
X155583Y1947971D01*
X154833Y1947411D01*
X153958Y1947038D01*
X152958Y1946851D01*
X151958D01*
X150958Y1947038D01*
X150083Y1947411D01*
X149333Y1947971D01*
X148833Y1948624D01*
X148708Y1949371D01*
X148833Y1950118D01*
X149333Y1950771D01*
X150083Y1951331D01*
X150958Y1951704D01*
X151958Y1951891D01*
X152958D01*
X153958Y1951704D01*
X154833Y1951331D01*
X155583Y1950771D01*
X156083Y1950118D01*
X156208Y1949371D01*
G01Y1955004D02*
X148708D01*
Y1957338D01*
X149083Y1958084D01*
X149583Y1958551D01*
X150583Y1958738D01*
X151583Y1958551D01*
X152208Y1957991D01*
X152583Y1957338D01*
Y1955004D01*
G01Y1957338D02*
X156208Y1958738D01*
G01X148708Y1971871D02*
X148958Y1971124D01*
X149583Y1970564D01*
X150333Y1970191D01*
X151333Y1969911D01*
X152458Y1969818D01*
X153583Y1969911D01*
X154583Y1970191D01*
X155333Y1970564D01*
X155958Y1971124D01*
X156208Y1971871D01*
X155958Y1972618D01*
X155333Y1973178D01*
X154583Y1973551D01*
X153583Y1973831D01*
X152458Y1973924D01*
X151333Y1973831D01*
X150333Y1973551D01*
X149583Y1973178D01*
X148958Y1972618D01*
X148708Y1971871D01*
G01X156458Y1979371D02*
X156333Y1979184D01*
X156083D01*
X155958Y1979371D01*
X156083Y1979558D01*
X156333D01*
X156458Y1979371D01*
G01X154708Y1984818D02*
X155583Y1985378D01*
X156083Y1986124D01*
X156208Y1986964D01*
X156083Y1987711D01*
X155458Y1988458D01*
X154708Y1988924D01*
X153958Y1989018D01*
X153083Y1988831D01*
X152458Y1988178D01*
X152208Y1987524D01*
Y1986684D01*
G01Y1987524D02*
X151833Y1988084D01*
X151208Y1988551D01*
X150458Y1988738D01*
X149708Y1988551D01*
X149083Y1988084D01*
X148708Y1987244D01*
X148833Y1986404D01*
X149333Y1985564D01*
G01X156208Y1994371D02*
X148708D01*
X150208Y1993251D01*
G01X156208D02*
Y1995491D01*
G01Y1999444D02*
X148708D01*
X154958Y2001871D01*
X148708Y2004298D01*
X156208D01*
G01Y2006944D02*
X148708D01*
X154958Y2009371D01*
X148708Y2011798D01*
X156208D01*
G01Y2022598D02*
X148708D01*
Y2026144D01*
G01X152333Y2024838D02*
Y2022598D01*
G01X148708Y2030751D02*
Y2032991D01*
G01Y2031871D02*
X156208D01*
G01Y2030751D02*
Y2032991D01*
G01Y2037224D02*
X148708D01*
X156208Y2041518D01*
X148708D01*
G01Y2045751D02*
Y2047991D01*
G01Y2046871D02*
X156208D01*
G01Y2045751D02*
Y2047991D01*
G01X155208Y2052411D02*
X155833Y2053158D01*
X156208Y2053998D01*
Y2054744D01*
X155833Y2055491D01*
X155208Y2056051D01*
X154333Y2056331D01*
X153458Y2056144D01*
X152708Y2055678D01*
X152208Y2054838D01*
X151958Y2053718D01*
X151458Y2053064D01*
X150583Y2052784D01*
X149708Y2052971D01*
X149083Y2053438D01*
X148708Y2054091D01*
Y2054744D01*
X148958Y2055398D01*
X149583Y2055958D01*
G01X156208Y2059911D02*
X148708D01*
G01Y2063831D02*
X156208D01*
G01X152458D02*
Y2059911D01*
G01X156208Y2071238D02*
Y2067504D01*
X148708D01*
Y2071238D01*
G01X152333Y2069744D02*
Y2067504D01*
G01X156208Y2074818D02*
X148708D01*
Y2076684D01*
X149083Y2077431D01*
X149583Y2077991D01*
X150333Y2078458D01*
X151208Y2078831D01*
X152458Y2078924D01*
X153708Y2078831D01*
X154583Y2078458D01*
X155333Y2077991D01*
X155833Y2077431D01*
X156208Y2076684D01*
Y2074818D01*
G01Y2090004D02*
X148708D01*
Y2092244D01*
X149083Y2092991D01*
X149958Y2093551D01*
X150958Y2093738D01*
X151958Y2093551D01*
X152708Y2093084D01*
X153083Y2092244D01*
Y2090004D01*
G01X148708Y2099371D02*
X156208D01*
G01X148708Y2097224D02*
Y2101518D01*
G01X156208Y2104911D02*
X148708D01*
G01Y2108831D02*
X156208D01*
G01X152458D02*
Y2104911D01*
G01X148708Y2120751D02*
Y2122991D01*
G01Y2121871D02*
X156208D01*
G01Y2120751D02*
Y2122991D01*
G01X155208Y2127411D02*
X155833Y2128158D01*
X156208Y2128998D01*
Y2129744D01*
X155833Y2130491D01*
X155208Y2131051D01*
X154333Y2131331D01*
X153458Y2131144D01*
X152708Y2130678D01*
X152208Y2129838D01*
X151958Y2128718D01*
X151458Y2128064D01*
X150583Y2127784D01*
X149708Y2127971D01*
X149083Y2128438D01*
X148708Y2129091D01*
Y2129744D01*
X148958Y2130398D01*
X149583Y2130958D01*
G01X148708Y2144371D02*
X148958Y2143624D01*
X149583Y2143064D01*
X150333Y2142691D01*
X151333Y2142411D01*
X152458Y2142318D01*
X153583Y2142411D01*
X154583Y2142691D01*
X155333Y2143064D01*
X155958Y2143624D01*
X156208Y2144371D01*
X155958Y2145118D01*
X155333Y2145678D01*
X154583Y2146051D01*
X153583Y2146331D01*
X152458Y2146424D01*
X151333Y2146331D01*
X150333Y2146051D01*
X149583Y2145678D01*
X148958Y2145118D01*
X148708Y2144371D01*
G01X156458Y2151871D02*
X156333Y2151684D01*
X156083D01*
X155958Y2151871D01*
X156083Y2152058D01*
X156333D01*
X156458Y2151871D01*
G01X156208Y2160491D02*
X148708D01*
X154083Y2157038D01*
Y2161704D01*
G01X156208Y2164444D02*
X148708D01*
X154958Y2166871D01*
X148708Y2169298D01*
X156208D01*
G01Y2171944D02*
X148708D01*
X154958Y2174371D01*
X148708Y2176798D01*
X156208D01*
G01Y2186944D02*
X148708D01*
X154958Y2189371D01*
X148708Y2191798D01*
X156208D01*
G01Y2198738D02*
Y2195004D01*
X148708D01*
Y2198738D01*
G01X152333Y2197244D02*
Y2195004D01*
G01X148708Y2204371D02*
X156208D01*
G01X148708Y2202224D02*
Y2206518D01*
G01X156208Y2210004D02*
X148708D01*
Y2212338D01*
X149083Y2213084D01*
X149583Y2213551D01*
X150583Y2213738D01*
X151583Y2213551D01*
X152208Y2212991D01*
X152583Y2212338D01*
Y2210004D01*
G01Y2212338D02*
X156208Y2213738D01*
G01X148708Y2218251D02*
Y2220491D01*
G01Y2219371D02*
X156208D01*
G01Y2218251D02*
Y2220491D01*
G01X149333Y2228924D02*
X148958Y2228364D01*
X148708Y2227711D01*
Y2226964D01*
X149083Y2226124D01*
X149708Y2225471D01*
X150458Y2225004D01*
X151708Y2224631D01*
X152833Y2224538D01*
X153958Y2224724D01*
X154708Y2225004D01*
X155458Y2225564D01*
X155958Y2226218D01*
X156208Y2226871D01*
Y2227524D01*
X155958Y2228178D01*
X155583Y2228738D01*
X155083Y2229204D01*
G01X156208Y2239818D02*
X148708D01*
Y2241684D01*
X149083Y2242431D01*
X149583Y2242991D01*
X150333Y2243458D01*
X151208Y2243831D01*
X152458Y2243924D01*
X153708Y2243831D01*
X154583Y2243458D01*
X155333Y2242991D01*
X155833Y2242431D01*
X156208Y2241684D01*
Y2239818D01*
G01Y2247504D02*
X148708D01*
Y2249838D01*
X149083Y2250584D01*
X149583Y2251051D01*
X150583Y2251238D01*
X151583Y2251051D01*
X152208Y2250491D01*
X152583Y2249838D01*
Y2247504D01*
G01Y2249838D02*
X156208Y2251238D01*
G01X148708Y2255751D02*
Y2257991D01*
G01Y2256871D02*
X156208D01*
G01Y2255751D02*
Y2257991D01*
G01X148708Y2262504D02*
X156208D01*
Y2266238D01*
G01X148708Y2270004D02*
X156208D01*
Y2273738D01*
G01X158708Y2278904D02*
X157458Y2277971D01*
X156208Y2277504D01*
X151208D01*
X149958Y2277971D01*
X148708Y2278904D01*
G01Y2286871D02*
X148958Y2286124D01*
X149583Y2285564D01*
X150333Y2285191D01*
X151333Y2284911D01*
X152458Y2284818D01*
X153583Y2284911D01*
X154583Y2285191D01*
X155333Y2285564D01*
X155958Y2286124D01*
X156208Y2286871D01*
X155958Y2287618D01*
X155333Y2288178D01*
X154583Y2288551D01*
X153583Y2288831D01*
X152458Y2288924D01*
X151333Y2288831D01*
X150333Y2288551D01*
X149583Y2288178D01*
X148958Y2287618D01*
X148708Y2286871D01*
G01X156458Y2294371D02*
X156333Y2294184D01*
X156083D01*
X155958Y2294371D01*
X156083Y2294558D01*
X156333D01*
X156458Y2294371D01*
G01X148708Y2301871D02*
X148958Y2301124D01*
X149583Y2300564D01*
X150333Y2300191D01*
X151333Y2299911D01*
X152458Y2299818D01*
X153583Y2299911D01*
X154583Y2300191D01*
X155333Y2300564D01*
X155958Y2301124D01*
X156208Y2301871D01*
X155958Y2302618D01*
X155333Y2303178D01*
X154583Y2303551D01*
X153583Y2303831D01*
X152458Y2303924D01*
X151333Y2303831D01*
X150333Y2303551D01*
X149583Y2303178D01*
X148958Y2302618D01*
X148708Y2301871D01*
G01X156208Y2309371D02*
X148708D01*
X150208Y2308251D01*
G01X156208D02*
Y2310491D01*
G01X155083Y2314818D02*
X155708Y2315378D01*
X156083Y2316031D01*
X156208Y2316871D01*
X155958Y2317711D01*
X155458Y2318364D01*
X154583Y2318831D01*
X153583Y2318924D01*
X152583Y2318738D01*
X151958Y2318271D01*
X151458Y2317618D01*
X151333Y2316964D01*
X151458Y2316311D01*
X151958Y2315471D01*
X148708Y2315751D01*
Y2318271D01*
G01X156208Y2324184D02*
X154583Y2324371D01*
X153208Y2324651D01*
X151958Y2325024D01*
X150583Y2325491D01*
X148708Y2326238D01*
Y2322504D01*
G01X150333Y2331031D02*
X148708Y2331498D01*
G01Y2332711D02*
X150333Y2332244D01*
G01X158708Y2339838D02*
X157458Y2340771D01*
X156208Y2341238D01*
X151208D01*
X149958Y2340771D01*
X148708Y2339838D01*
G01X164302Y1453504D02*
G03I-2451J0D01*
G01X155641Y1457835D02*
G03I-2452J0D01*
G01X164302Y1468859D02*
G03I-2451J0D01*
G01X155641Y1473189D02*
G03I-2452J0D01*
G01X164302Y1499567D02*
G03I-2451J0D01*
G01Y1484213D02*
G03I-2451J0D01*
G01X155641Y1488544D02*
G03I-2452J0D01*
G01X164302Y1514922D02*
G03I-2451J0D01*
G01X155641Y1503898D02*
G03I-2452J0D01*
G01Y1519252D02*
G03I-2452J0D01*
G01X164302Y1555867D02*
G03I-2451J0D01*
G01X155641Y1560197D02*
G03I-2452J0D01*
G01X164302Y1571221D02*
G03I-2451J0D01*
G01X155641Y1575552D02*
G03I-2452J0D01*
G01X164302Y1586575D02*
G03I-2451J0D01*
G01X155641Y1590906D02*
G03I-2452J0D01*
G01X164302Y1601930D02*
G03I-2451J0D01*
G01X155641Y1606260D02*
G03I-2452J0D01*
G01X164302Y1617284D02*
G03I-2451J0D01*
G01X155641Y1621615D02*
G03I-2452J0D01*
G01X168866Y1698581D02*
X161366D01*
X167616Y1701008D01*
X161366Y1703435D01*
X168866D01*
G01Y1706175D02*
X161366Y1708508D01*
X168866Y1710841D01*
G01X166241Y1710001D02*
Y1707015D01*
G01X168866Y1714141D02*
X161366D01*
Y1716475D01*
X161741Y1717221D01*
X162241Y1717688D01*
X163241Y1717875D01*
X164241Y1717688D01*
X164866Y1717128D01*
X165241Y1716475D01*
Y1714141D01*
G01Y1716475D02*
X168866Y1717875D01*
G01Y1721455D02*
X161366D01*
G01Y1725001D02*
X165991Y1721455D01*
G01X168866Y1725561D02*
X163866Y1723041D01*
G01X169116Y1731008D02*
X168991Y1730821D01*
X168741D01*
X168616Y1731008D01*
X168741Y1731195D01*
X168991D01*
X169116Y1731008D01*
G01X165741D02*
X165616Y1730821D01*
X165366D01*
X165241Y1731008D01*
X165366Y1731195D01*
X165616D01*
X165741Y1731008D01*
G01X168866Y1736641D02*
X161366D01*
Y1738975D01*
X161741Y1739721D01*
X162241Y1740188D01*
X163241Y1740375D01*
X164241Y1740188D01*
X164866Y1739628D01*
X165241Y1738975D01*
Y1736641D01*
G01Y1738975D02*
X168866Y1740375D01*
G01Y1747875D02*
Y1744141D01*
X161366D01*
Y1747875D01*
G01X164991Y1746381D02*
Y1744141D01*
G01X161991Y1755561D02*
X161616Y1755001D01*
X161366Y1754348D01*
Y1753601D01*
X161741Y1752761D01*
X162366Y1752108D01*
X163116Y1751641D01*
X164366Y1751268D01*
X165491Y1751175D01*
X166616Y1751361D01*
X167366Y1751641D01*
X168116Y1752201D01*
X168616Y1752855D01*
X168866Y1753508D01*
Y1754161D01*
X168616Y1754815D01*
X168241Y1755375D01*
X167741Y1755841D01*
G01X168866Y1761008D02*
X168741Y1760261D01*
X168241Y1759608D01*
X167491Y1759048D01*
X166616Y1758675D01*
X165616Y1758488D01*
X164616D01*
X163616Y1758675D01*
X162741Y1759048D01*
X161991Y1759608D01*
X161491Y1760261D01*
X161366Y1761008D01*
X161491Y1761755D01*
X161991Y1762408D01*
X162741Y1762968D01*
X163616Y1763341D01*
X164616Y1763528D01*
X165616D01*
X166616Y1763341D01*
X167491Y1762968D01*
X168241Y1762408D01*
X168741Y1761755D01*
X168866Y1761008D01*
G01Y1766081D02*
X161366D01*
X167616Y1768508D01*
X161366Y1770935D01*
X168866D01*
G01Y1773581D02*
X161366D01*
X167616Y1776008D01*
X161366Y1778435D01*
X168866D01*
G01Y1785375D02*
Y1781641D01*
X161366D01*
Y1785375D01*
G01X164991Y1783881D02*
Y1781641D01*
G01X168866Y1788861D02*
X161366D01*
X168866Y1793155D01*
X161366D01*
G01X168866Y1796455D02*
X161366D01*
Y1798321D01*
X161741Y1799068D01*
X162241Y1799628D01*
X162991Y1800095D01*
X163866Y1800468D01*
X165116Y1800561D01*
X166366Y1800468D01*
X167241Y1800095D01*
X167991Y1799628D01*
X168491Y1799068D01*
X168866Y1798321D01*
Y1796455D01*
G01Y1807875D02*
Y1804141D01*
X161366D01*
Y1807875D01*
G01X164991Y1806381D02*
Y1804141D01*
G01X168866Y1811455D02*
X161366D01*
Y1813321D01*
X161741Y1814068D01*
X162241Y1814628D01*
X162991Y1815095D01*
X163866Y1815468D01*
X165116Y1815561D01*
X166366Y1815468D01*
X167241Y1815095D01*
X167991Y1814628D01*
X168491Y1814068D01*
X168866Y1813321D01*
Y1811455D01*
G01Y1826455D02*
X161366D01*
Y1828321D01*
X161741Y1829068D01*
X162241Y1829628D01*
X162991Y1830095D01*
X163866Y1830468D01*
X165116Y1830561D01*
X166366Y1830468D01*
X167241Y1830095D01*
X167991Y1829628D01*
X168491Y1829068D01*
X168866Y1828321D01*
Y1826455D01*
G01Y1834141D02*
X161366D01*
Y1836475D01*
X161741Y1837221D01*
X162241Y1837688D01*
X163241Y1837875D01*
X164241Y1837688D01*
X164866Y1837128D01*
X165241Y1836475D01*
Y1834141D01*
G01Y1836475D02*
X168866Y1837875D01*
G01X161366Y1842388D02*
Y1844628D01*
G01Y1843508D02*
X168866D01*
G01Y1842388D02*
Y1844628D01*
G01X161366Y1849141D02*
X168866D01*
Y1852875D01*
G01X161366Y1856641D02*
X168866D01*
Y1860375D01*
G01X167866Y1871548D02*
X168491Y1872295D01*
X168866Y1873135D01*
Y1873881D01*
X168491Y1874628D01*
X167866Y1875188D01*
X166991Y1875468D01*
X166116Y1875281D01*
X165366Y1874815D01*
X164866Y1873975D01*
X164616Y1872855D01*
X164116Y1872201D01*
X163241Y1871921D01*
X162366Y1872108D01*
X161741Y1872575D01*
X161366Y1873228D01*
Y1873881D01*
X161616Y1874535D01*
X162241Y1875095D01*
G01X161366Y1879888D02*
Y1882128D01*
G01Y1881008D02*
X168866D01*
G01Y1879888D02*
Y1882128D01*
G01X161366Y1886735D02*
Y1890281D01*
X168866Y1886735D01*
Y1890281D01*
G01Y1897875D02*
Y1894141D01*
X161366D01*
Y1897875D01*
G01X164991Y1896381D02*
Y1894141D01*
G01X168866Y1909235D02*
X161366D01*
Y1912781D01*
G01X164991Y1911475D02*
Y1909235D01*
G01X168866Y1918508D02*
X168741Y1917761D01*
X168241Y1917108D01*
X167491Y1916548D01*
X166616Y1916175D01*
X165616Y1915988D01*
X164616D01*
X163616Y1916175D01*
X162741Y1916548D01*
X161991Y1917108D01*
X161491Y1917761D01*
X161366Y1918508D01*
X161491Y1919255D01*
X161991Y1919908D01*
X162741Y1920468D01*
X163616Y1920841D01*
X164616Y1921028D01*
X165616D01*
X166616Y1920841D01*
X167491Y1920468D01*
X168241Y1919908D01*
X168741Y1919255D01*
X168866Y1918508D01*
G01Y1924141D02*
X161366D01*
Y1926475D01*
X161741Y1927221D01*
X162241Y1927688D01*
X163241Y1927875D01*
X164241Y1927688D01*
X164866Y1927128D01*
X165241Y1926475D01*
Y1924141D01*
G01Y1926475D02*
X168866Y1927875D01*
G01X161366Y1941008D02*
X161616Y1940261D01*
X162241Y1939701D01*
X162991Y1939328D01*
X163991Y1939048D01*
X165116Y1938955D01*
X166241Y1939048D01*
X167241Y1939328D01*
X167991Y1939701D01*
X168616Y1940261D01*
X168866Y1941008D01*
X168616Y1941755D01*
X167991Y1942315D01*
X167241Y1942688D01*
X166241Y1942968D01*
X165116Y1943061D01*
X163991Y1942968D01*
X162991Y1942688D01*
X162241Y1942315D01*
X161616Y1941755D01*
X161366Y1941008D01*
G01X169116Y1948508D02*
X168991Y1948321D01*
X168741D01*
X168616Y1948508D01*
X168741Y1948695D01*
X168991D01*
X169116Y1948508D01*
G01X167741Y1953955D02*
X168366Y1954515D01*
X168741Y1955168D01*
X168866Y1956008D01*
X168616Y1956848D01*
X168116Y1957501D01*
X167241Y1957968D01*
X166241Y1958061D01*
X165241Y1957875D01*
X164616Y1957408D01*
X164116Y1956755D01*
X163991Y1956101D01*
X164116Y1955448D01*
X164616Y1954608D01*
X161366Y1954888D01*
Y1957408D01*
G01X168866Y1961081D02*
X161366D01*
X167616Y1963508D01*
X161366Y1965935D01*
X168866D01*
G01Y1968581D02*
X161366D01*
X167616Y1971008D01*
X161366Y1973435D01*
X168866D01*
G01Y1984235D02*
X161366D01*
Y1987781D01*
G01X164991Y1986475D02*
Y1984235D01*
G01X161366Y1992388D02*
Y1994628D01*
G01Y1993508D02*
X168866D01*
G01Y1992388D02*
Y1994628D01*
G01Y1998861D02*
X161366D01*
X168866Y2003155D01*
X161366D01*
G01Y2007388D02*
Y2009628D01*
G01Y2008508D02*
X168866D01*
G01Y2007388D02*
Y2009628D01*
G01X167866Y2014048D02*
X168491Y2014795D01*
X168866Y2015635D01*
Y2016381D01*
X168491Y2017128D01*
X167866Y2017688D01*
X166991Y2017968D01*
X166116Y2017781D01*
X165366Y2017315D01*
X164866Y2016475D01*
X164616Y2015355D01*
X164116Y2014701D01*
X163241Y2014421D01*
X162366Y2014608D01*
X161741Y2015075D01*
X161366Y2015728D01*
Y2016381D01*
X161616Y2017035D01*
X162241Y2017595D01*
G01X168866Y2021548D02*
X161366D01*
G01Y2025468D02*
X168866D01*
G01X165116D02*
Y2021548D01*
G01X168866Y2032875D02*
Y2029141D01*
X161366D01*
Y2032875D01*
G01X164991Y2031381D02*
Y2029141D01*
G01X168866Y2036455D02*
X161366D01*
Y2038321D01*
X161741Y2039068D01*
X162241Y2039628D01*
X162991Y2040095D01*
X163866Y2040468D01*
X165116Y2040561D01*
X166366Y2040468D01*
X167241Y2040095D01*
X167991Y2039628D01*
X168491Y2039068D01*
X168866Y2038321D01*
Y2036455D01*
G01Y2051641D02*
X161366D01*
Y2053881D01*
X161741Y2054628D01*
X162616Y2055188D01*
X163616Y2055375D01*
X164616Y2055188D01*
X165366Y2054721D01*
X165741Y2053881D01*
Y2051641D01*
G01X161366Y2061008D02*
X168866D01*
G01X161366Y2058861D02*
Y2063155D01*
G01X168866Y2066548D02*
X161366D01*
G01Y2070468D02*
X168866D01*
G01X165116D02*
Y2066548D01*
G01X161366Y2082388D02*
Y2084628D01*
G01Y2083508D02*
X168866D01*
G01Y2082388D02*
Y2084628D01*
G01X167866Y2089048D02*
X168491Y2089795D01*
X168866Y2090635D01*
Y2091381D01*
X168491Y2092128D01*
X167866Y2092688D01*
X166991Y2092968D01*
X166116Y2092781D01*
X165366Y2092315D01*
X164866Y2091475D01*
X164616Y2090355D01*
X164116Y2089701D01*
X163241Y2089421D01*
X162366Y2089608D01*
X161741Y2090075D01*
X161366Y2090728D01*
Y2091381D01*
X161616Y2092035D01*
X162241Y2092595D01*
G01X161366Y2106008D02*
X161616Y2105261D01*
X162241Y2104701D01*
X162991Y2104328D01*
X163991Y2104048D01*
X165116Y2103955D01*
X166241Y2104048D01*
X167241Y2104328D01*
X167991Y2104701D01*
X168616Y2105261D01*
X168866Y2106008D01*
X168616Y2106755D01*
X167991Y2107315D01*
X167241Y2107688D01*
X166241Y2107968D01*
X165116Y2108061D01*
X163991Y2107968D01*
X162991Y2107688D01*
X162241Y2107315D01*
X161616Y2106755D01*
X161366Y2106008D01*
G01X169116Y2113508D02*
X168991Y2113321D01*
X168741D01*
X168616Y2113508D01*
X168741Y2113695D01*
X168991D01*
X169116Y2113508D01*
G01X165741Y2119235D02*
X164866Y2119888D01*
X164366Y2120448D01*
X164116Y2121195D01*
X164366Y2121848D01*
X164866Y2122315D01*
X165616Y2122688D01*
X166491Y2122781D01*
X167241Y2122688D01*
X167991Y2122315D01*
X168616Y2121755D01*
X168866Y2121101D01*
X168616Y2120355D01*
X167866Y2119701D01*
X166741Y2119328D01*
X165491Y2119235D01*
X163866Y2119421D01*
X162991Y2119701D01*
X162116Y2120168D01*
X161491Y2120821D01*
X161366Y2121475D01*
X161616Y2122128D01*
X162241Y2122595D01*
G01X168866Y2126081D02*
X161366D01*
X167616Y2128508D01*
X161366Y2130935D01*
X168866D01*
G01Y2133581D02*
X161366D01*
X167616Y2136008D01*
X161366Y2138435D01*
X168866D01*
G01Y2148581D02*
X161366D01*
X167616Y2151008D01*
X161366Y2153435D01*
X168866D01*
G01Y2160375D02*
Y2156641D01*
X161366D01*
Y2160375D01*
G01X164991Y2158881D02*
Y2156641D01*
G01X161366Y2166008D02*
X168866D01*
G01X161366Y2163861D02*
Y2168155D01*
G01X168866Y2171641D02*
X161366D01*
Y2173975D01*
X161741Y2174721D01*
X162241Y2175188D01*
X163241Y2175375D01*
X164241Y2175188D01*
X164866Y2174628D01*
X165241Y2173975D01*
Y2171641D01*
G01Y2173975D02*
X168866Y2175375D01*
G01X161366Y2179888D02*
Y2182128D01*
G01Y2181008D02*
X168866D01*
G01Y2179888D02*
Y2182128D01*
G01X161991Y2190561D02*
X161616Y2190001D01*
X161366Y2189348D01*
Y2188601D01*
X161741Y2187761D01*
X162366Y2187108D01*
X163116Y2186641D01*
X164366Y2186268D01*
X165491Y2186175D01*
X166616Y2186361D01*
X167366Y2186641D01*
X168116Y2187201D01*
X168616Y2187855D01*
X168866Y2188508D01*
Y2189161D01*
X168616Y2189815D01*
X168241Y2190375D01*
X167741Y2190841D01*
G01X168866Y2201455D02*
X161366D01*
Y2203321D01*
X161741Y2204068D01*
X162241Y2204628D01*
X162991Y2205095D01*
X163866Y2205468D01*
X165116Y2205561D01*
X166366Y2205468D01*
X167241Y2205095D01*
X167991Y2204628D01*
X168491Y2204068D01*
X168866Y2203321D01*
Y2201455D01*
G01Y2209141D02*
X161366D01*
Y2211475D01*
X161741Y2212221D01*
X162241Y2212688D01*
X163241Y2212875D01*
X164241Y2212688D01*
X164866Y2212128D01*
X165241Y2211475D01*
Y2209141D01*
G01Y2211475D02*
X168866Y2212875D01*
G01X161366Y2217388D02*
Y2219628D01*
G01Y2218508D02*
X168866D01*
G01Y2217388D02*
Y2219628D01*
G01X161366Y2224141D02*
X168866D01*
Y2227875D01*
G01X161366Y2231641D02*
X168866D01*
Y2235375D01*
G01X171366Y2240541D02*
X170116Y2239608D01*
X168866Y2239141D01*
X163866D01*
X162616Y2239608D01*
X161366Y2240541D01*
G01Y2248508D02*
X161616Y2247761D01*
X162241Y2247201D01*
X162991Y2246828D01*
X163991Y2246548D01*
X165116Y2246455D01*
X166241Y2246548D01*
X167241Y2246828D01*
X167991Y2247201D01*
X168616Y2247761D01*
X168866Y2248508D01*
X168616Y2249255D01*
X167991Y2249815D01*
X167241Y2250188D01*
X166241Y2250468D01*
X165116Y2250561D01*
X163991Y2250468D01*
X162991Y2250188D01*
X162241Y2249815D01*
X161616Y2249255D01*
X161366Y2248508D01*
G01X169116Y2256008D02*
X168991Y2255821D01*
X168741D01*
X168616Y2256008D01*
X168741Y2256195D01*
X168991D01*
X169116Y2256008D01*
G01X161366Y2263508D02*
X161616Y2262761D01*
X162241Y2262201D01*
X162991Y2261828D01*
X163991Y2261548D01*
X165116Y2261455D01*
X166241Y2261548D01*
X167241Y2261828D01*
X167991Y2262201D01*
X168616Y2262761D01*
X168866Y2263508D01*
X168616Y2264255D01*
X167991Y2264815D01*
X167241Y2265188D01*
X166241Y2265468D01*
X165116Y2265561D01*
X163991Y2265468D01*
X162991Y2265188D01*
X162241Y2264815D01*
X161616Y2264255D01*
X161366Y2263508D01*
G01X162616Y2269235D02*
X161866Y2269795D01*
X161491Y2270448D01*
X161366Y2271195D01*
X161616Y2272128D01*
X162241Y2272781D01*
X162991Y2272968D01*
X163741Y2272875D01*
X164366Y2272501D01*
X165616Y2270635D01*
X166491Y2269795D01*
X167741Y2269235D01*
X168866Y2269048D01*
Y2272968D01*
G01X167366Y2276455D02*
X168241Y2277015D01*
X168741Y2277761D01*
X168866Y2278601D01*
X168741Y2279348D01*
X168116Y2280095D01*
X167366Y2280561D01*
X166616Y2280655D01*
X165741Y2280468D01*
X165116Y2279815D01*
X164866Y2279161D01*
Y2278321D01*
G01Y2279161D02*
X164491Y2279721D01*
X163866Y2280188D01*
X163116Y2280375D01*
X162366Y2280188D01*
X161741Y2279721D01*
X161366Y2278881D01*
X161491Y2278041D01*
X161991Y2277201D01*
G01X165741Y2284235D02*
X164866Y2284888D01*
X164366Y2285448D01*
X164116Y2286195D01*
X164366Y2286848D01*
X164866Y2287315D01*
X165616Y2287688D01*
X166491Y2287781D01*
X167241Y2287688D01*
X167991Y2287315D01*
X168616Y2286755D01*
X168866Y2286101D01*
X168616Y2285355D01*
X167866Y2284701D01*
X166741Y2284328D01*
X165491Y2284235D01*
X163866Y2284421D01*
X162991Y2284701D01*
X162116Y2285168D01*
X161491Y2285821D01*
X161366Y2286475D01*
X161616Y2287128D01*
X162241Y2287595D01*
G01X162991Y2292668D02*
X161366Y2293135D01*
G01Y2294348D02*
X162991Y2293881D01*
G01X171366Y2301475D02*
X170116Y2302408D01*
X168866Y2302875D01*
X163866D01*
X162616Y2302408D01*
X161366Y2301475D01*
G01X181625Y1453504D02*
G03I-2452J0D01*
G01X172964Y1457835D02*
G03I-2452J0D01*
G01X181625Y1468859D02*
G03I-2452J0D01*
G01X172964Y1473189D02*
G03I-2452J0D01*
G01X181625Y1499567D02*
G03I-2452J0D01*
G01Y1484213D02*
G03I-2452J0D01*
G01X172964Y1488544D02*
G03I-2452J0D01*
G01X181625Y1514922D02*
G03I-2452J0D01*
G01X172964Y1503898D02*
G03I-2452J0D01*
G01Y1519252D02*
G03I-2452J0D01*
G01X181625Y1555867D02*
G03I-2452J0D01*
G01X172964Y1560197D02*
G03I-2452J0D01*
G01X181625Y1571221D02*
G03I-2452J0D01*
G01X172964Y1575552D02*
G03I-2452J0D01*
G01X181625Y1586575D02*
G03I-2452J0D01*
G01X172964Y1590906D02*
G03I-2452J0D01*
G01X181625Y1601930D02*
G03I-2452J0D01*
G01X172964Y1606260D02*
G03I-2452J0D01*
G01X181625Y1617284D02*
G03I-2452J0D01*
G01X172964Y1621615D02*
G03I-2452J0D01*
G01X185398Y-477835D02*
Y-485835D01*
X189398D01*
G01X197198D02*
Y-480502D01*
G01Y-481435D02*
X196798Y-480902D01*
X196198Y-480635D01*
X195498Y-480502D01*
X194798Y-480768D01*
X194198Y-481302D01*
X193798Y-482102D01*
X193598Y-483168D01*
X193798Y-484235D01*
X194198Y-485035D01*
X194798Y-485568D01*
X195498Y-485835D01*
X196198Y-485702D01*
X196798Y-485302D01*
X197198Y-484769D01*
G01X201298Y-488235D02*
X201898Y-488502D01*
X202698Y-488235D01*
X203198Y-487702D01*
X203598Y-487035D01*
X204198Y-484902D01*
X205498Y-480502D01*
G01X202298D02*
X204198Y-484902D01*
G01X209898Y-482235D02*
X213098D01*
X212798Y-481302D01*
X212298Y-480768D01*
X211598Y-480502D01*
X210898Y-480635D01*
X210298Y-481035D01*
X209898Y-481968D01*
X209698Y-482769D01*
Y-483568D01*
X209898Y-484368D01*
X210398Y-485168D01*
X210998Y-485702D01*
X211698Y-485835D01*
X212398Y-485568D01*
X213098Y-484769D01*
G01X217998Y-485835D02*
Y-480502D01*
G01Y-481568D02*
X218498Y-481035D01*
X218998Y-480635D01*
X219698Y-480502D01*
X220198Y-480635D01*
X220798Y-481035D01*
G01X190287Y1457835D02*
G03I-2452J0D01*
G01Y1473189D02*
G03I-2452J0D01*
G01Y1488544D02*
G03I-2452J0D01*
G01Y1503898D02*
G03I-2452J0D01*
G01Y1519252D02*
G03I-2452J0D01*
G01X190286Y1560197D02*
G03I-2451J0D01*
G01X190287Y1575552D02*
G03I-2452J0D01*
G01Y1590906D02*
G03I-2452J0D01*
G01X190286Y1606260D02*
G03I-2451J0D01*
G01X190287Y1621615D02*
G03I-2452J0D01*
G01X211398Y-535835D02*
Y-532235D01*
X209398Y-527835D01*
G01X213398D02*
X211398Y-532235D01*
G01X217698Y-530502D02*
Y-534235D01*
X218098Y-535168D01*
X218698Y-535702D01*
X219398Y-535835D01*
X220098Y-535702D01*
X220698Y-535168D01*
X221098Y-534235D01*
G01Y-535835D02*
Y-530502D01*
G01X225698Y-535835D02*
Y-530502D01*
G01Y-531835D02*
X226098Y-531168D01*
X226698Y-530635D01*
X227498Y-530502D01*
X228198Y-530635D01*
X228798Y-531168D01*
X229098Y-532102D01*
Y-535835D01*
G01X237198D02*
Y-530502D01*
G01Y-531435D02*
X236798Y-530902D01*
X236198Y-530635D01*
X235498Y-530502D01*
X234798Y-530768D01*
X234198Y-531302D01*
X233798Y-532102D01*
X233598Y-533168D01*
X233798Y-534235D01*
X234198Y-535035D01*
X234798Y-535568D01*
X235498Y-535835D01*
X236198Y-535702D01*
X236798Y-535302D01*
X237198Y-534769D01*
G01X209498Y-510835D02*
Y-502835D01*
X213298D01*
G01X211898Y-506702D02*
X209498D01*
G01X216898Y-510835D02*
X219398Y-502835D01*
X221898Y-510835D01*
G01X220998Y-508035D02*
X217798D01*
G01X228198Y-506568D02*
X228598Y-506168D01*
X228898Y-505502D01*
X229098Y-504568D01*
X228898Y-503768D01*
X228498Y-503235D01*
X227798Y-502835D01*
X225098D01*
Y-510835D01*
X228398D01*
X229098Y-510302D01*
X229498Y-509502D01*
X229698Y-508568D01*
X229498Y-507635D01*
X228898Y-506835D01*
X228198Y-506568D01*
X225098D01*
G01X280646Y1703714D02*
X273146D01*
X280646Y1708008D01*
X273146D01*
G01X280646Y1713361D02*
X280521Y1712614D01*
X280021Y1711961D01*
X279271Y1711401D01*
X278396Y1711028D01*
X277396Y1710841D01*
X276396D01*
X275396Y1711028D01*
X274521Y1711401D01*
X273771Y1711961D01*
X273271Y1712614D01*
X273146Y1713361D01*
X273271Y1714108D01*
X273771Y1714761D01*
X274521Y1715321D01*
X275396Y1715694D01*
X276396Y1715881D01*
X277396D01*
X278396Y1715694D01*
X279271Y1715321D01*
X280021Y1714761D01*
X280521Y1714108D01*
X280646Y1713361D01*
G01Y1718714D02*
X273146D01*
X280646Y1723008D01*
X273146D01*
G01X278146Y1727148D02*
Y1729574D01*
G01X280646Y1733434D02*
X273146D01*
X279396Y1735861D01*
X273146Y1738288D01*
X280646D01*
G01Y1741028D02*
X273146Y1743361D01*
X280646Y1745694D01*
G01X278021Y1744854D02*
Y1741868D01*
G01X280646Y1748994D02*
X273146D01*
Y1751328D01*
X273521Y1752074D01*
X274021Y1752541D01*
X275021Y1752728D01*
X276021Y1752541D01*
X276646Y1751981D01*
X277021Y1751328D01*
Y1748994D01*
G01Y1751328D02*
X280646Y1752728D01*
G01Y1756308D02*
X273146D01*
G01Y1759854D02*
X277771Y1756308D01*
G01X280646Y1760414D02*
X275646Y1757894D01*
G01X280896Y1765861D02*
X280771Y1765674D01*
X280521D01*
X280396Y1765861D01*
X280521Y1766048D01*
X280771D01*
X280896Y1765861D01*
G01X277521D02*
X277396Y1765674D01*
X277146D01*
X277021Y1765861D01*
X277146Y1766048D01*
X277396D01*
X277521Y1765861D01*
G01X280646Y1771494D02*
X273146D01*
Y1773828D01*
X273521Y1774574D01*
X274021Y1775041D01*
X275021Y1775228D01*
X276021Y1775041D01*
X276646Y1774481D01*
X277021Y1773828D01*
Y1771494D01*
G01Y1773828D02*
X280646Y1775228D01*
G01Y1782728D02*
Y1778994D01*
X273146D01*
Y1782728D01*
G01X276771Y1781234D02*
Y1778994D01*
G01X273771Y1790414D02*
X273396Y1789854D01*
X273146Y1789201D01*
Y1788454D01*
X273521Y1787614D01*
X274146Y1786961D01*
X274896Y1786494D01*
X276146Y1786121D01*
X277271Y1786028D01*
X278396Y1786214D01*
X279146Y1786494D01*
X279896Y1787054D01*
X280396Y1787708D01*
X280646Y1788361D01*
Y1789014D01*
X280396Y1789668D01*
X280021Y1790228D01*
X279521Y1790694D01*
G01X280646Y1795861D02*
X280521Y1795114D01*
X280021Y1794461D01*
X279271Y1793901D01*
X278396Y1793528D01*
X277396Y1793341D01*
X276396D01*
X275396Y1793528D01*
X274521Y1793901D01*
X273771Y1794461D01*
X273271Y1795114D01*
X273146Y1795861D01*
X273271Y1796608D01*
X273771Y1797261D01*
X274521Y1797821D01*
X275396Y1798194D01*
X276396Y1798381D01*
X277396D01*
X278396Y1798194D01*
X279271Y1797821D01*
X280021Y1797261D01*
X280521Y1796608D01*
X280646Y1795861D01*
G01Y1800934D02*
X273146D01*
X279396Y1803361D01*
X273146Y1805788D01*
X280646D01*
G01Y1808434D02*
X273146D01*
X279396Y1810861D01*
X273146Y1813288D01*
X280646D01*
G01Y1820228D02*
Y1816494D01*
X273146D01*
Y1820228D01*
G01X276771Y1818734D02*
Y1816494D01*
G01X280646Y1823714D02*
X273146D01*
X280646Y1828008D01*
X273146D01*
G01X280646Y1831308D02*
X273146D01*
Y1833174D01*
X273521Y1833921D01*
X274021Y1834481D01*
X274771Y1834948D01*
X275646Y1835321D01*
X276896Y1835414D01*
X278146Y1835321D01*
X279021Y1834948D01*
X279771Y1834481D01*
X280271Y1833921D01*
X280646Y1833174D01*
Y1831308D01*
G01Y1842728D02*
Y1838994D01*
X273146D01*
Y1842728D01*
G01X276771Y1841234D02*
Y1838994D01*
G01X280646Y1846308D02*
X273146D01*
Y1848174D01*
X273521Y1848921D01*
X274021Y1849481D01*
X274771Y1849948D01*
X275646Y1850321D01*
X276896Y1850414D01*
X278146Y1850321D01*
X279021Y1849948D01*
X279771Y1849481D01*
X280271Y1848921D01*
X280646Y1848174D01*
Y1846308D01*
G01Y1861308D02*
X273146D01*
Y1863174D01*
X273521Y1863921D01*
X274021Y1864481D01*
X274771Y1864948D01*
X275646Y1865321D01*
X276896Y1865414D01*
X278146Y1865321D01*
X279021Y1864948D01*
X279771Y1864481D01*
X280271Y1863921D01*
X280646Y1863174D01*
Y1861308D01*
G01Y1868994D02*
X273146D01*
Y1871328D01*
X273521Y1872074D01*
X274021Y1872541D01*
X275021Y1872728D01*
X276021Y1872541D01*
X276646Y1871981D01*
X277021Y1871328D01*
Y1868994D01*
G01Y1871328D02*
X280646Y1872728D01*
G01X273146Y1877241D02*
Y1879481D01*
G01Y1878361D02*
X280646D01*
G01Y1877241D02*
Y1879481D01*
G01X273146Y1883994D02*
X280646D01*
Y1887728D01*
G01X273146Y1891494D02*
X280646D01*
Y1895228D01*
G01X279646Y1906401D02*
X280271Y1907148D01*
X280646Y1907988D01*
Y1908734D01*
X280271Y1909481D01*
X279646Y1910041D01*
X278771Y1910321D01*
X277896Y1910134D01*
X277146Y1909668D01*
X276646Y1908828D01*
X276396Y1907708D01*
X275896Y1907054D01*
X275021Y1906774D01*
X274146Y1906961D01*
X273521Y1907428D01*
X273146Y1908081D01*
Y1908734D01*
X273396Y1909388D01*
X274021Y1909948D01*
G01X273146Y1914741D02*
Y1916981D01*
G01Y1915861D02*
X280646D01*
G01Y1914741D02*
Y1916981D01*
G01X273146Y1921588D02*
Y1925134D01*
X280646Y1921588D01*
Y1925134D01*
G01Y1932728D02*
Y1928994D01*
X273146D01*
Y1932728D01*
G01X276771Y1931234D02*
Y1928994D01*
G01X280646Y1944088D02*
X273146D01*
Y1947634D01*
G01X276771Y1946328D02*
Y1944088D01*
G01X280646Y1953361D02*
X280521Y1952614D01*
X280021Y1951961D01*
X279271Y1951401D01*
X278396Y1951028D01*
X277396Y1950841D01*
X276396D01*
X275396Y1951028D01*
X274521Y1951401D01*
X273771Y1951961D01*
X273271Y1952614D01*
X273146Y1953361D01*
X273271Y1954108D01*
X273771Y1954761D01*
X274521Y1955321D01*
X275396Y1955694D01*
X276396Y1955881D01*
X277396D01*
X278396Y1955694D01*
X279271Y1955321D01*
X280021Y1954761D01*
X280521Y1954108D01*
X280646Y1953361D01*
G01Y1958994D02*
X273146D01*
Y1961328D01*
X273521Y1962074D01*
X274021Y1962541D01*
X275021Y1962728D01*
X276021Y1962541D01*
X276646Y1961981D01*
X277021Y1961328D01*
Y1958994D01*
G01Y1961328D02*
X280646Y1962728D01*
G01X273146Y1975861D02*
X273396Y1975114D01*
X274021Y1974554D01*
X274771Y1974181D01*
X275771Y1973901D01*
X276896Y1973808D01*
X278021Y1973901D01*
X279021Y1974181D01*
X279771Y1974554D01*
X280396Y1975114D01*
X280646Y1975861D01*
X280396Y1976608D01*
X279771Y1977168D01*
X279021Y1977541D01*
X278021Y1977821D01*
X276896Y1977914D01*
X275771Y1977821D01*
X274771Y1977541D01*
X274021Y1977168D01*
X273396Y1976608D01*
X273146Y1975861D01*
G01X280896Y1983361D02*
X280771Y1983174D01*
X280521D01*
X280396Y1983361D01*
X280521Y1983548D01*
X280771D01*
X280896Y1983361D01*
G01X279146Y1988808D02*
X280021Y1989368D01*
X280521Y1990114D01*
X280646Y1990954D01*
X280521Y1991701D01*
X279896Y1992448D01*
X279146Y1992914D01*
X278396Y1993008D01*
X277521Y1992821D01*
X276896Y1992168D01*
X276646Y1991514D01*
Y1990674D01*
G01Y1991514D02*
X276271Y1992074D01*
X275646Y1992541D01*
X274896Y1992728D01*
X274146Y1992541D01*
X273521Y1992074D01*
X273146Y1991234D01*
X273271Y1990394D01*
X273771Y1989554D01*
G01X280646Y1998361D02*
X273146D01*
X274646Y1997241D01*
G01X280646D02*
Y1999481D01*
G01Y2003434D02*
X273146D01*
X279396Y2005861D01*
X273146Y2008288D01*
X280646D01*
G01Y2010934D02*
X273146D01*
X279396Y2013361D01*
X273146Y2015788D01*
X280646D01*
G01Y2026588D02*
X273146D01*
Y2030134D01*
G01X276771Y2028828D02*
Y2026588D01*
G01X273146Y2034741D02*
Y2036981D01*
G01Y2035861D02*
X280646D01*
G01Y2034741D02*
Y2036981D01*
G01Y2041214D02*
X273146D01*
X280646Y2045508D01*
X273146D01*
G01Y2049741D02*
Y2051981D01*
G01Y2050861D02*
X280646D01*
G01Y2049741D02*
Y2051981D01*
G01X279646Y2056401D02*
X280271Y2057148D01*
X280646Y2057988D01*
Y2058734D01*
X280271Y2059481D01*
X279646Y2060041D01*
X278771Y2060321D01*
X277896Y2060134D01*
X277146Y2059668D01*
X276646Y2058828D01*
X276396Y2057708D01*
X275896Y2057054D01*
X275021Y2056774D01*
X274146Y2056961D01*
X273521Y2057428D01*
X273146Y2058081D01*
Y2058734D01*
X273396Y2059388D01*
X274021Y2059948D01*
G01X280646Y2063901D02*
X273146D01*
G01Y2067821D02*
X280646D01*
G01X276896D02*
Y2063901D01*
G01X280646Y2075228D02*
Y2071494D01*
X273146D01*
Y2075228D01*
G01X276771Y2073734D02*
Y2071494D01*
G01X280646Y2078808D02*
X273146D01*
Y2080674D01*
X273521Y2081421D01*
X274021Y2081981D01*
X274771Y2082448D01*
X275646Y2082821D01*
X276896Y2082914D01*
X278146Y2082821D01*
X279021Y2082448D01*
X279771Y2081981D01*
X280271Y2081421D01*
X280646Y2080674D01*
Y2078808D01*
G01Y2093994D02*
X273146D01*
Y2096234D01*
X273521Y2096981D01*
X274396Y2097541D01*
X275396Y2097728D01*
X276396Y2097541D01*
X277146Y2097074D01*
X277521Y2096234D01*
Y2093994D01*
G01X273146Y2103361D02*
X280646D01*
G01X273146Y2101214D02*
Y2105508D01*
G01X280646Y2108901D02*
X273146D01*
G01Y2112821D02*
X280646D01*
G01X276896D02*
Y2108901D01*
G01X273146Y2124741D02*
Y2126981D01*
G01Y2125861D02*
X280646D01*
G01Y2124741D02*
Y2126981D01*
G01X279646Y2131401D02*
X280271Y2132148D01*
X280646Y2132988D01*
Y2133734D01*
X280271Y2134481D01*
X279646Y2135041D01*
X278771Y2135321D01*
X277896Y2135134D01*
X277146Y2134668D01*
X276646Y2133828D01*
X276396Y2132708D01*
X275896Y2132054D01*
X275021Y2131774D01*
X274146Y2131961D01*
X273521Y2132428D01*
X273146Y2133081D01*
Y2133734D01*
X273396Y2134388D01*
X274021Y2134948D01*
G01X273146Y2148361D02*
X273396Y2147614D01*
X274021Y2147054D01*
X274771Y2146681D01*
X275771Y2146401D01*
X276896Y2146308D01*
X278021Y2146401D01*
X279021Y2146681D01*
X279771Y2147054D01*
X280396Y2147614D01*
X280646Y2148361D01*
X280396Y2149108D01*
X279771Y2149668D01*
X279021Y2150041D01*
X278021Y2150321D01*
X276896Y2150414D01*
X275771Y2150321D01*
X274771Y2150041D01*
X274021Y2149668D01*
X273396Y2149108D01*
X273146Y2148361D01*
G01X280896Y2155861D02*
X280771Y2155674D01*
X280521D01*
X280396Y2155861D01*
X280521Y2156048D01*
X280771D01*
X280896Y2155861D01*
G01X280646Y2164481D02*
X273146D01*
X278521Y2161028D01*
Y2165694D01*
G01X280646Y2168434D02*
X273146D01*
X279396Y2170861D01*
X273146Y2173288D01*
X280646D01*
G01Y2175934D02*
X273146D01*
X279396Y2178361D01*
X273146Y2180788D01*
X280646D01*
G01Y2190934D02*
X273146D01*
X279396Y2193361D01*
X273146Y2195788D01*
X280646D01*
G01Y2202728D02*
Y2198994D01*
X273146D01*
Y2202728D01*
G01X276771Y2201234D02*
Y2198994D01*
G01X273146Y2208361D02*
X280646D01*
G01X273146Y2206214D02*
Y2210508D01*
G01X280646Y2213994D02*
X273146D01*
Y2216328D01*
X273521Y2217074D01*
X274021Y2217541D01*
X275021Y2217728D01*
X276021Y2217541D01*
X276646Y2216981D01*
X277021Y2216328D01*
Y2213994D01*
G01Y2216328D02*
X280646Y2217728D01*
G01X273146Y2222241D02*
Y2224481D01*
G01Y2223361D02*
X280646D01*
G01Y2222241D02*
Y2224481D01*
G01X273771Y2232914D02*
X273396Y2232354D01*
X273146Y2231701D01*
Y2230954D01*
X273521Y2230114D01*
X274146Y2229461D01*
X274896Y2228994D01*
X276146Y2228621D01*
X277271Y2228528D01*
X278396Y2228714D01*
X279146Y2228994D01*
X279896Y2229554D01*
X280396Y2230208D01*
X280646Y2230861D01*
Y2231514D01*
X280396Y2232168D01*
X280021Y2232728D01*
X279521Y2233194D01*
G01X280646Y2243808D02*
X273146D01*
Y2245674D01*
X273521Y2246421D01*
X274021Y2246981D01*
X274771Y2247448D01*
X275646Y2247821D01*
X276896Y2247914D01*
X278146Y2247821D01*
X279021Y2247448D01*
X279771Y2246981D01*
X280271Y2246421D01*
X280646Y2245674D01*
Y2243808D01*
G01Y2251494D02*
X273146D01*
Y2253828D01*
X273521Y2254574D01*
X274021Y2255041D01*
X275021Y2255228D01*
X276021Y2255041D01*
X276646Y2254481D01*
X277021Y2253828D01*
Y2251494D01*
G01Y2253828D02*
X280646Y2255228D01*
G01X273146Y2259741D02*
Y2261981D01*
G01Y2260861D02*
X280646D01*
G01Y2259741D02*
Y2261981D01*
G01X273146Y2266494D02*
X280646D01*
Y2270228D01*
G01X273146Y2273994D02*
X280646D01*
Y2277728D01*
G01X283146Y2282894D02*
X281896Y2281961D01*
X280646Y2281494D01*
X275646D01*
X274396Y2281961D01*
X273146Y2282894D01*
G01Y2290861D02*
X273396Y2290114D01*
X274021Y2289554D01*
X274771Y2289181D01*
X275771Y2288901D01*
X276896Y2288808D01*
X278021Y2288901D01*
X279021Y2289181D01*
X279771Y2289554D01*
X280396Y2290114D01*
X280646Y2290861D01*
X280396Y2291608D01*
X279771Y2292168D01*
X279021Y2292541D01*
X278021Y2292821D01*
X276896Y2292914D01*
X275771Y2292821D01*
X274771Y2292541D01*
X274021Y2292168D01*
X273396Y2291608D01*
X273146Y2290861D01*
G01X280896Y2298361D02*
X280771Y2298174D01*
X280521D01*
X280396Y2298361D01*
X280521Y2298548D01*
X280771D01*
X280896Y2298361D01*
G01X273146Y2305861D02*
X273396Y2305114D01*
X274021Y2304554D01*
X274771Y2304181D01*
X275771Y2303901D01*
X276896Y2303808D01*
X278021Y2303901D01*
X279021Y2304181D01*
X279771Y2304554D01*
X280396Y2305114D01*
X280646Y2305861D01*
X280396Y2306608D01*
X279771Y2307168D01*
X279021Y2307541D01*
X278021Y2307821D01*
X276896Y2307914D01*
X275771Y2307821D01*
X274771Y2307541D01*
X274021Y2307168D01*
X273396Y2306608D01*
X273146Y2305861D01*
G01X280646Y2313361D02*
X273146D01*
X274646Y2312241D01*
G01X280646D02*
Y2314481D01*
G01X279521Y2318808D02*
X280146Y2319368D01*
X280521Y2320021D01*
X280646Y2320861D01*
X280396Y2321701D01*
X279896Y2322354D01*
X279021Y2322821D01*
X278021Y2322914D01*
X277021Y2322728D01*
X276396Y2322261D01*
X275896Y2321608D01*
X275771Y2320954D01*
X275896Y2320301D01*
X276396Y2319461D01*
X273146Y2319741D01*
Y2322261D01*
G01X280646Y2328174D02*
X279021Y2328361D01*
X277646Y2328641D01*
X276396Y2329014D01*
X275021Y2329481D01*
X273146Y2330228D01*
Y2326494D01*
G01X274771Y2335021D02*
X273146Y2335488D01*
G01Y2336701D02*
X274771Y2336234D01*
G01X283146Y2343828D02*
X281896Y2344761D01*
X280646Y2345228D01*
X275646D01*
X274396Y2344761D01*
X273146Y2343828D01*
G01X294223Y1457835D02*
G03I-2452J0D01*
G01X285561Y1453504D02*
G03I-2451J0D01*
G01X294223Y1473189D02*
G03I-2452J0D01*
G01X285562Y1468859D02*
G03I-2452J0D01*
G01X285561Y1499567D02*
G03I-2451J0D01*
G01X294223Y1488544D02*
G03I-2452J0D01*
G01X285562Y1484213D02*
G03I-2452J0D01*
G01Y1514922D02*
G03I-2452J0D01*
G01X294223Y1503898D02*
G03I-2452J0D01*
G01Y1519252D02*
G03I-2452J0D01*
G01X285562Y1555867D02*
G03I-2452J0D01*
G01X294223Y1560197D02*
G03I-2452J0D01*
G01Y1575552D02*
G03I-2452J0D01*
G01X285562Y1571221D02*
G03I-2452J0D01*
G01X294223Y1590906D02*
G03I-2452J0D01*
G01X285562Y1586575D02*
G03I-2452J0D01*
G01X294223Y1606260D02*
G03I-2452J0D01*
G01X285562Y1601930D02*
G03I-2452J0D01*
G01X294223Y1621615D02*
G03I-2452J0D01*
G01X285562Y1617284D02*
G03I-2452J0D01*
G01X294455Y1705736D02*
X286955D01*
X293205Y1708163D01*
X286955Y1710590D01*
X294455D01*
G01Y1713330D02*
X286955Y1715663D01*
X294455Y1717996D01*
G01X291830Y1717156D02*
Y1714170D01*
G01X294455Y1721296D02*
X286955D01*
Y1723630D01*
X287330Y1724376D01*
X287830Y1724843D01*
X288830Y1725030D01*
X289830Y1724843D01*
X290455Y1724283D01*
X290830Y1723630D01*
Y1721296D01*
G01Y1723630D02*
X294455Y1725030D01*
G01Y1728610D02*
X286955D01*
G01Y1732156D02*
X291580Y1728610D01*
G01X294455Y1732716D02*
X289455Y1730196D01*
G01X294705Y1738163D02*
X294580Y1737976D01*
X294330D01*
X294205Y1738163D01*
X294330Y1738350D01*
X294580D01*
X294705Y1738163D01*
G01X291330D02*
X291205Y1737976D01*
X290955D01*
X290830Y1738163D01*
X290955Y1738350D01*
X291205D01*
X291330Y1738163D01*
G01X294455Y1743796D02*
X286955D01*
Y1746130D01*
X287330Y1746876D01*
X287830Y1747343D01*
X288830Y1747530D01*
X289830Y1747343D01*
X290455Y1746783D01*
X290830Y1746130D01*
Y1743796D01*
G01Y1746130D02*
X294455Y1747530D01*
G01Y1755030D02*
Y1751296D01*
X286955D01*
Y1755030D01*
G01X290580Y1753536D02*
Y1751296D01*
G01X287580Y1762716D02*
X287205Y1762156D01*
X286955Y1761503D01*
Y1760756D01*
X287330Y1759916D01*
X287955Y1759263D01*
X288705Y1758796D01*
X289955Y1758423D01*
X291080Y1758330D01*
X292205Y1758516D01*
X292955Y1758796D01*
X293705Y1759356D01*
X294205Y1760010D01*
X294455Y1760663D01*
Y1761316D01*
X294205Y1761970D01*
X293830Y1762530D01*
X293330Y1762996D01*
G01X294455Y1768163D02*
X294330Y1767416D01*
X293830Y1766763D01*
X293080Y1766203D01*
X292205Y1765830D01*
X291205Y1765643D01*
X290205D01*
X289205Y1765830D01*
X288330Y1766203D01*
X287580Y1766763D01*
X287080Y1767416D01*
X286955Y1768163D01*
X287080Y1768910D01*
X287580Y1769563D01*
X288330Y1770123D01*
X289205Y1770496D01*
X290205Y1770683D01*
X291205D01*
X292205Y1770496D01*
X293080Y1770123D01*
X293830Y1769563D01*
X294330Y1768910D01*
X294455Y1768163D01*
G01Y1773236D02*
X286955D01*
X293205Y1775663D01*
X286955Y1778090D01*
X294455D01*
G01Y1780736D02*
X286955D01*
X293205Y1783163D01*
X286955Y1785590D01*
X294455D01*
G01Y1792530D02*
Y1788796D01*
X286955D01*
Y1792530D01*
G01X290580Y1791036D02*
Y1788796D01*
G01X294455Y1796016D02*
X286955D01*
X294455Y1800310D01*
X286955D01*
G01X294455Y1803610D02*
X286955D01*
Y1805476D01*
X287330Y1806223D01*
X287830Y1806783D01*
X288580Y1807250D01*
X289455Y1807623D01*
X290705Y1807716D01*
X291955Y1807623D01*
X292830Y1807250D01*
X293580Y1806783D01*
X294080Y1806223D01*
X294455Y1805476D01*
Y1803610D01*
G01Y1815030D02*
Y1811296D01*
X286955D01*
Y1815030D01*
G01X290580Y1813536D02*
Y1811296D01*
G01X294455Y1818610D02*
X286955D01*
Y1820476D01*
X287330Y1821223D01*
X287830Y1821783D01*
X288580Y1822250D01*
X289455Y1822623D01*
X290705Y1822716D01*
X291955Y1822623D01*
X292830Y1822250D01*
X293580Y1821783D01*
X294080Y1821223D01*
X294455Y1820476D01*
Y1818610D01*
G01Y1833610D02*
X286955D01*
Y1835476D01*
X287330Y1836223D01*
X287830Y1836783D01*
X288580Y1837250D01*
X289455Y1837623D01*
X290705Y1837716D01*
X291955Y1837623D01*
X292830Y1837250D01*
X293580Y1836783D01*
X294080Y1836223D01*
X294455Y1835476D01*
Y1833610D01*
G01Y1841296D02*
X286955D01*
Y1843630D01*
X287330Y1844376D01*
X287830Y1844843D01*
X288830Y1845030D01*
X289830Y1844843D01*
X290455Y1844283D01*
X290830Y1843630D01*
Y1841296D01*
G01Y1843630D02*
X294455Y1845030D01*
G01X286955Y1849543D02*
Y1851783D01*
G01Y1850663D02*
X294455D01*
G01Y1849543D02*
Y1851783D01*
G01X286955Y1856296D02*
X294455D01*
Y1860030D01*
G01X286955Y1863796D02*
X294455D01*
Y1867530D01*
G01X293455Y1878703D02*
X294080Y1879450D01*
X294455Y1880290D01*
Y1881036D01*
X294080Y1881783D01*
X293455Y1882343D01*
X292580Y1882623D01*
X291705Y1882436D01*
X290955Y1881970D01*
X290455Y1881130D01*
X290205Y1880010D01*
X289705Y1879356D01*
X288830Y1879076D01*
X287955Y1879263D01*
X287330Y1879730D01*
X286955Y1880383D01*
Y1881036D01*
X287205Y1881690D01*
X287830Y1882250D01*
G01X286955Y1887043D02*
Y1889283D01*
G01Y1888163D02*
X294455D01*
G01Y1887043D02*
Y1889283D01*
G01X286955Y1893890D02*
Y1897436D01*
X294455Y1893890D01*
Y1897436D01*
G01Y1905030D02*
Y1901296D01*
X286955D01*
Y1905030D01*
G01X290580Y1903536D02*
Y1901296D01*
G01X294455Y1916390D02*
X286955D01*
Y1919936D01*
G01X290580Y1918630D02*
Y1916390D01*
G01X294455Y1925663D02*
X294330Y1924916D01*
X293830Y1924263D01*
X293080Y1923703D01*
X292205Y1923330D01*
X291205Y1923143D01*
X290205D01*
X289205Y1923330D01*
X288330Y1923703D01*
X287580Y1924263D01*
X287080Y1924916D01*
X286955Y1925663D01*
X287080Y1926410D01*
X287580Y1927063D01*
X288330Y1927623D01*
X289205Y1927996D01*
X290205Y1928183D01*
X291205D01*
X292205Y1927996D01*
X293080Y1927623D01*
X293830Y1927063D01*
X294330Y1926410D01*
X294455Y1925663D01*
G01Y1931296D02*
X286955D01*
Y1933630D01*
X287330Y1934376D01*
X287830Y1934843D01*
X288830Y1935030D01*
X289830Y1934843D01*
X290455Y1934283D01*
X290830Y1933630D01*
Y1931296D01*
G01Y1933630D02*
X294455Y1935030D01*
G01X286955Y1948163D02*
X287205Y1947416D01*
X287830Y1946856D01*
X288580Y1946483D01*
X289580Y1946203D01*
X290705Y1946110D01*
X291830Y1946203D01*
X292830Y1946483D01*
X293580Y1946856D01*
X294205Y1947416D01*
X294455Y1948163D01*
X294205Y1948910D01*
X293580Y1949470D01*
X292830Y1949843D01*
X291830Y1950123D01*
X290705Y1950216D01*
X289580Y1950123D01*
X288580Y1949843D01*
X287830Y1949470D01*
X287205Y1948910D01*
X286955Y1948163D01*
G01X294705Y1955663D02*
X294580Y1955476D01*
X294330D01*
X294205Y1955663D01*
X294330Y1955850D01*
X294580D01*
X294705Y1955663D01*
G01X293330Y1961110D02*
X293955Y1961670D01*
X294330Y1962323D01*
X294455Y1963163D01*
X294205Y1964003D01*
X293705Y1964656D01*
X292830Y1965123D01*
X291830Y1965216D01*
X290830Y1965030D01*
X290205Y1964563D01*
X289705Y1963910D01*
X289580Y1963256D01*
X289705Y1962603D01*
X290205Y1961763D01*
X286955Y1962043D01*
Y1964563D01*
G01X294455Y1968236D02*
X286955D01*
X293205Y1970663D01*
X286955Y1973090D01*
X294455D01*
G01Y1975736D02*
X286955D01*
X293205Y1978163D01*
X286955Y1980590D01*
X294455D01*
G01Y1991390D02*
X286955D01*
Y1994936D01*
G01X290580Y1993630D02*
Y1991390D01*
G01X286955Y1999543D02*
Y2001783D01*
G01Y2000663D02*
X294455D01*
G01Y1999543D02*
Y2001783D01*
G01Y2006016D02*
X286955D01*
X294455Y2010310D01*
X286955D01*
G01Y2014543D02*
Y2016783D01*
G01Y2015663D02*
X294455D01*
G01Y2014543D02*
Y2016783D01*
G01X293455Y2021203D02*
X294080Y2021950D01*
X294455Y2022790D01*
Y2023536D01*
X294080Y2024283D01*
X293455Y2024843D01*
X292580Y2025123D01*
X291705Y2024936D01*
X290955Y2024470D01*
X290455Y2023630D01*
X290205Y2022510D01*
X289705Y2021856D01*
X288830Y2021576D01*
X287955Y2021763D01*
X287330Y2022230D01*
X286955Y2022883D01*
Y2023536D01*
X287205Y2024190D01*
X287830Y2024750D01*
G01X294455Y2028703D02*
X286955D01*
G01Y2032623D02*
X294455D01*
G01X290705D02*
Y2028703D01*
G01X294455Y2040030D02*
Y2036296D01*
X286955D01*
Y2040030D01*
G01X290580Y2038536D02*
Y2036296D01*
G01X294455Y2043610D02*
X286955D01*
Y2045476D01*
X287330Y2046223D01*
X287830Y2046783D01*
X288580Y2047250D01*
X289455Y2047623D01*
X290705Y2047716D01*
X291955Y2047623D01*
X292830Y2047250D01*
X293580Y2046783D01*
X294080Y2046223D01*
X294455Y2045476D01*
Y2043610D01*
G01Y2058796D02*
X286955D01*
Y2061036D01*
X287330Y2061783D01*
X288205Y2062343D01*
X289205Y2062530D01*
X290205Y2062343D01*
X290955Y2061876D01*
X291330Y2061036D01*
Y2058796D01*
G01X286955Y2068163D02*
X294455D01*
G01X286955Y2066016D02*
Y2070310D01*
G01X294455Y2073703D02*
X286955D01*
G01Y2077623D02*
X294455D01*
G01X290705D02*
Y2073703D01*
G01X286955Y2089543D02*
Y2091783D01*
G01Y2090663D02*
X294455D01*
G01Y2089543D02*
Y2091783D01*
G01X293455Y2096203D02*
X294080Y2096950D01*
X294455Y2097790D01*
Y2098536D01*
X294080Y2099283D01*
X293455Y2099843D01*
X292580Y2100123D01*
X291705Y2099936D01*
X290955Y2099470D01*
X290455Y2098630D01*
X290205Y2097510D01*
X289705Y2096856D01*
X288830Y2096576D01*
X287955Y2096763D01*
X287330Y2097230D01*
X286955Y2097883D01*
Y2098536D01*
X287205Y2099190D01*
X287830Y2099750D01*
G01X286955Y2113163D02*
X287205Y2112416D01*
X287830Y2111856D01*
X288580Y2111483D01*
X289580Y2111203D01*
X290705Y2111110D01*
X291830Y2111203D01*
X292830Y2111483D01*
X293580Y2111856D01*
X294205Y2112416D01*
X294455Y2113163D01*
X294205Y2113910D01*
X293580Y2114470D01*
X292830Y2114843D01*
X291830Y2115123D01*
X290705Y2115216D01*
X289580Y2115123D01*
X288580Y2114843D01*
X287830Y2114470D01*
X287205Y2113910D01*
X286955Y2113163D01*
G01X294705Y2120663D02*
X294580Y2120476D01*
X294330D01*
X294205Y2120663D01*
X294330Y2120850D01*
X294580D01*
X294705Y2120663D01*
G01X291330Y2126390D02*
X290455Y2127043D01*
X289955Y2127603D01*
X289705Y2128350D01*
X289955Y2129003D01*
X290455Y2129470D01*
X291205Y2129843D01*
X292080Y2129936D01*
X292830Y2129843D01*
X293580Y2129470D01*
X294205Y2128910D01*
X294455Y2128256D01*
X294205Y2127510D01*
X293455Y2126856D01*
X292330Y2126483D01*
X291080Y2126390D01*
X289455Y2126576D01*
X288580Y2126856D01*
X287705Y2127323D01*
X287080Y2127976D01*
X286955Y2128630D01*
X287205Y2129283D01*
X287830Y2129750D01*
G01X294455Y2133236D02*
X286955D01*
X293205Y2135663D01*
X286955Y2138090D01*
X294455D01*
G01Y2140736D02*
X286955D01*
X293205Y2143163D01*
X286955Y2145590D01*
X294455D01*
G01Y2155736D02*
X286955D01*
X293205Y2158163D01*
X286955Y2160590D01*
X294455D01*
G01Y2167530D02*
Y2163796D01*
X286955D01*
Y2167530D01*
G01X290580Y2166036D02*
Y2163796D01*
G01X286955Y2173163D02*
X294455D01*
G01X286955Y2171016D02*
Y2175310D01*
G01X294455Y2178796D02*
X286955D01*
Y2181130D01*
X287330Y2181876D01*
X287830Y2182343D01*
X288830Y2182530D01*
X289830Y2182343D01*
X290455Y2181783D01*
X290830Y2181130D01*
Y2178796D01*
G01Y2181130D02*
X294455Y2182530D01*
G01X286955Y2187043D02*
Y2189283D01*
G01Y2188163D02*
X294455D01*
G01Y2187043D02*
Y2189283D01*
G01X287580Y2197716D02*
X287205Y2197156D01*
X286955Y2196503D01*
Y2195756D01*
X287330Y2194916D01*
X287955Y2194263D01*
X288705Y2193796D01*
X289955Y2193423D01*
X291080Y2193330D01*
X292205Y2193516D01*
X292955Y2193796D01*
X293705Y2194356D01*
X294205Y2195010D01*
X294455Y2195663D01*
Y2196316D01*
X294205Y2196970D01*
X293830Y2197530D01*
X293330Y2197996D01*
G01X294455Y2208610D02*
X286955D01*
Y2210476D01*
X287330Y2211223D01*
X287830Y2211783D01*
X288580Y2212250D01*
X289455Y2212623D01*
X290705Y2212716D01*
X291955Y2212623D01*
X292830Y2212250D01*
X293580Y2211783D01*
X294080Y2211223D01*
X294455Y2210476D01*
Y2208610D01*
G01Y2216296D02*
X286955D01*
Y2218630D01*
X287330Y2219376D01*
X287830Y2219843D01*
X288830Y2220030D01*
X289830Y2219843D01*
X290455Y2219283D01*
X290830Y2218630D01*
Y2216296D01*
G01Y2218630D02*
X294455Y2220030D01*
G01X286955Y2224543D02*
Y2226783D01*
G01Y2225663D02*
X294455D01*
G01Y2224543D02*
Y2226783D01*
G01X286955Y2231296D02*
X294455D01*
Y2235030D01*
G01X286955Y2238796D02*
X294455D01*
Y2242530D01*
G01X296955Y2247696D02*
X295705Y2246763D01*
X294455Y2246296D01*
X289455D01*
X288205Y2246763D01*
X286955Y2247696D01*
G01Y2255663D02*
X287205Y2254916D01*
X287830Y2254356D01*
X288580Y2253983D01*
X289580Y2253703D01*
X290705Y2253610D01*
X291830Y2253703D01*
X292830Y2253983D01*
X293580Y2254356D01*
X294205Y2254916D01*
X294455Y2255663D01*
X294205Y2256410D01*
X293580Y2256970D01*
X292830Y2257343D01*
X291830Y2257623D01*
X290705Y2257716D01*
X289580Y2257623D01*
X288580Y2257343D01*
X287830Y2256970D01*
X287205Y2256410D01*
X286955Y2255663D01*
G01X294705Y2263163D02*
X294580Y2262976D01*
X294330D01*
X294205Y2263163D01*
X294330Y2263350D01*
X294580D01*
X294705Y2263163D01*
G01X286955Y2270663D02*
X287205Y2269916D01*
X287830Y2269356D01*
X288580Y2268983D01*
X289580Y2268703D01*
X290705Y2268610D01*
X291830Y2268703D01*
X292830Y2268983D01*
X293580Y2269356D01*
X294205Y2269916D01*
X294455Y2270663D01*
X294205Y2271410D01*
X293580Y2271970D01*
X292830Y2272343D01*
X291830Y2272623D01*
X290705Y2272716D01*
X289580Y2272623D01*
X288580Y2272343D01*
X287830Y2271970D01*
X287205Y2271410D01*
X286955Y2270663D01*
G01X288205Y2276390D02*
X287455Y2276950D01*
X287080Y2277603D01*
X286955Y2278350D01*
X287205Y2279283D01*
X287830Y2279936D01*
X288580Y2280123D01*
X289330Y2280030D01*
X289955Y2279656D01*
X291205Y2277790D01*
X292080Y2276950D01*
X293330Y2276390D01*
X294455Y2276203D01*
Y2280123D01*
G01X292955Y2283610D02*
X293830Y2284170D01*
X294330Y2284916D01*
X294455Y2285756D01*
X294330Y2286503D01*
X293705Y2287250D01*
X292955Y2287716D01*
X292205Y2287810D01*
X291330Y2287623D01*
X290705Y2286970D01*
X290455Y2286316D01*
Y2285476D01*
G01Y2286316D02*
X290080Y2286876D01*
X289455Y2287343D01*
X288705Y2287530D01*
X287955Y2287343D01*
X287330Y2286876D01*
X286955Y2286036D01*
X287080Y2285196D01*
X287580Y2284356D01*
G01X291330Y2291390D02*
X290455Y2292043D01*
X289955Y2292603D01*
X289705Y2293350D01*
X289955Y2294003D01*
X290455Y2294470D01*
X291205Y2294843D01*
X292080Y2294936D01*
X292830Y2294843D01*
X293580Y2294470D01*
X294205Y2293910D01*
X294455Y2293256D01*
X294205Y2292510D01*
X293455Y2291856D01*
X292330Y2291483D01*
X291080Y2291390D01*
X289455Y2291576D01*
X288580Y2291856D01*
X287705Y2292323D01*
X287080Y2292976D01*
X286955Y2293630D01*
X287205Y2294283D01*
X287830Y2294750D01*
G01X288580Y2299823D02*
X286955Y2300290D01*
G01Y2301503D02*
X288580Y2301036D01*
G01X296955Y2308630D02*
X295705Y2309563D01*
X294455Y2310030D01*
X289455D01*
X288205Y2309563D01*
X286955Y2308630D01*
G01X311998Y-529168D02*
X312598Y-528368D01*
X313298Y-527968D01*
X314098Y-527835D01*
X315098Y-528102D01*
X315798Y-528768D01*
X315998Y-529568D01*
X315898Y-530369D01*
X315498Y-531035D01*
X313498Y-532368D01*
X312598Y-533302D01*
X311998Y-534635D01*
X311798Y-535835D01*
X315998D01*
G01X321898Y-527835D02*
X321098Y-528102D01*
X320498Y-528768D01*
X320098Y-529568D01*
X319798Y-530635D01*
X319698Y-531835D01*
X319798Y-533035D01*
X320098Y-534102D01*
X320498Y-534902D01*
X321098Y-535568D01*
X321898Y-535835D01*
X322698Y-535568D01*
X323298Y-534902D01*
X323698Y-534102D01*
X323998Y-533035D01*
X324098Y-531835D01*
X323998Y-530635D01*
X323698Y-529568D01*
X323298Y-528768D01*
X322698Y-528102D01*
X321898Y-527835D01*
G01X327998Y-529168D02*
X328598Y-528368D01*
X329298Y-527968D01*
X330098Y-527835D01*
X331098Y-528102D01*
X331798Y-528768D01*
X331998Y-529568D01*
X331898Y-530369D01*
X331498Y-531035D01*
X329498Y-532368D01*
X328598Y-533302D01*
X327998Y-534635D01*
X327798Y-535835D01*
X331998D01*
G01X335698Y-534235D02*
X336298Y-535168D01*
X337098Y-535702D01*
X337998Y-535835D01*
X338798Y-535702D01*
X339598Y-535035D01*
X340098Y-534235D01*
X340198Y-533435D01*
X339998Y-532502D01*
X339298Y-531835D01*
X338598Y-531568D01*
X337698D01*
G01X338598D02*
X339198Y-531168D01*
X339698Y-530502D01*
X339898Y-529702D01*
X339698Y-528902D01*
X339198Y-528235D01*
X338298Y-527835D01*
X337398Y-527968D01*
X336498Y-528502D01*
G01X344098Y-536102D02*
X347698Y-527835D01*
G01X353898D02*
X353098Y-528102D01*
X352498Y-528768D01*
X352098Y-529568D01*
X351798Y-530635D01*
X351698Y-531835D01*
X351798Y-533035D01*
X352098Y-534102D01*
X352498Y-534902D01*
X353098Y-535568D01*
X353898Y-535835D01*
X354698Y-535568D01*
X355298Y-534902D01*
X355698Y-534102D01*
X355998Y-533035D01*
X356098Y-531835D01*
X355998Y-530635D01*
X355698Y-529568D01*
X355298Y-528768D01*
X354698Y-528102D01*
X353898Y-527835D01*
G01X361898Y-535835D02*
Y-527835D01*
X360698Y-529435D01*
G01Y-535835D02*
X363098D01*
G01X368098Y-536102D02*
X371698Y-527835D01*
G01X377898D02*
X377098Y-528102D01*
X376498Y-528768D01*
X376098Y-529568D01*
X375798Y-530635D01*
X375698Y-531835D01*
X375798Y-533035D01*
X376098Y-534102D01*
X376498Y-534902D01*
X377098Y-535568D01*
X377898Y-535835D01*
X378698Y-535568D01*
X379298Y-534902D01*
X379698Y-534102D01*
X379998Y-533035D01*
X380098Y-531835D01*
X379998Y-530635D01*
X379698Y-529568D01*
X379298Y-528768D01*
X378698Y-528102D01*
X377898Y-527835D01*
G01X384198Y-534902D02*
X384898Y-535568D01*
X385698Y-535835D01*
X386498Y-535568D01*
X387198Y-534769D01*
X387698Y-533568D01*
X387898Y-532368D01*
Y-530902D01*
X387698Y-529702D01*
X387198Y-528635D01*
X386598Y-528102D01*
X385898Y-527835D01*
X385098Y-528102D01*
X384498Y-528635D01*
X384098Y-529435D01*
X383898Y-530502D01*
X384098Y-531435D01*
X384598Y-532368D01*
X385198Y-532902D01*
X385898Y-533035D01*
X386698Y-532769D01*
X387298Y-532102D01*
X387898Y-530902D01*
G01X311698Y-510835D02*
Y-502835D01*
X313698D01*
X314498Y-503235D01*
X315098Y-503768D01*
X315598Y-504568D01*
X315998Y-505502D01*
X316098Y-506835D01*
X315998Y-508168D01*
X315598Y-509102D01*
X315098Y-509902D01*
X314498Y-510435D01*
X313698Y-510835D01*
X311698D01*
G01X319398D02*
X321898Y-502835D01*
X324398Y-510835D01*
G01X323498Y-508035D02*
X320298D01*
G01X329898Y-502835D02*
X329098Y-503102D01*
X328498Y-503768D01*
X328098Y-504568D01*
X327798Y-505635D01*
X327698Y-506835D01*
X327798Y-508035D01*
X328098Y-509102D01*
X328498Y-509902D01*
X329098Y-510568D01*
X329898Y-510835D01*
X330698Y-510568D01*
X331298Y-509902D01*
X331698Y-509102D01*
X331998Y-508035D01*
X332098Y-506835D01*
X331998Y-505635D01*
X331698Y-504568D01*
X331298Y-503768D01*
X330698Y-503102D01*
X329898Y-502835D01*
G01X335998Y-510835D02*
Y-502835D01*
X339798D01*
G01X338398Y-506702D02*
X335998D01*
G01X345898Y-502835D02*
X345098Y-503102D01*
X344498Y-503768D01*
X344098Y-504568D01*
X343798Y-505635D01*
X343698Y-506835D01*
X343798Y-508035D01*
X344098Y-509102D01*
X344498Y-509902D01*
X345098Y-510568D01*
X345898Y-510835D01*
X346698Y-510568D01*
X347298Y-509902D01*
X347698Y-509102D01*
X347998Y-508035D01*
X348098Y-506835D01*
X347998Y-505635D01*
X347698Y-504568D01*
X347298Y-503768D01*
X346698Y-503102D01*
X345898Y-502835D01*
G01X353898D02*
Y-510835D01*
G01X351598Y-502835D02*
X356198D01*
G01X363898Y-510835D02*
X359898D01*
Y-502835D01*
X363898D01*
G01X362298Y-506702D02*
X359898D01*
G01X370698Y-506568D02*
X371098Y-506168D01*
X371398Y-505502D01*
X371598Y-504568D01*
X371398Y-503768D01*
X370998Y-503235D01*
X370298Y-502835D01*
X367598D01*
Y-510835D01*
X370898D01*
X371598Y-510302D01*
X371998Y-509502D01*
X372198Y-508568D01*
X371998Y-507635D01*
X371398Y-506835D01*
X370698Y-506568D01*
X367598D01*
G01X376698Y-502835D02*
X379098D01*
G01X377898D02*
Y-510835D01*
G01X376698D02*
X379098D01*
G01X383998D02*
Y-502835D01*
X387798D01*
G01X386398Y-506702D02*
X383998D01*
G01X393898Y-502835D02*
X393098Y-503102D01*
X392498Y-503768D01*
X392098Y-504568D01*
X391798Y-505635D01*
X391698Y-506835D01*
X391798Y-508035D01*
X392098Y-509102D01*
X392498Y-509902D01*
X393098Y-510568D01*
X393898Y-510835D01*
X394698Y-510568D01*
X395298Y-509902D01*
X395698Y-509102D01*
X395998Y-508035D01*
X396098Y-506835D01*
X395998Y-505635D01*
X395698Y-504568D01*
X395298Y-503768D01*
X394698Y-503102D01*
X393898Y-502835D01*
G01X311546Y1457835D02*
G03I-2452J0D01*
G01X302884Y1453504D02*
G03I-2451J0D01*
G01X311546Y1473189D02*
G03I-2452J0D01*
G01X302885Y1468859D02*
G03I-2452J0D01*
G01X302884Y1499567D02*
G03I-2451J0D01*
G01X311546Y1488544D02*
G03I-2452J0D01*
G01X302885Y1484213D02*
G03I-2452J0D01*
G01Y1514922D02*
G03I-2452J0D01*
G01X311546Y1503898D02*
G03I-2452J0D01*
G01Y1519252D02*
G03I-2452J0D01*
G01Y1560197D02*
G03I-2452J0D01*
G01X302885Y1555867D02*
G03I-2452J0D01*
G01X311546Y1575552D02*
G03I-2452J0D01*
G01X302885Y1571221D02*
G03I-2452J0D01*
G01X311546Y1590906D02*
G03I-2452J0D01*
G01X302885Y1586575D02*
G03I-2452J0D01*
G01X311546Y1606260D02*
G03I-2452J0D01*
G01X302885Y1601930D02*
G03I-2452J0D01*
G01X311546Y1621615D02*
G03I-2452J0D01*
G01X302885Y1617284D02*
G03I-2452J0D01*
G01X328869Y1457835D02*
G03I-2452J0D01*
G01X320207Y1453504D02*
G03I-2451J0D01*
G01X328869Y1473189D02*
G03I-2452J0D01*
G01X320208Y1468859D02*
G03I-2452J0D01*
G01X320207Y1499567D02*
G03I-2451J0D01*
G01X328869Y1488544D02*
G03I-2452J0D01*
G01X320208Y1484213D02*
G03I-2452J0D01*
G01Y1514922D02*
G03I-2452J0D01*
G01X328869Y1503898D02*
G03I-2452J0D01*
G01Y1519252D02*
G03I-2452J0D01*
G01Y1560197D02*
G03I-2452J0D01*
G01X320208Y1555867D02*
G03I-2452J0D01*
G01X328869Y1575552D02*
G03I-2452J0D01*
G01X320208Y1571221D02*
G03I-2452J0D01*
G01X328869Y1590906D02*
G03I-2452J0D01*
G01X320207Y1586575D02*
G03I-2451J0D01*
G01X328869Y1606260D02*
G03I-2452J0D01*
G01X320208Y1601930D02*
G03I-2452J0D01*
G01X328869Y1621615D02*
G03I-2452J0D01*
G01X320208Y1617284D02*
G03I-2452J0D01*
G01X329498Y-485835D02*
Y-477835D01*
X333298D01*
G01X331898Y-481702D02*
X329498D01*
G01X339398Y-477835D02*
X338598Y-478102D01*
X337998Y-478768D01*
X337598Y-479568D01*
X337298Y-480635D01*
X337198Y-481835D01*
X337298Y-483035D01*
X337598Y-484102D01*
X337998Y-484902D01*
X338598Y-485568D01*
X339398Y-485835D01*
X340198Y-485568D01*
X340798Y-484902D01*
X341198Y-484102D01*
X341498Y-483035D01*
X341598Y-481835D01*
X341498Y-480635D01*
X341198Y-479568D01*
X340798Y-478768D01*
X340198Y-478102D01*
X339398Y-477835D01*
G01X347398D02*
Y-485835D01*
G01X345098Y-477835D02*
X349698D01*
G01X352398Y-488502D02*
X358398D01*
G01X361898Y-482235D02*
X365098D01*
X364798Y-481302D01*
X364298Y-480768D01*
X363598Y-480502D01*
X362898Y-480635D01*
X362298Y-481035D01*
X361898Y-481968D01*
X361698Y-482769D01*
Y-483568D01*
X361898Y-484368D01*
X362398Y-485168D01*
X362998Y-485702D01*
X363698Y-485835D01*
X364398Y-485568D01*
X365098Y-484769D01*
G01X369898Y-480502D02*
X372898Y-485835D01*
G01Y-480502D02*
X369898Y-485835D01*
G01X377598Y-488502D02*
Y-480502D01*
G01Y-481702D02*
X378098Y-481035D01*
X378598Y-480635D01*
X379398Y-480502D01*
X380098Y-480635D01*
X380798Y-481302D01*
X381098Y-482235D01*
X381198Y-483168D01*
X381098Y-484102D01*
X380798Y-485035D01*
X380198Y-485568D01*
X379398Y-485835D01*
X378698Y-485702D01*
X377998Y-485302D01*
X377598Y-484769D01*
G01X389198Y-485835D02*
Y-480502D01*
G01Y-481435D02*
X388798Y-480902D01*
X388198Y-480635D01*
X387498Y-480502D01*
X386798Y-480768D01*
X386198Y-481302D01*
X385798Y-482102D01*
X385598Y-483168D01*
X385798Y-484235D01*
X386198Y-485035D01*
X386798Y-485568D01*
X387498Y-485835D01*
X388198Y-485702D01*
X388798Y-485302D01*
X389198Y-484769D01*
G01X393698Y-485835D02*
Y-480502D01*
G01Y-481835D02*
X394098Y-481168D01*
X394698Y-480635D01*
X395498Y-480502D01*
X396198Y-480635D01*
X396798Y-481168D01*
X397098Y-482102D01*
Y-485835D01*
G01X405198Y-477835D02*
Y-485835D01*
G01Y-484635D02*
X404798Y-485302D01*
X404198Y-485702D01*
X403498Y-485835D01*
X402698Y-485568D01*
X402098Y-484902D01*
X401698Y-484102D01*
X401598Y-483168D01*
X401698Y-482235D01*
X402098Y-481435D01*
X402698Y-480768D01*
X403498Y-480502D01*
X404198Y-480635D01*
X404698Y-480902D01*
X405198Y-481435D01*
G01X409898Y-482235D02*
X413098D01*
X412798Y-481302D01*
X412298Y-480768D01*
X411598Y-480502D01*
X410898Y-480635D01*
X410298Y-481035D01*
X409898Y-481968D01*
X409698Y-482769D01*
Y-483568D01*
X409898Y-484368D01*
X410398Y-485168D01*
X410998Y-485702D01*
X411698Y-485835D01*
X412398Y-485568D01*
X413098Y-484769D01*
G01X417998Y-485835D02*
Y-480502D01*
G01Y-481568D02*
X418498Y-481035D01*
X418998Y-480635D01*
X419698Y-480502D01*
X420198Y-480635D01*
X420798Y-481035D01*
G01X424398Y-488502D02*
X430398D01*
G01X433598Y-485835D02*
Y-477835D01*
G01Y-481835D02*
X434098Y-481035D01*
X434698Y-480635D01*
X435298Y-480502D01*
X436198Y-480768D01*
X436798Y-481302D01*
X437198Y-482235D01*
Y-483302D01*
X436998Y-484368D01*
X436598Y-485168D01*
X435898Y-485702D01*
X435298Y-485835D01*
X434698Y-485702D01*
X434098Y-485302D01*
X433598Y-484635D01*
G01X445198Y-477835D02*
Y-485835D01*
G01Y-484635D02*
X444798Y-485302D01*
X444198Y-485702D01*
X443498Y-485835D01*
X442698Y-485568D01*
X442098Y-484902D01*
X441698Y-484102D01*
X441598Y-483168D01*
X441698Y-482235D01*
X442098Y-481435D01*
X442698Y-480768D01*
X443498Y-480502D01*
X444198Y-480635D01*
X444698Y-480902D01*
X445198Y-481435D01*
G01X346192Y1457835D02*
G03I-2452J0D01*
G01X337530Y1453504D02*
G03I-2452J0D01*
G01X346192Y1473189D02*
G03I-2452J0D01*
G01X337530Y1468859D02*
G03I-2452J0D01*
G01Y1499567D02*
G03I-2452J0D01*
G01X346192Y1488544D02*
G03I-2452J0D01*
G01X337530Y1484213D02*
G03I-2452J0D01*
G01Y1514922D02*
G03I-2452J0D01*
G01X346192Y1503898D02*
G03I-2452J0D01*
G01Y1519252D02*
G03I-2452J0D01*
G01Y1560197D02*
G03I-2452J0D01*
G01X337530Y1555867D02*
G03I-2452J0D01*
G01X346192Y1575552D02*
G03I-2452J0D01*
G01X337530Y1571221D02*
G03I-2452J0D01*
G01X346192Y1590906D02*
G03I-2452J0D01*
G01X337530Y1586575D02*
G03I-2452J0D01*
G01X346192Y1606260D02*
G03I-2452J0D01*
G01X337530Y1601930D02*
G03I-2452J0D01*
G01X346192Y1621615D02*
G03I-2452J0D01*
G01X337530Y1617284D02*
G03I-2452J0D01*
G01X356702Y-420284D02*
X358161Y-419354D01*
X358994Y-418114D01*
X359202Y-416719D01*
X358994Y-415479D01*
X357952Y-414239D01*
X356702Y-413464D01*
X355452Y-413309D01*
X353994Y-413619D01*
X352952Y-414704D01*
X352535Y-415789D01*
Y-417184D01*
G01Y-415789D02*
X351910Y-414859D01*
X350869Y-414084D01*
X349619Y-413774D01*
X348369Y-414084D01*
X347327Y-414859D01*
X346702Y-416254D01*
X346910Y-417649D01*
X347744Y-419044D01*
G01X357327Y-407884D02*
X358369Y-406954D01*
X358994Y-405869D01*
X359202Y-404474D01*
X358785Y-403079D01*
X357952Y-401994D01*
X356494Y-401219D01*
X354827Y-401064D01*
X353160Y-401374D01*
X352119Y-402149D01*
X351285Y-403234D01*
X351077Y-404319D01*
X351285Y-405404D01*
X352119Y-406799D01*
X346702Y-406334D01*
Y-402149D01*
G01X348785Y-395019D02*
X347536Y-394089D01*
X346910Y-393004D01*
X346702Y-391764D01*
X347119Y-390214D01*
X348160Y-389129D01*
X349410Y-388819D01*
X350661Y-388974D01*
X351702Y-389594D01*
X353785Y-392694D01*
X355244Y-394089D01*
X357327Y-395019D01*
X359202Y-395329D01*
Y-388819D01*
G01X357744Y-382309D02*
X358785Y-381224D01*
X359202Y-379984D01*
X358785Y-378744D01*
X357536Y-377659D01*
X355660Y-376884D01*
X353785Y-376574D01*
X351494D01*
X349619Y-376884D01*
X347952Y-377659D01*
X347119Y-378589D01*
X346702Y-379674D01*
X347119Y-380914D01*
X347952Y-381844D01*
X349202Y-382464D01*
X350869Y-382774D01*
X352327Y-382464D01*
X353785Y-381689D01*
X354619Y-380759D01*
X354827Y-379674D01*
X354411Y-378434D01*
X353369Y-377504D01*
X351494Y-376574D01*
G01X359619Y-367274D02*
X359410Y-367584D01*
X358994D01*
X358785Y-367274D01*
X358994Y-366964D01*
X359410D01*
X359619Y-367274D01*
G01X357327Y-358284D02*
X358369Y-357354D01*
X358994Y-356269D01*
X359202Y-354874D01*
X358785Y-353479D01*
X357952Y-352394D01*
X356494Y-351619D01*
X354827Y-351464D01*
X353160Y-351774D01*
X352119Y-352549D01*
X351285Y-353634D01*
X351077Y-354719D01*
X351285Y-355804D01*
X352119Y-357199D01*
X346702Y-356734D01*
Y-352549D01*
G01X348785Y-345419D02*
X347536Y-344489D01*
X346910Y-343404D01*
X346702Y-342164D01*
X347119Y-340614D01*
X348160Y-339529D01*
X349410Y-339219D01*
X350661Y-339374D01*
X351702Y-339994D01*
X353785Y-343094D01*
X355244Y-344489D01*
X357327Y-345419D01*
X359202Y-345729D01*
Y-339219D01*
G01Y-307874D02*
X358994Y-306789D01*
X358369Y-305549D01*
X357327Y-304774D01*
X355869Y-304464D01*
X354411Y-304774D01*
X353160Y-305704D01*
X352535Y-307099D01*
Y-308649D01*
X352119Y-309579D01*
X351077Y-310354D01*
X349619Y-310664D01*
X348160Y-310199D01*
X347119Y-309114D01*
X346702Y-307874D01*
X347119Y-306634D01*
X348160Y-305549D01*
X349619Y-305084D01*
X351077Y-305394D01*
X352119Y-306169D01*
X352535Y-307099D01*
Y-308649D01*
X353160Y-310044D01*
X354411Y-310974D01*
X355869Y-311284D01*
X357327Y-310974D01*
X358369Y-310199D01*
X358994Y-308959D01*
X359202Y-307874D01*
G01X357744Y-298109D02*
X358785Y-297024D01*
X359202Y-295784D01*
X358785Y-294544D01*
X357536Y-293459D01*
X355660Y-292684D01*
X353785Y-292374D01*
X351494D01*
X349619Y-292684D01*
X347952Y-293459D01*
X347119Y-294389D01*
X346702Y-295474D01*
X347119Y-296714D01*
X347952Y-297644D01*
X349202Y-298264D01*
X350869Y-298574D01*
X352327Y-298264D01*
X353785Y-297489D01*
X354619Y-296559D01*
X354827Y-295474D01*
X354411Y-294234D01*
X353369Y-293304D01*
X351494Y-292374D01*
G01X359619Y-283074D02*
X359410Y-283384D01*
X358994D01*
X358785Y-283074D01*
X358994Y-282764D01*
X359410D01*
X359619Y-283074D01*
G01X353994Y-273619D02*
X352535Y-272534D01*
X351702Y-271604D01*
X351285Y-270364D01*
X351702Y-269279D01*
X352535Y-268504D01*
X353785Y-267884D01*
X355244Y-267729D01*
X356494Y-267884D01*
X357744Y-268504D01*
X358785Y-269434D01*
X359202Y-270519D01*
X358785Y-271759D01*
X357536Y-272844D01*
X355660Y-273464D01*
X353577Y-273619D01*
X350869Y-273309D01*
X349410Y-272844D01*
X347952Y-272069D01*
X346910Y-270984D01*
X346702Y-269899D01*
X347119Y-268814D01*
X348160Y-268039D01*
G01X357327Y-261684D02*
X358369Y-260754D01*
X358994Y-259669D01*
X359202Y-258274D01*
X358785Y-256879D01*
X357952Y-255794D01*
X356494Y-255019D01*
X354827Y-254864D01*
X353160Y-255174D01*
X352119Y-255949D01*
X351285Y-257034D01*
X351077Y-258119D01*
X351285Y-259204D01*
X352119Y-260599D01*
X346702Y-260134D01*
Y-255949D01*
G01X363515Y1457835D02*
G03I-2452J0D01*
G01X354853Y1453504D02*
G03I-2452J0D01*
G01X363515Y1473189D02*
G03I-2452J0D01*
G01X354853Y1468859D02*
G03I-2452J0D01*
G01Y1499567D02*
G03I-2452J0D01*
G01X363515Y1488544D02*
G03I-2452J0D01*
G01X354853Y1484213D02*
G03I-2452J0D01*
G01Y1514922D02*
G03I-2452J0D01*
G01X363515Y1503898D02*
G03I-2452J0D01*
G01Y1519252D02*
G03I-2452J0D01*
G01X363514Y1560197D02*
G03I-2451J0D01*
G01X354853Y1555867D02*
G03I-2452J0D01*
G01X363515Y1575552D02*
G03I-2452J0D01*
G01X354853Y1571221D02*
G03I-2452J0D01*
G01X363515Y1590906D02*
G03I-2452J0D01*
G01X354853Y1586575D02*
G03I-2452J0D01*
G01X363514Y1606260D02*
G03I-2451J0D01*
G01X354853Y1601930D02*
G03I-2452J0D01*
G01X363515Y1621615D02*
G03I-2452J0D01*
G01X354853Y1617284D02*
G03I-2452J0D01*
G01X400398Y-538835D02*
Y-530835D01*
X399198Y-532435D01*
G01Y-538835D02*
X401598D01*
G01X406498Y-535502D02*
X407198Y-534568D01*
X407798Y-534035D01*
X408598Y-533768D01*
X409298Y-534035D01*
X409798Y-534568D01*
X410198Y-535368D01*
X410298Y-536302D01*
X410198Y-537102D01*
X409798Y-537902D01*
X409198Y-538568D01*
X408498Y-538835D01*
X407698Y-538568D01*
X406998Y-537769D01*
X406598Y-536568D01*
X406498Y-535235D01*
X406698Y-533502D01*
X406998Y-532568D01*
X407498Y-531635D01*
X408198Y-530968D01*
X408898Y-530835D01*
X409598Y-531102D01*
X410098Y-531768D01*
G01X416398Y-539102D02*
X416198Y-538968D01*
Y-538702D01*
X416398Y-538568D01*
X416598Y-538702D01*
Y-538968D01*
X416398Y-539102D01*
G01X422498Y-535502D02*
X423198Y-534568D01*
X423798Y-534035D01*
X424598Y-533768D01*
X425298Y-534035D01*
X425798Y-534568D01*
X426198Y-535368D01*
X426298Y-536302D01*
X426198Y-537102D01*
X425798Y-537902D01*
X425198Y-538568D01*
X424498Y-538835D01*
X423698Y-538568D01*
X422998Y-537769D01*
X422598Y-536568D01*
X422498Y-535235D01*
X422698Y-533502D01*
X422998Y-532568D01*
X423498Y-531635D01*
X424198Y-530968D01*
X424898Y-530835D01*
X425598Y-531102D01*
X426098Y-531768D01*
G01X445398Y-538835D02*
Y-530835D01*
X444198Y-532435D01*
G01Y-538835D02*
X446598D01*
G01X453198D02*
X453398Y-537102D01*
X453698Y-535635D01*
X454098Y-534302D01*
X454598Y-532835D01*
X455398Y-530835D01*
X451398D01*
G01X461398Y-539102D02*
X461198Y-538968D01*
Y-538702D01*
X461398Y-538568D01*
X461598Y-538702D01*
Y-538968D01*
X461398Y-539102D01*
G01X467498Y-532168D02*
X468098Y-531368D01*
X468798Y-530968D01*
X469598Y-530835D01*
X470598Y-531102D01*
X471298Y-531768D01*
X471498Y-532568D01*
X471398Y-533369D01*
X470998Y-534035D01*
X468998Y-535368D01*
X468098Y-536302D01*
X467498Y-537635D01*
X467298Y-538835D01*
X471498D01*
G01X458790Y1453504D02*
G03I-2451J0D01*
G01X458791Y1468859D02*
G03I-2452J0D01*
G01X458790Y1499567D02*
G03I-2451J0D01*
G01X458791Y1484213D02*
G03I-2452J0D01*
G01Y1514922D02*
G03I-2452J0D01*
G01Y1555867D02*
G03I-2452J0D01*
G01Y1571221D02*
G03I-2452J0D01*
G01Y1586575D02*
G03I-2452J0D01*
G01Y1601930D02*
G03I-2452J0D01*
G01Y1617284D02*
G03I-2452J0D01*
G01X465498Y-513835D02*
Y-505835D01*
X469298D01*
G01X467898Y-509702D02*
X465498D01*
G01X476113Y1453504D02*
G03I-2451J0D01*
G01X467452Y1457835D02*
G03I-2452J0D01*
G01X476114Y1468859D02*
G03I-2452J0D01*
G01X467452Y1473189D02*
G03I-2452J0D01*
G01X476113Y1499567D02*
G03I-2451J0D01*
G01X476114Y1484213D02*
G03I-2452J0D01*
G01X467452Y1488544D02*
G03I-2452J0D01*
G01X476114Y1514922D02*
G03I-2452J0D01*
G01X467452Y1503898D02*
G03I-2452J0D01*
G01Y1519252D02*
G03I-2452J0D01*
G01X476114Y1555867D02*
G03I-2452J0D01*
G01X467452Y1560197D02*
G03I-2452J0D01*
G01X476114Y1571221D02*
G03I-2452J0D01*
G01X467452Y1575552D02*
G03I-2452J0D01*
G01X476114Y1586575D02*
G03I-2452J0D01*
G01X467452Y1590906D02*
G03I-2452J0D01*
G01X476114Y1601930D02*
G03I-2452J0D01*
G01X467452Y1606260D02*
G03I-2452J0D01*
G01X476114Y1617284D02*
G03I-2452J0D01*
G01X467452Y1621615D02*
G03I-2452J0D01*
G01X483131Y-70883D02*
Y-73983D01*
X484665D01*
G01X486998D02*
X486691Y-73931D01*
X486423Y-73725D01*
X486193Y-73415D01*
X486040Y-73053D01*
X485963Y-72640D01*
Y-72226D01*
X486040Y-71813D01*
X486193Y-71451D01*
X486423Y-71141D01*
X486691Y-70935D01*
X486998Y-70883D01*
X487305Y-70935D01*
X487573Y-71141D01*
X487803Y-71451D01*
X487956Y-71813D01*
X488033Y-72226D01*
Y-72640D01*
X487956Y-73053D01*
X487803Y-73415D01*
X487573Y-73725D01*
X487305Y-73931D01*
X486998Y-73983D01*
G01X490328Y-72433D02*
X491095D01*
Y-73363D01*
X490865Y-73673D01*
X490596Y-73880D01*
X490213Y-73983D01*
X489830Y-73880D01*
X489561Y-73673D01*
X489331Y-73363D01*
X489178Y-73001D01*
X489101Y-72588D01*
Y-72226D01*
X489178Y-71916D01*
X489331Y-71555D01*
X489561Y-71245D01*
X489791Y-71038D01*
X490098Y-70883D01*
X490366D01*
X490673Y-70986D01*
X490903Y-71193D01*
G01X493198Y-73983D02*
X492891Y-73931D01*
X492623Y-73725D01*
X492393Y-73415D01*
X492240Y-73053D01*
X492163Y-72640D01*
Y-72226D01*
X492240Y-71813D01*
X492393Y-71451D01*
X492623Y-71141D01*
X492891Y-70935D01*
X493198Y-70883D01*
X493505Y-70935D01*
X493773Y-71141D01*
X494003Y-71451D01*
X494156Y-71813D01*
X494233Y-72226D01*
Y-72640D01*
X494156Y-73053D01*
X494003Y-73415D01*
X493773Y-73725D01*
X493505Y-73931D01*
X493198Y-73983D01*
G01X474631Y-65983D02*
Y-62883D01*
X475551D01*
X475858Y-63038D01*
X476088Y-63400D01*
X476165Y-63813D01*
X476088Y-64226D01*
X475896Y-64536D01*
X475551Y-64691D01*
X474631D01*
G01X479341Y-63141D02*
X479111Y-62986D01*
X478843Y-62883D01*
X478536D01*
X478191Y-63038D01*
X477923Y-63296D01*
X477731Y-63606D01*
X477578Y-64123D01*
X477540Y-64588D01*
X477616Y-65053D01*
X477731Y-65363D01*
X477961Y-65673D01*
X478230Y-65880D01*
X478498Y-65983D01*
X478766D01*
X479035Y-65880D01*
X479265Y-65725D01*
X479456Y-65518D01*
G01X481905Y-64330D02*
X482058Y-64175D01*
X482173Y-63916D01*
X482250Y-63555D01*
X482173Y-63245D01*
X482020Y-63038D01*
X481751Y-62883D01*
X480716D01*
Y-65983D01*
X481981D01*
X482250Y-65776D01*
X482403Y-65466D01*
X482480Y-65105D01*
X482403Y-64743D01*
X482173Y-64433D01*
X481905Y-64330D01*
X480716D01*
G01X486840Y-62883D02*
X487798Y-65983D01*
X488756Y-62883D01*
G01X491665Y-65983D02*
X490131D01*
Y-62883D01*
X491665D01*
G01X491051Y-64381D02*
X490131D01*
G01X493116Y-65983D02*
Y-62883D01*
X494880Y-65983D01*
Y-62883D01*
G01X496255Y-65983D02*
Y-62883D01*
X497021D01*
X497328Y-63038D01*
X497558Y-63245D01*
X497750Y-63555D01*
X497903Y-63916D01*
X497941Y-64433D01*
X497903Y-64950D01*
X497750Y-65311D01*
X497558Y-65621D01*
X497328Y-65828D01*
X497021Y-65983D01*
X496255D01*
G01X500198D02*
X499891Y-65931D01*
X499623Y-65725D01*
X499393Y-65415D01*
X499240Y-65053D01*
X499163Y-64640D01*
Y-64226D01*
X499240Y-63813D01*
X499393Y-63451D01*
X499623Y-63141D01*
X499891Y-62935D01*
X500198Y-62883D01*
X500505Y-62935D01*
X500773Y-63141D01*
X501003Y-63451D01*
X501156Y-63813D01*
X501233Y-64226D01*
Y-64640D01*
X501156Y-65053D01*
X501003Y-65415D01*
X500773Y-65725D01*
X500505Y-65931D01*
X500198Y-65983D01*
G01X502531D02*
Y-62883D01*
X503490D01*
X503796Y-63038D01*
X503988Y-63245D01*
X504065Y-63658D01*
X503988Y-64071D01*
X503758Y-64330D01*
X503490Y-64485D01*
X502531D01*
G01X503490D02*
X504065Y-65983D01*
G01X493436Y1453504D02*
G03I-2451J0D01*
G01X484775Y1457835D02*
G03I-2452J0D01*
G01X493437Y1468859D02*
G03I-2452J0D01*
G01X484775Y1473189D02*
G03I-2452J0D01*
G01X493436Y1499567D02*
G03I-2451J0D01*
G01X493437Y1484213D02*
G03I-2452J0D01*
G01X484775Y1488544D02*
G03I-2452J0D01*
G01X493437Y1514922D02*
G03I-2452J0D01*
G01X484775Y1503898D02*
G03I-2452J0D01*
G01Y1519252D02*
G03I-2452J0D01*
G01X493437Y1555867D02*
G03I-2452J0D01*
G01X484775Y1560197D02*
G03I-2452J0D01*
G01X493437Y1571221D02*
G03I-2452J0D01*
G01X484775Y1575552D02*
G03I-2452J0D01*
G01X493436Y1586575D02*
G03I-2451J0D01*
G01X484775Y1590906D02*
G03I-2452J0D01*
G01X493437Y1601930D02*
G03I-2452J0D01*
G01X484775Y1606260D02*
G03I-2452J0D01*
G01X493437Y1617284D02*
G03I-2452J0D01*
G01X484775Y1621615D02*
G03I-2452J0D01*
G01X510759Y1453504D02*
G03I-2452J0D01*
G01X502098Y1457835D02*
G03I-2452J0D01*
G01X510759Y1468859D02*
G03I-2452J0D01*
G01X502098Y1473189D02*
G03I-2452J0D01*
G01X510759Y1484213D02*
G03I-2452J0D01*
G01X502098Y1488544D02*
G03I-2452J0D01*
G01X510759Y1514922D02*
G03I-2452J0D01*
G01Y1499567D02*
G03I-2452J0D01*
G01X502098Y1503898D02*
G03I-2452J0D01*
G01Y1519252D02*
G03I-2452J0D01*
G01X510759Y1555867D02*
G03I-2452J0D01*
G01X502098Y1560197D02*
G03I-2452J0D01*
G01X510759Y1571221D02*
G03I-2452J0D01*
G01X502098Y1575552D02*
G03I-2452J0D01*
G01X510759Y1586575D02*
G03I-2452J0D01*
G01X502098Y1590906D02*
G03I-2452J0D01*
G01X510759Y1601930D02*
G03I-2452J0D01*
G01X502098Y1606260D02*
G03I-2452J0D01*
G01X510759Y1617284D02*
G03I-2452J0D01*
G01X502098Y1621615D02*
G03I-2452J0D01*
G01X502806Y1698997D02*
X495306D01*
X502806Y1703291D01*
X495306D01*
G01X502806Y1708644D02*
X502681Y1707897D01*
X502181Y1707244D01*
X501431Y1706684D01*
X500556Y1706311D01*
X499556Y1706124D01*
X498556D01*
X497556Y1706311D01*
X496681Y1706684D01*
X495931Y1707244D01*
X495431Y1707897D01*
X495306Y1708644D01*
X495431Y1709391D01*
X495931Y1710044D01*
X496681Y1710604D01*
X497556Y1710977D01*
X498556Y1711164D01*
X499556D01*
X500556Y1710977D01*
X501431Y1710604D01*
X502181Y1710044D01*
X502681Y1709391D01*
X502806Y1708644D01*
G01Y1713997D02*
X495306D01*
X502806Y1718291D01*
X495306D01*
G01X500306Y1722431D02*
Y1724857D01*
G01X502806Y1728717D02*
X495306D01*
X501556Y1731144D01*
X495306Y1733571D01*
X502806D01*
G01Y1736311D02*
X495306Y1738644D01*
X502806Y1740977D01*
G01X500181Y1740137D02*
Y1737151D01*
G01X502806Y1744277D02*
X495306D01*
Y1746611D01*
X495681Y1747357D01*
X496181Y1747824D01*
X497181Y1748011D01*
X498181Y1747824D01*
X498806Y1747264D01*
X499181Y1746611D01*
Y1744277D01*
G01Y1746611D02*
X502806Y1748011D01*
G01Y1751591D02*
X495306D01*
G01Y1755137D02*
X499931Y1751591D01*
G01X502806Y1755697D02*
X497806Y1753177D01*
G01X503056Y1761144D02*
X502931Y1760957D01*
X502681D01*
X502556Y1761144D01*
X502681Y1761331D01*
X502931D01*
X503056Y1761144D01*
G01X499681D02*
X499556Y1760957D01*
X499306D01*
X499181Y1761144D01*
X499306Y1761331D01*
X499556D01*
X499681Y1761144D01*
G01X502806Y1766777D02*
X495306D01*
Y1769111D01*
X495681Y1769857D01*
X496181Y1770324D01*
X497181Y1770511D01*
X498181Y1770324D01*
X498806Y1769764D01*
X499181Y1769111D01*
Y1766777D01*
G01Y1769111D02*
X502806Y1770511D01*
G01Y1778011D02*
Y1774277D01*
X495306D01*
Y1778011D01*
G01X498931Y1776517D02*
Y1774277D01*
G01X495931Y1785697D02*
X495556Y1785137D01*
X495306Y1784484D01*
Y1783737D01*
X495681Y1782897D01*
X496306Y1782244D01*
X497056Y1781777D01*
X498306Y1781404D01*
X499431Y1781311D01*
X500556Y1781497D01*
X501306Y1781777D01*
X502056Y1782337D01*
X502556Y1782991D01*
X502806Y1783644D01*
Y1784297D01*
X502556Y1784951D01*
X502181Y1785511D01*
X501681Y1785977D01*
G01X502806Y1791144D02*
X502681Y1790397D01*
X502181Y1789744D01*
X501431Y1789184D01*
X500556Y1788811D01*
X499556Y1788624D01*
X498556D01*
X497556Y1788811D01*
X496681Y1789184D01*
X495931Y1789744D01*
X495431Y1790397D01*
X495306Y1791144D01*
X495431Y1791891D01*
X495931Y1792544D01*
X496681Y1793104D01*
X497556Y1793477D01*
X498556Y1793664D01*
X499556D01*
X500556Y1793477D01*
X501431Y1793104D01*
X502181Y1792544D01*
X502681Y1791891D01*
X502806Y1791144D01*
G01Y1796217D02*
X495306D01*
X501556Y1798644D01*
X495306Y1801071D01*
X502806D01*
G01Y1803717D02*
X495306D01*
X501556Y1806144D01*
X495306Y1808571D01*
X502806D01*
G01Y1815511D02*
Y1811777D01*
X495306D01*
Y1815511D01*
G01X498931Y1814017D02*
Y1811777D01*
G01X502806Y1818997D02*
X495306D01*
X502806Y1823291D01*
X495306D01*
G01X502806Y1826591D02*
X495306D01*
Y1828457D01*
X495681Y1829204D01*
X496181Y1829764D01*
X496931Y1830231D01*
X497806Y1830604D01*
X499056Y1830697D01*
X500306Y1830604D01*
X501181Y1830231D01*
X501931Y1829764D01*
X502431Y1829204D01*
X502806Y1828457D01*
Y1826591D01*
G01Y1838011D02*
Y1834277D01*
X495306D01*
Y1838011D01*
G01X498931Y1836517D02*
Y1834277D01*
G01X502806Y1841591D02*
X495306D01*
Y1843457D01*
X495681Y1844204D01*
X496181Y1844764D01*
X496931Y1845231D01*
X497806Y1845604D01*
X499056Y1845697D01*
X500306Y1845604D01*
X501181Y1845231D01*
X501931Y1844764D01*
X502431Y1844204D01*
X502806Y1843457D01*
Y1841591D01*
G01Y1856591D02*
X495306D01*
Y1858457D01*
X495681Y1859204D01*
X496181Y1859764D01*
X496931Y1860231D01*
X497806Y1860604D01*
X499056Y1860697D01*
X500306Y1860604D01*
X501181Y1860231D01*
X501931Y1859764D01*
X502431Y1859204D01*
X502806Y1858457D01*
Y1856591D01*
G01Y1864277D02*
X495306D01*
Y1866611D01*
X495681Y1867357D01*
X496181Y1867824D01*
X497181Y1868011D01*
X498181Y1867824D01*
X498806Y1867264D01*
X499181Y1866611D01*
Y1864277D01*
G01Y1866611D02*
X502806Y1868011D01*
G01X495306Y1872524D02*
Y1874764D01*
G01Y1873644D02*
X502806D01*
G01Y1872524D02*
Y1874764D01*
G01X495306Y1879277D02*
X502806D01*
Y1883011D01*
G01X495306Y1886777D02*
X502806D01*
Y1890511D01*
G01X501806Y1901684D02*
X502431Y1902431D01*
X502806Y1903271D01*
Y1904017D01*
X502431Y1904764D01*
X501806Y1905324D01*
X500931Y1905604D01*
X500056Y1905417D01*
X499306Y1904951D01*
X498806Y1904111D01*
X498556Y1902991D01*
X498056Y1902337D01*
X497181Y1902057D01*
X496306Y1902244D01*
X495681Y1902711D01*
X495306Y1903364D01*
Y1904017D01*
X495556Y1904671D01*
X496181Y1905231D01*
G01X495306Y1910024D02*
Y1912264D01*
G01Y1911144D02*
X502806D01*
G01Y1910024D02*
Y1912264D01*
G01X495306Y1916871D02*
Y1920417D01*
X502806Y1916871D01*
Y1920417D01*
G01Y1928011D02*
Y1924277D01*
X495306D01*
Y1928011D01*
G01X498931Y1926517D02*
Y1924277D01*
G01X502806Y1939371D02*
X495306D01*
Y1942917D01*
G01X498931Y1941611D02*
Y1939371D01*
G01X502806Y1948644D02*
X502681Y1947897D01*
X502181Y1947244D01*
X501431Y1946684D01*
X500556Y1946311D01*
X499556Y1946124D01*
X498556D01*
X497556Y1946311D01*
X496681Y1946684D01*
X495931Y1947244D01*
X495431Y1947897D01*
X495306Y1948644D01*
X495431Y1949391D01*
X495931Y1950044D01*
X496681Y1950604D01*
X497556Y1950977D01*
X498556Y1951164D01*
X499556D01*
X500556Y1950977D01*
X501431Y1950604D01*
X502181Y1950044D01*
X502681Y1949391D01*
X502806Y1948644D01*
G01Y1954277D02*
X495306D01*
Y1956611D01*
X495681Y1957357D01*
X496181Y1957824D01*
X497181Y1958011D01*
X498181Y1957824D01*
X498806Y1957264D01*
X499181Y1956611D01*
Y1954277D01*
G01Y1956611D02*
X502806Y1958011D01*
G01X495306Y1971144D02*
X495556Y1970397D01*
X496181Y1969837D01*
X496931Y1969464D01*
X497931Y1969184D01*
X499056Y1969091D01*
X500181Y1969184D01*
X501181Y1969464D01*
X501931Y1969837D01*
X502556Y1970397D01*
X502806Y1971144D01*
X502556Y1971891D01*
X501931Y1972451D01*
X501181Y1972824D01*
X500181Y1973104D01*
X499056Y1973197D01*
X497931Y1973104D01*
X496931Y1972824D01*
X496181Y1972451D01*
X495556Y1971891D01*
X495306Y1971144D01*
G01X503056Y1978644D02*
X502931Y1978457D01*
X502681D01*
X502556Y1978644D01*
X502681Y1978831D01*
X502931D01*
X503056Y1978644D01*
G01X501306Y1984091D02*
X502181Y1984651D01*
X502681Y1985397D01*
X502806Y1986237D01*
X502681Y1986984D01*
X502056Y1987731D01*
X501306Y1988197D01*
X500556Y1988291D01*
X499681Y1988104D01*
X499056Y1987451D01*
X498806Y1986797D01*
Y1985957D01*
G01Y1986797D02*
X498431Y1987357D01*
X497806Y1987824D01*
X497056Y1988011D01*
X496306Y1987824D01*
X495681Y1987357D01*
X495306Y1986517D01*
X495431Y1985677D01*
X495931Y1984837D01*
G01X502806Y1993644D02*
X495306D01*
X496806Y1992524D01*
G01X502806D02*
Y1994764D01*
G01Y1998717D02*
X495306D01*
X501556Y2001144D01*
X495306Y2003571D01*
X502806D01*
G01Y2006217D02*
X495306D01*
X501556Y2008644D01*
X495306Y2011071D01*
X502806D01*
G01Y2021871D02*
X495306D01*
Y2025417D01*
G01X498931Y2024111D02*
Y2021871D01*
G01X495306Y2030024D02*
Y2032264D01*
G01Y2031144D02*
X502806D01*
G01Y2030024D02*
Y2032264D01*
G01Y2036497D02*
X495306D01*
X502806Y2040791D01*
X495306D01*
G01Y2045024D02*
Y2047264D01*
G01Y2046144D02*
X502806D01*
G01Y2045024D02*
Y2047264D01*
G01X501806Y2051684D02*
X502431Y2052431D01*
X502806Y2053271D01*
Y2054017D01*
X502431Y2054764D01*
X501806Y2055324D01*
X500931Y2055604D01*
X500056Y2055417D01*
X499306Y2054951D01*
X498806Y2054111D01*
X498556Y2052991D01*
X498056Y2052337D01*
X497181Y2052057D01*
X496306Y2052244D01*
X495681Y2052711D01*
X495306Y2053364D01*
Y2054017D01*
X495556Y2054671D01*
X496181Y2055231D01*
G01X502806Y2059184D02*
X495306D01*
G01Y2063104D02*
X502806D01*
G01X499056D02*
Y2059184D01*
G01X502806Y2070511D02*
Y2066777D01*
X495306D01*
Y2070511D01*
G01X498931Y2069017D02*
Y2066777D01*
G01X502806Y2074091D02*
X495306D01*
Y2075957D01*
X495681Y2076704D01*
X496181Y2077264D01*
X496931Y2077731D01*
X497806Y2078104D01*
X499056Y2078197D01*
X500306Y2078104D01*
X501181Y2077731D01*
X501931Y2077264D01*
X502431Y2076704D01*
X502806Y2075957D01*
Y2074091D01*
G01Y2089277D02*
X495306D01*
Y2091517D01*
X495681Y2092264D01*
X496556Y2092824D01*
X497556Y2093011D01*
X498556Y2092824D01*
X499306Y2092357D01*
X499681Y2091517D01*
Y2089277D01*
G01X495306Y2098644D02*
X502806D01*
G01X495306Y2096497D02*
Y2100791D01*
G01X502806Y2104184D02*
X495306D01*
G01Y2108104D02*
X502806D01*
G01X499056D02*
Y2104184D01*
G01X495306Y2120024D02*
Y2122264D01*
G01Y2121144D02*
X502806D01*
G01Y2120024D02*
Y2122264D01*
G01X501806Y2126684D02*
X502431Y2127431D01*
X502806Y2128271D01*
Y2129017D01*
X502431Y2129764D01*
X501806Y2130324D01*
X500931Y2130604D01*
X500056Y2130417D01*
X499306Y2129951D01*
X498806Y2129111D01*
X498556Y2127991D01*
X498056Y2127337D01*
X497181Y2127057D01*
X496306Y2127244D01*
X495681Y2127711D01*
X495306Y2128364D01*
Y2129017D01*
X495556Y2129671D01*
X496181Y2130231D01*
G01X495306Y2143644D02*
X495556Y2142897D01*
X496181Y2142337D01*
X496931Y2141964D01*
X497931Y2141684D01*
X499056Y2141591D01*
X500181Y2141684D01*
X501181Y2141964D01*
X501931Y2142337D01*
X502556Y2142897D01*
X502806Y2143644D01*
X502556Y2144391D01*
X501931Y2144951D01*
X501181Y2145324D01*
X500181Y2145604D01*
X499056Y2145697D01*
X497931Y2145604D01*
X496931Y2145324D01*
X496181Y2144951D01*
X495556Y2144391D01*
X495306Y2143644D01*
G01X503056Y2151144D02*
X502931Y2150957D01*
X502681D01*
X502556Y2151144D01*
X502681Y2151331D01*
X502931D01*
X503056Y2151144D01*
G01X502806Y2159764D02*
X495306D01*
X500681Y2156311D01*
Y2160977D01*
G01X502806Y2163717D02*
X495306D01*
X501556Y2166144D01*
X495306Y2168571D01*
X502806D01*
G01Y2171217D02*
X495306D01*
X501556Y2173644D01*
X495306Y2176071D01*
X502806D01*
G01Y2186217D02*
X495306D01*
X501556Y2188644D01*
X495306Y2191071D01*
X502806D01*
G01Y2198011D02*
Y2194277D01*
X495306D01*
Y2198011D01*
G01X498931Y2196517D02*
Y2194277D01*
G01X495306Y2203644D02*
X502806D01*
G01X495306Y2201497D02*
Y2205791D01*
G01X502806Y2209277D02*
X495306D01*
Y2211611D01*
X495681Y2212357D01*
X496181Y2212824D01*
X497181Y2213011D01*
X498181Y2212824D01*
X498806Y2212264D01*
X499181Y2211611D01*
Y2209277D01*
G01Y2211611D02*
X502806Y2213011D01*
G01X495306Y2217524D02*
Y2219764D01*
G01Y2218644D02*
X502806D01*
G01Y2217524D02*
Y2219764D01*
G01X495931Y2228197D02*
X495556Y2227637D01*
X495306Y2226984D01*
Y2226237D01*
X495681Y2225397D01*
X496306Y2224744D01*
X497056Y2224277D01*
X498306Y2223904D01*
X499431Y2223811D01*
X500556Y2223997D01*
X501306Y2224277D01*
X502056Y2224837D01*
X502556Y2225491D01*
X502806Y2226144D01*
Y2226797D01*
X502556Y2227451D01*
X502181Y2228011D01*
X501681Y2228477D01*
G01X502806Y2239091D02*
X495306D01*
Y2240957D01*
X495681Y2241704D01*
X496181Y2242264D01*
X496931Y2242731D01*
X497806Y2243104D01*
X499056Y2243197D01*
X500306Y2243104D01*
X501181Y2242731D01*
X501931Y2242264D01*
X502431Y2241704D01*
X502806Y2240957D01*
Y2239091D01*
G01Y2246777D02*
X495306D01*
Y2249111D01*
X495681Y2249857D01*
X496181Y2250324D01*
X497181Y2250511D01*
X498181Y2250324D01*
X498806Y2249764D01*
X499181Y2249111D01*
Y2246777D01*
G01Y2249111D02*
X502806Y2250511D01*
G01X495306Y2255024D02*
Y2257264D01*
G01Y2256144D02*
X502806D01*
G01Y2255024D02*
Y2257264D01*
G01X495306Y2261777D02*
X502806D01*
Y2265511D01*
G01X495306Y2269277D02*
X502806D01*
Y2273011D01*
G01X505306Y2278177D02*
X504056Y2277244D01*
X502806Y2276777D01*
X497806D01*
X496556Y2277244D01*
X495306Y2278177D01*
G01Y2286144D02*
X495556Y2285397D01*
X496181Y2284837D01*
X496931Y2284464D01*
X497931Y2284184D01*
X499056Y2284091D01*
X500181Y2284184D01*
X501181Y2284464D01*
X501931Y2284837D01*
X502556Y2285397D01*
X502806Y2286144D01*
X502556Y2286891D01*
X501931Y2287451D01*
X501181Y2287824D01*
X500181Y2288104D01*
X499056Y2288197D01*
X497931Y2288104D01*
X496931Y2287824D01*
X496181Y2287451D01*
X495556Y2286891D01*
X495306Y2286144D01*
G01X503056Y2293644D02*
X502931Y2293457D01*
X502681D01*
X502556Y2293644D01*
X502681Y2293831D01*
X502931D01*
X503056Y2293644D01*
G01X495306Y2301144D02*
X495556Y2300397D01*
X496181Y2299837D01*
X496931Y2299464D01*
X497931Y2299184D01*
X499056Y2299091D01*
X500181Y2299184D01*
X501181Y2299464D01*
X501931Y2299837D01*
X502556Y2300397D01*
X502806Y2301144D01*
X502556Y2301891D01*
X501931Y2302451D01*
X501181Y2302824D01*
X500181Y2303104D01*
X499056Y2303197D01*
X497931Y2303104D01*
X496931Y2302824D01*
X496181Y2302451D01*
X495556Y2301891D01*
X495306Y2301144D01*
G01X502806Y2308644D02*
X495306D01*
X496806Y2307524D01*
G01X502806D02*
Y2309764D01*
G01X501681Y2314091D02*
X502306Y2314651D01*
X502681Y2315304D01*
X502806Y2316144D01*
X502556Y2316984D01*
X502056Y2317637D01*
X501181Y2318104D01*
X500181Y2318197D01*
X499181Y2318011D01*
X498556Y2317544D01*
X498056Y2316891D01*
X497931Y2316237D01*
X498056Y2315584D01*
X498556Y2314744D01*
X495306Y2315024D01*
Y2317544D01*
G01X502806Y2323457D02*
X501181Y2323644D01*
X499806Y2323924D01*
X498556Y2324297D01*
X497181Y2324764D01*
X495306Y2325511D01*
Y2321777D01*
G01X496931Y2330304D02*
X495306Y2330771D01*
G01Y2331984D02*
X496931Y2331517D01*
G01X505306Y2339111D02*
X504056Y2340044D01*
X502806Y2340511D01*
X497806D01*
X496556Y2340044D01*
X495306Y2339111D01*
G01X519421Y1457835D02*
G03I-2452J0D01*
G01Y1473189D02*
G03I-2452J0D01*
G01Y1488544D02*
G03I-2452J0D01*
G01Y1503898D02*
G03I-2452J0D01*
G01Y1519252D02*
G03I-2452J0D01*
G01Y1560197D02*
G03I-2452J0D01*
G01Y1575552D02*
G03I-2452J0D01*
G01Y1590906D02*
G03I-2452J0D01*
G01Y1606260D02*
G03I-2452J0D01*
G01Y1621615D02*
G03I-2452J0D01*
G01X514548Y1698034D02*
X507048D01*
X513298Y1700461D01*
X507048Y1702888D01*
X514548D01*
G01Y1705628D02*
X507048Y1707961D01*
X514548Y1710294D01*
G01X511923Y1709454D02*
Y1706468D01*
G01X514548Y1713594D02*
X507048D01*
Y1715928D01*
X507423Y1716674D01*
X507923Y1717141D01*
X508923Y1717328D01*
X509923Y1717141D01*
X510548Y1716581D01*
X510923Y1715928D01*
Y1713594D01*
G01Y1715928D02*
X514548Y1717328D01*
G01Y1720908D02*
X507048D01*
G01Y1724454D02*
X511673Y1720908D01*
G01X514548Y1725014D02*
X509548Y1722494D01*
G01X514798Y1730461D02*
X514673Y1730274D01*
X514423D01*
X514298Y1730461D01*
X514423Y1730648D01*
X514673D01*
X514798Y1730461D01*
G01X511423D02*
X511298Y1730274D01*
X511048D01*
X510923Y1730461D01*
X511048Y1730648D01*
X511298D01*
X511423Y1730461D01*
G01X514548Y1736094D02*
X507048D01*
Y1738428D01*
X507423Y1739174D01*
X507923Y1739641D01*
X508923Y1739828D01*
X509923Y1739641D01*
X510548Y1739081D01*
X510923Y1738428D01*
Y1736094D01*
G01Y1738428D02*
X514548Y1739828D01*
G01Y1747328D02*
Y1743594D01*
X507048D01*
Y1747328D01*
G01X510673Y1745834D02*
Y1743594D01*
G01X507673Y1755014D02*
X507298Y1754454D01*
X507048Y1753801D01*
Y1753054D01*
X507423Y1752214D01*
X508048Y1751561D01*
X508798Y1751094D01*
X510048Y1750721D01*
X511173Y1750628D01*
X512298Y1750814D01*
X513048Y1751094D01*
X513798Y1751654D01*
X514298Y1752308D01*
X514548Y1752961D01*
Y1753614D01*
X514298Y1754268D01*
X513923Y1754828D01*
X513423Y1755294D01*
G01X514548Y1760461D02*
X514423Y1759714D01*
X513923Y1759061D01*
X513173Y1758501D01*
X512298Y1758128D01*
X511298Y1757941D01*
X510298D01*
X509298Y1758128D01*
X508423Y1758501D01*
X507673Y1759061D01*
X507173Y1759714D01*
X507048Y1760461D01*
X507173Y1761208D01*
X507673Y1761861D01*
X508423Y1762421D01*
X509298Y1762794D01*
X510298Y1762981D01*
X511298D01*
X512298Y1762794D01*
X513173Y1762421D01*
X513923Y1761861D01*
X514423Y1761208D01*
X514548Y1760461D01*
G01Y1765534D02*
X507048D01*
X513298Y1767961D01*
X507048Y1770388D01*
X514548D01*
G01Y1773034D02*
X507048D01*
X513298Y1775461D01*
X507048Y1777888D01*
X514548D01*
G01Y1784828D02*
Y1781094D01*
X507048D01*
Y1784828D01*
G01X510673Y1783334D02*
Y1781094D01*
G01X514548Y1788314D02*
X507048D01*
X514548Y1792608D01*
X507048D01*
G01X514548Y1795908D02*
X507048D01*
Y1797774D01*
X507423Y1798521D01*
X507923Y1799081D01*
X508673Y1799548D01*
X509548Y1799921D01*
X510798Y1800014D01*
X512048Y1799921D01*
X512923Y1799548D01*
X513673Y1799081D01*
X514173Y1798521D01*
X514548Y1797774D01*
Y1795908D01*
G01Y1807328D02*
Y1803594D01*
X507048D01*
Y1807328D01*
G01X510673Y1805834D02*
Y1803594D01*
G01X514548Y1810908D02*
X507048D01*
Y1812774D01*
X507423Y1813521D01*
X507923Y1814081D01*
X508673Y1814548D01*
X509548Y1814921D01*
X510798Y1815014D01*
X512048Y1814921D01*
X512923Y1814548D01*
X513673Y1814081D01*
X514173Y1813521D01*
X514548Y1812774D01*
Y1810908D01*
G01Y1825908D02*
X507048D01*
Y1827774D01*
X507423Y1828521D01*
X507923Y1829081D01*
X508673Y1829548D01*
X509548Y1829921D01*
X510798Y1830014D01*
X512048Y1829921D01*
X512923Y1829548D01*
X513673Y1829081D01*
X514173Y1828521D01*
X514548Y1827774D01*
Y1825908D01*
G01Y1833594D02*
X507048D01*
Y1835928D01*
X507423Y1836674D01*
X507923Y1837141D01*
X508923Y1837328D01*
X509923Y1837141D01*
X510548Y1836581D01*
X510923Y1835928D01*
Y1833594D01*
G01Y1835928D02*
X514548Y1837328D01*
G01X507048Y1841841D02*
Y1844081D01*
G01Y1842961D02*
X514548D01*
G01Y1841841D02*
Y1844081D01*
G01X507048Y1848594D02*
X514548D01*
Y1852328D01*
G01X507048Y1856094D02*
X514548D01*
Y1859828D01*
G01X513548Y1871001D02*
X514173Y1871748D01*
X514548Y1872588D01*
Y1873334D01*
X514173Y1874081D01*
X513548Y1874641D01*
X512673Y1874921D01*
X511798Y1874734D01*
X511048Y1874268D01*
X510548Y1873428D01*
X510298Y1872308D01*
X509798Y1871654D01*
X508923Y1871374D01*
X508048Y1871561D01*
X507423Y1872028D01*
X507048Y1872681D01*
Y1873334D01*
X507298Y1873988D01*
X507923Y1874548D01*
G01X507048Y1879341D02*
Y1881581D01*
G01Y1880461D02*
X514548D01*
G01Y1879341D02*
Y1881581D01*
G01X507048Y1886188D02*
Y1889734D01*
X514548Y1886188D01*
Y1889734D01*
G01Y1897328D02*
Y1893594D01*
X507048D01*
Y1897328D01*
G01X510673Y1895834D02*
Y1893594D01*
G01X514548Y1908688D02*
X507048D01*
Y1912234D01*
G01X510673Y1910928D02*
Y1908688D01*
G01X514548Y1917961D02*
X514423Y1917214D01*
X513923Y1916561D01*
X513173Y1916001D01*
X512298Y1915628D01*
X511298Y1915441D01*
X510298D01*
X509298Y1915628D01*
X508423Y1916001D01*
X507673Y1916561D01*
X507173Y1917214D01*
X507048Y1917961D01*
X507173Y1918708D01*
X507673Y1919361D01*
X508423Y1919921D01*
X509298Y1920294D01*
X510298Y1920481D01*
X511298D01*
X512298Y1920294D01*
X513173Y1919921D01*
X513923Y1919361D01*
X514423Y1918708D01*
X514548Y1917961D01*
G01Y1923594D02*
X507048D01*
Y1925928D01*
X507423Y1926674D01*
X507923Y1927141D01*
X508923Y1927328D01*
X509923Y1927141D01*
X510548Y1926581D01*
X510923Y1925928D01*
Y1923594D01*
G01Y1925928D02*
X514548Y1927328D01*
G01X507048Y1940461D02*
X507298Y1939714D01*
X507923Y1939154D01*
X508673Y1938781D01*
X509673Y1938501D01*
X510798Y1938408D01*
X511923Y1938501D01*
X512923Y1938781D01*
X513673Y1939154D01*
X514298Y1939714D01*
X514548Y1940461D01*
X514298Y1941208D01*
X513673Y1941768D01*
X512923Y1942141D01*
X511923Y1942421D01*
X510798Y1942514D01*
X509673Y1942421D01*
X508673Y1942141D01*
X507923Y1941768D01*
X507298Y1941208D01*
X507048Y1940461D01*
G01X514798Y1947961D02*
X514673Y1947774D01*
X514423D01*
X514298Y1947961D01*
X514423Y1948148D01*
X514673D01*
X514798Y1947961D01*
G01X513423Y1953408D02*
X514048Y1953968D01*
X514423Y1954621D01*
X514548Y1955461D01*
X514298Y1956301D01*
X513798Y1956954D01*
X512923Y1957421D01*
X511923Y1957514D01*
X510923Y1957328D01*
X510298Y1956861D01*
X509798Y1956208D01*
X509673Y1955554D01*
X509798Y1954901D01*
X510298Y1954061D01*
X507048Y1954341D01*
Y1956861D01*
G01X514548Y1960534D02*
X507048D01*
X513298Y1962961D01*
X507048Y1965388D01*
X514548D01*
G01Y1968034D02*
X507048D01*
X513298Y1970461D01*
X507048Y1972888D01*
X514548D01*
G01Y1983688D02*
X507048D01*
Y1987234D01*
G01X510673Y1985928D02*
Y1983688D01*
G01X507048Y1991841D02*
Y1994081D01*
G01Y1992961D02*
X514548D01*
G01Y1991841D02*
Y1994081D01*
G01Y1998314D02*
X507048D01*
X514548Y2002608D01*
X507048D01*
G01Y2006841D02*
Y2009081D01*
G01Y2007961D02*
X514548D01*
G01Y2006841D02*
Y2009081D01*
G01X513548Y2013501D02*
X514173Y2014248D01*
X514548Y2015088D01*
Y2015834D01*
X514173Y2016581D01*
X513548Y2017141D01*
X512673Y2017421D01*
X511798Y2017234D01*
X511048Y2016768D01*
X510548Y2015928D01*
X510298Y2014808D01*
X509798Y2014154D01*
X508923Y2013874D01*
X508048Y2014061D01*
X507423Y2014528D01*
X507048Y2015181D01*
Y2015834D01*
X507298Y2016488D01*
X507923Y2017048D01*
G01X514548Y2021001D02*
X507048D01*
G01Y2024921D02*
X514548D01*
G01X510798D02*
Y2021001D01*
G01X514548Y2032328D02*
Y2028594D01*
X507048D01*
Y2032328D01*
G01X510673Y2030834D02*
Y2028594D01*
G01X514548Y2035908D02*
X507048D01*
Y2037774D01*
X507423Y2038521D01*
X507923Y2039081D01*
X508673Y2039548D01*
X509548Y2039921D01*
X510798Y2040014D01*
X512048Y2039921D01*
X512923Y2039548D01*
X513673Y2039081D01*
X514173Y2038521D01*
X514548Y2037774D01*
Y2035908D01*
G01Y2051094D02*
X507048D01*
Y2053334D01*
X507423Y2054081D01*
X508298Y2054641D01*
X509298Y2054828D01*
X510298Y2054641D01*
X511048Y2054174D01*
X511423Y2053334D01*
Y2051094D01*
G01X507048Y2060461D02*
X514548D01*
G01X507048Y2058314D02*
Y2062608D01*
G01X514548Y2066001D02*
X507048D01*
G01Y2069921D02*
X514548D01*
G01X510798D02*
Y2066001D01*
G01X507048Y2081841D02*
Y2084081D01*
G01Y2082961D02*
X514548D01*
G01Y2081841D02*
Y2084081D01*
G01X513548Y2088501D02*
X514173Y2089248D01*
X514548Y2090088D01*
Y2090834D01*
X514173Y2091581D01*
X513548Y2092141D01*
X512673Y2092421D01*
X511798Y2092234D01*
X511048Y2091768D01*
X510548Y2090928D01*
X510298Y2089808D01*
X509798Y2089154D01*
X508923Y2088874D01*
X508048Y2089061D01*
X507423Y2089528D01*
X507048Y2090181D01*
Y2090834D01*
X507298Y2091488D01*
X507923Y2092048D01*
G01X507048Y2105461D02*
X507298Y2104714D01*
X507923Y2104154D01*
X508673Y2103781D01*
X509673Y2103501D01*
X510798Y2103408D01*
X511923Y2103501D01*
X512923Y2103781D01*
X513673Y2104154D01*
X514298Y2104714D01*
X514548Y2105461D01*
X514298Y2106208D01*
X513673Y2106768D01*
X512923Y2107141D01*
X511923Y2107421D01*
X510798Y2107514D01*
X509673Y2107421D01*
X508673Y2107141D01*
X507923Y2106768D01*
X507298Y2106208D01*
X507048Y2105461D01*
G01X514798Y2112961D02*
X514673Y2112774D01*
X514423D01*
X514298Y2112961D01*
X514423Y2113148D01*
X514673D01*
X514798Y2112961D01*
G01X511423Y2118688D02*
X510548Y2119341D01*
X510048Y2119901D01*
X509798Y2120648D01*
X510048Y2121301D01*
X510548Y2121768D01*
X511298Y2122141D01*
X512173Y2122234D01*
X512923Y2122141D01*
X513673Y2121768D01*
X514298Y2121208D01*
X514548Y2120554D01*
X514298Y2119808D01*
X513548Y2119154D01*
X512423Y2118781D01*
X511173Y2118688D01*
X509548Y2118874D01*
X508673Y2119154D01*
X507798Y2119621D01*
X507173Y2120274D01*
X507048Y2120928D01*
X507298Y2121581D01*
X507923Y2122048D01*
G01X514548Y2125534D02*
X507048D01*
X513298Y2127961D01*
X507048Y2130388D01*
X514548D01*
G01Y2133034D02*
X507048D01*
X513298Y2135461D01*
X507048Y2137888D01*
X514548D01*
G01Y2148034D02*
X507048D01*
X513298Y2150461D01*
X507048Y2152888D01*
X514548D01*
G01Y2159828D02*
Y2156094D01*
X507048D01*
Y2159828D01*
G01X510673Y2158334D02*
Y2156094D01*
G01X507048Y2165461D02*
X514548D01*
G01X507048Y2163314D02*
Y2167608D01*
G01X514548Y2171094D02*
X507048D01*
Y2173428D01*
X507423Y2174174D01*
X507923Y2174641D01*
X508923Y2174828D01*
X509923Y2174641D01*
X510548Y2174081D01*
X510923Y2173428D01*
Y2171094D01*
G01Y2173428D02*
X514548Y2174828D01*
G01X507048Y2179341D02*
Y2181581D01*
G01Y2180461D02*
X514548D01*
G01Y2179341D02*
Y2181581D01*
G01X507673Y2190014D02*
X507298Y2189454D01*
X507048Y2188801D01*
Y2188054D01*
X507423Y2187214D01*
X508048Y2186561D01*
X508798Y2186094D01*
X510048Y2185721D01*
X511173Y2185628D01*
X512298Y2185814D01*
X513048Y2186094D01*
X513798Y2186654D01*
X514298Y2187308D01*
X514548Y2187961D01*
Y2188614D01*
X514298Y2189268D01*
X513923Y2189828D01*
X513423Y2190294D01*
G01X514548Y2200908D02*
X507048D01*
Y2202774D01*
X507423Y2203521D01*
X507923Y2204081D01*
X508673Y2204548D01*
X509548Y2204921D01*
X510798Y2205014D01*
X512048Y2204921D01*
X512923Y2204548D01*
X513673Y2204081D01*
X514173Y2203521D01*
X514548Y2202774D01*
Y2200908D01*
G01Y2208594D02*
X507048D01*
Y2210928D01*
X507423Y2211674D01*
X507923Y2212141D01*
X508923Y2212328D01*
X509923Y2212141D01*
X510548Y2211581D01*
X510923Y2210928D01*
Y2208594D01*
G01Y2210928D02*
X514548Y2212328D01*
G01X507048Y2216841D02*
Y2219081D01*
G01Y2217961D02*
X514548D01*
G01Y2216841D02*
Y2219081D01*
G01X507048Y2223594D02*
X514548D01*
Y2227328D01*
G01X507048Y2231094D02*
X514548D01*
Y2234828D01*
G01X517048Y2239994D02*
X515798Y2239061D01*
X514548Y2238594D01*
X509548D01*
X508298Y2239061D01*
X507048Y2239994D01*
G01Y2247961D02*
X507298Y2247214D01*
X507923Y2246654D01*
X508673Y2246281D01*
X509673Y2246001D01*
X510798Y2245908D01*
X511923Y2246001D01*
X512923Y2246281D01*
X513673Y2246654D01*
X514298Y2247214D01*
X514548Y2247961D01*
X514298Y2248708D01*
X513673Y2249268D01*
X512923Y2249641D01*
X511923Y2249921D01*
X510798Y2250014D01*
X509673Y2249921D01*
X508673Y2249641D01*
X507923Y2249268D01*
X507298Y2248708D01*
X507048Y2247961D01*
G01X514798Y2255461D02*
X514673Y2255274D01*
X514423D01*
X514298Y2255461D01*
X514423Y2255648D01*
X514673D01*
X514798Y2255461D01*
G01X507048Y2262961D02*
X507298Y2262214D01*
X507923Y2261654D01*
X508673Y2261281D01*
X509673Y2261001D01*
X510798Y2260908D01*
X511923Y2261001D01*
X512923Y2261281D01*
X513673Y2261654D01*
X514298Y2262214D01*
X514548Y2262961D01*
X514298Y2263708D01*
X513673Y2264268D01*
X512923Y2264641D01*
X511923Y2264921D01*
X510798Y2265014D01*
X509673Y2264921D01*
X508673Y2264641D01*
X507923Y2264268D01*
X507298Y2263708D01*
X507048Y2262961D01*
G01X508298Y2268688D02*
X507548Y2269248D01*
X507173Y2269901D01*
X507048Y2270648D01*
X507298Y2271581D01*
X507923Y2272234D01*
X508673Y2272421D01*
X509423Y2272328D01*
X510048Y2271954D01*
X511298Y2270088D01*
X512173Y2269248D01*
X513423Y2268688D01*
X514548Y2268501D01*
Y2272421D01*
G01X513048Y2275908D02*
X513923Y2276468D01*
X514423Y2277214D01*
X514548Y2278054D01*
X514423Y2278801D01*
X513798Y2279548D01*
X513048Y2280014D01*
X512298Y2280108D01*
X511423Y2279921D01*
X510798Y2279268D01*
X510548Y2278614D01*
Y2277774D01*
G01Y2278614D02*
X510173Y2279174D01*
X509548Y2279641D01*
X508798Y2279828D01*
X508048Y2279641D01*
X507423Y2279174D01*
X507048Y2278334D01*
X507173Y2277494D01*
X507673Y2276654D01*
G01X511423Y2283688D02*
X510548Y2284341D01*
X510048Y2284901D01*
X509798Y2285648D01*
X510048Y2286301D01*
X510548Y2286768D01*
X511298Y2287141D01*
X512173Y2287234D01*
X512923Y2287141D01*
X513673Y2286768D01*
X514298Y2286208D01*
X514548Y2285554D01*
X514298Y2284808D01*
X513548Y2284154D01*
X512423Y2283781D01*
X511173Y2283688D01*
X509548Y2283874D01*
X508673Y2284154D01*
X507798Y2284621D01*
X507173Y2285274D01*
X507048Y2285928D01*
X507298Y2286581D01*
X507923Y2287048D01*
G01X508673Y2292121D02*
X507048Y2292588D01*
G01Y2293801D02*
X508673Y2293334D01*
G01X517048Y2300928D02*
X515798Y2301861D01*
X514548Y2302328D01*
X509548D01*
X508298Y2301861D01*
X507048Y2300928D01*
G01X536744Y1457835D02*
G03I-2452J0D01*
G01X528082Y1453504D02*
G03I-2452J0D01*
G01X536744Y1473189D02*
G03I-2452J0D01*
G01X528082Y1468859D02*
G03I-2452J0D01*
G01Y1499567D02*
G03I-2452J0D01*
G01X536744Y1488544D02*
G03I-2452J0D01*
G01X528082Y1484213D02*
G03I-2452J0D01*
G01Y1514922D02*
G03I-2452J0D01*
G01X536744Y1503898D02*
G03I-2452J0D01*
G01Y1519252D02*
G03I-2452J0D01*
G01X536743Y1560197D02*
G03I-2451J0D01*
G01X528082Y1555867D02*
G03I-2452J0D01*
G01X536744Y1575552D02*
G03I-2452J0D01*
G01X528082Y1571221D02*
G03I-2452J0D01*
G01X536744Y1590906D02*
G03I-2452J0D01*
G01X528082Y1586575D02*
G03I-2452J0D01*
G01X536743Y1606260D02*
G03I-2451J0D01*
G01X528082Y1601930D02*
G03I-2452J0D01*
G01X536744Y1621615D02*
G03I-2452J0D01*
G01X528082Y1617284D02*
G03I-2452J0D01*
G01X578193Y-438012D02*
X579235Y-437082D01*
X579860Y-435997D01*
X580068Y-434602D01*
X579651Y-433207D01*
X578818Y-432122D01*
X577360Y-431347D01*
X575693Y-431192D01*
X574026Y-431502D01*
X572985Y-432277D01*
X572151Y-433362D01*
X571943Y-434447D01*
X572151Y-435532D01*
X572985Y-436927D01*
X567568Y-436462D01*
Y-432277D01*
G01X580068Y-422512D02*
X577360Y-422202D01*
X575068Y-421737D01*
X572985Y-421117D01*
X570693Y-420342D01*
X567568Y-419102D01*
Y-425302D01*
G01X577568Y-413212D02*
X579027Y-412282D01*
X579860Y-411042D01*
X580068Y-409647D01*
X579860Y-408407D01*
X578818Y-407167D01*
X577568Y-406392D01*
X576318Y-406237D01*
X574860Y-406547D01*
X573818Y-407632D01*
X573401Y-408717D01*
Y-410112D01*
G01Y-408717D02*
X572776Y-407787D01*
X571735Y-407012D01*
X570485Y-406702D01*
X569235Y-407012D01*
X568193Y-407787D01*
X567568Y-409182D01*
X567776Y-410577D01*
X568610Y-411972D01*
G01X580068Y-397402D02*
X579860Y-396317D01*
X579235Y-395077D01*
X578193Y-394302D01*
X576735Y-393992D01*
X575277Y-394302D01*
X574026Y-395232D01*
X573401Y-396627D01*
Y-398177D01*
X572985Y-399107D01*
X571943Y-399882D01*
X570485Y-400192D01*
X569026Y-399727D01*
X567985Y-398642D01*
X567568Y-397402D01*
X567985Y-396162D01*
X569026Y-395077D01*
X570485Y-394612D01*
X571943Y-394922D01*
X572985Y-395697D01*
X573401Y-396627D01*
Y-398177D01*
X574026Y-399572D01*
X575277Y-400502D01*
X576735Y-400812D01*
X578193Y-400502D01*
X579235Y-399727D01*
X579860Y-398487D01*
X580068Y-397402D01*
G01X580485Y-385002D02*
X580276Y-385312D01*
X579860D01*
X579651Y-385002D01*
X579860Y-384692D01*
X580276D01*
X580485Y-385002D01*
G01X580068Y-372602D02*
X567568D01*
X570068Y-374462D01*
G01X580068D02*
Y-370742D01*
G01Y-360202D02*
X579860Y-359117D01*
X579235Y-357877D01*
X578193Y-357102D01*
X576735Y-356792D01*
X575277Y-357102D01*
X574026Y-358032D01*
X573401Y-359427D01*
Y-360977D01*
X572985Y-361907D01*
X571943Y-362682D01*
X570485Y-362992D01*
X569026Y-362527D01*
X567985Y-361442D01*
X567568Y-360202D01*
X567985Y-358962D01*
X569026Y-357877D01*
X570485Y-357412D01*
X571943Y-357722D01*
X572985Y-358497D01*
X573401Y-359427D01*
Y-360977D01*
X574026Y-362372D01*
X575277Y-363302D01*
X576735Y-363612D01*
X578193Y-363302D01*
X579235Y-362527D01*
X579860Y-361287D01*
X580068Y-360202D01*
G01Y-325602D02*
X567568D01*
X570068Y-327462D01*
G01X580068D02*
Y-323742D01*
G01Y-311342D02*
X567568D01*
X576526Y-317077D01*
Y-309327D01*
G01X578193Y-304212D02*
X579235Y-303282D01*
X579860Y-302197D01*
X580068Y-300802D01*
X579651Y-299407D01*
X578818Y-298322D01*
X577360Y-297547D01*
X575693Y-297392D01*
X574026Y-297702D01*
X572985Y-298477D01*
X572151Y-299562D01*
X571943Y-300647D01*
X572151Y-301732D01*
X572985Y-303127D01*
X567568Y-302662D01*
Y-298477D01*
G01X580485Y-288402D02*
X580276Y-288712D01*
X579860D01*
X579651Y-288402D01*
X579860Y-288092D01*
X580276D01*
X580485Y-288402D01*
G01X580068Y-276312D02*
X577360Y-276002D01*
X575068Y-275537D01*
X572985Y-274917D01*
X570693Y-274142D01*
X567568Y-272902D01*
Y-279102D01*
G01X578193Y-267012D02*
X579235Y-266082D01*
X579860Y-264997D01*
X580068Y-263602D01*
X579651Y-262207D01*
X578818Y-261122D01*
X577360Y-260347D01*
X575693Y-260192D01*
X574026Y-260502D01*
X572985Y-261277D01*
X572151Y-262362D01*
X571943Y-263447D01*
X572151Y-264532D01*
X572985Y-265927D01*
X567568Y-265462D01*
Y-261277D01*
G01X640680Y1457835D02*
G03I-2452J0D01*
G01X632018Y1453504D02*
G03I-2451J0D01*
G01X640680Y1473189D02*
G03I-2452J0D01*
G01X632019Y1468859D02*
G03I-2452J0D01*
G01X632018Y1499567D02*
G03I-2451J0D01*
G01X640680Y1488544D02*
G03I-2452J0D01*
G01X632019Y1484213D02*
G03I-2452J0D01*
G01Y1514922D02*
G03I-2452J0D01*
G01X640680Y1503898D02*
G03I-2452J0D01*
G01Y1519252D02*
G03I-2452J0D01*
G01X632019Y1555867D02*
G03I-2452J0D01*
G01X640680Y1560197D02*
G03I-2452J0D01*
G01Y1575552D02*
G03I-2452J0D01*
G01X632019Y1571221D02*
G03I-2452J0D01*
G01X640680Y1590906D02*
G03I-2452J0D01*
G01X632019Y1586575D02*
G03I-2452J0D01*
G01X640680Y1606260D02*
G03I-2452J0D01*
G01X632019Y1601930D02*
G03I-2452J0D01*
G01X640680Y1621615D02*
G03I-2452J0D01*
G01X632019Y1617284D02*
G03I-2452J0D01*
G01X649341Y1453504D02*
G03I-2451J0D01*
G01X649342Y1468859D02*
G03I-2452J0D01*
G01X649341Y1499567D02*
G03I-2451J0D01*
G01X649342Y1484213D02*
G03I-2452J0D01*
G01Y1514922D02*
G03I-2452J0D01*
G01Y1555867D02*
G03I-2452J0D01*
G01Y1571221D02*
G03I-2452J0D01*
G01Y1586575D02*
G03I-2452J0D01*
G01Y1601930D02*
G03I-2452J0D01*
G01Y1617284D02*
G03I-2452J0D01*
G01X666664Y1453504D02*
G03I-2451J0D01*
G01X658003Y1457835D02*
G03I-2452J0D01*
G01X666665Y1468859D02*
G03I-2452J0D01*
G01X658003Y1473189D02*
G03I-2452J0D01*
G01X666664Y1499567D02*
G03I-2451J0D01*
G01X666665Y1484213D02*
G03I-2452J0D01*
G01X658003Y1488544D02*
G03I-2452J0D01*
G01X666665Y1514922D02*
G03I-2452J0D01*
G01X658003Y1503898D02*
G03I-2452J0D01*
G01Y1519252D02*
G03I-2452J0D01*
G01X666665Y1555867D02*
G03I-2452J0D01*
G01X658003Y1560197D02*
G03I-2452J0D01*
G01X666665Y1571221D02*
G03I-2452J0D01*
G01X658003Y1575552D02*
G03I-2452J0D01*
G01X666664Y1586575D02*
G03I-2451J0D01*
G01X658003Y1590906D02*
G03I-2452J0D01*
G01X666665Y1601930D02*
G03I-2452J0D01*
G01X658003Y1606260D02*
G03I-2452J0D01*
G01X666665Y1617284D02*
G03I-2452J0D01*
G01X658003Y1621615D02*
G03I-2452J0D01*
G01X683987Y1453504D02*
G03I-2452J0D01*
G01X675326Y1457835D02*
G03I-2452J0D01*
G01X683987Y1468859D02*
G03I-2452J0D01*
G01X675326Y1473189D02*
G03I-2452J0D01*
G01X683987Y1499567D02*
G03I-2452J0D01*
G01Y1484213D02*
G03I-2452J0D01*
G01X675326Y1488544D02*
G03I-2452J0D01*
G01X683987Y1514922D02*
G03I-2452J0D01*
G01X675326Y1503898D02*
G03I-2452J0D01*
G01Y1519252D02*
G03I-2452J0D01*
G01X683987Y1555867D02*
G03I-2452J0D01*
G01X675326Y1560197D02*
G03I-2452J0D01*
G01X683987Y1571221D02*
G03I-2452J0D01*
G01X675326Y1575552D02*
G03I-2452J0D01*
G01X683987Y1586575D02*
G03I-2452J0D01*
G01X675326Y1590906D02*
G03I-2452J0D01*
G01X683987Y1601930D02*
G03I-2452J0D01*
G01X675326Y1606260D02*
G03I-2452J0D01*
G01X683987Y1617284D02*
G03I-2452J0D01*
G01X675326Y1621615D02*
G03I-2452J0D01*
G01X686484Y1700923D02*
X678984D01*
X686484Y1705217D01*
X678984D01*
G01X686484Y1710570D02*
X686359Y1709823D01*
X685859Y1709170D01*
X685109Y1708610D01*
X684234Y1708237D01*
X683234Y1708050D01*
X682234D01*
X681234Y1708237D01*
X680359Y1708610D01*
X679609Y1709170D01*
X679109Y1709823D01*
X678984Y1710570D01*
X679109Y1711317D01*
X679609Y1711970D01*
X680359Y1712530D01*
X681234Y1712903D01*
X682234Y1713090D01*
X683234D01*
X684234Y1712903D01*
X685109Y1712530D01*
X685859Y1711970D01*
X686359Y1711317D01*
X686484Y1710570D01*
G01Y1715923D02*
X678984D01*
X686484Y1720217D01*
X678984D01*
G01X683984Y1724357D02*
Y1726783D01*
G01X686484Y1730643D02*
X678984D01*
X685234Y1733070D01*
X678984Y1735497D01*
X686484D01*
G01Y1738237D02*
X678984Y1740570D01*
X686484Y1742903D01*
G01X683859Y1742063D02*
Y1739077D01*
G01X686484Y1746203D02*
X678984D01*
Y1748537D01*
X679359Y1749283D01*
X679859Y1749750D01*
X680859Y1749937D01*
X681859Y1749750D01*
X682484Y1749190D01*
X682859Y1748537D01*
Y1746203D01*
G01Y1748537D02*
X686484Y1749937D01*
G01Y1753517D02*
X678984D01*
G01Y1757063D02*
X683609Y1753517D01*
G01X686484Y1757623D02*
X681484Y1755103D01*
G01X686734Y1763070D02*
X686609Y1762883D01*
X686359D01*
X686234Y1763070D01*
X686359Y1763257D01*
X686609D01*
X686734Y1763070D01*
G01X683359D02*
X683234Y1762883D01*
X682984D01*
X682859Y1763070D01*
X682984Y1763257D01*
X683234D01*
X683359Y1763070D01*
G01X686484Y1768703D02*
X678984D01*
Y1771037D01*
X679359Y1771783D01*
X679859Y1772250D01*
X680859Y1772437D01*
X681859Y1772250D01*
X682484Y1771690D01*
X682859Y1771037D01*
Y1768703D01*
G01Y1771037D02*
X686484Y1772437D01*
G01Y1779937D02*
Y1776203D01*
X678984D01*
Y1779937D01*
G01X682609Y1778443D02*
Y1776203D01*
G01X679609Y1787623D02*
X679234Y1787063D01*
X678984Y1786410D01*
Y1785663D01*
X679359Y1784823D01*
X679984Y1784170D01*
X680734Y1783703D01*
X681984Y1783330D01*
X683109Y1783237D01*
X684234Y1783423D01*
X684984Y1783703D01*
X685734Y1784263D01*
X686234Y1784917D01*
X686484Y1785570D01*
Y1786223D01*
X686234Y1786877D01*
X685859Y1787437D01*
X685359Y1787903D01*
G01X686484Y1793070D02*
X686359Y1792323D01*
X685859Y1791670D01*
X685109Y1791110D01*
X684234Y1790737D01*
X683234Y1790550D01*
X682234D01*
X681234Y1790737D01*
X680359Y1791110D01*
X679609Y1791670D01*
X679109Y1792323D01*
X678984Y1793070D01*
X679109Y1793817D01*
X679609Y1794470D01*
X680359Y1795030D01*
X681234Y1795403D01*
X682234Y1795590D01*
X683234D01*
X684234Y1795403D01*
X685109Y1795030D01*
X685859Y1794470D01*
X686359Y1793817D01*
X686484Y1793070D01*
G01Y1798143D02*
X678984D01*
X685234Y1800570D01*
X678984Y1802997D01*
X686484D01*
G01Y1805643D02*
X678984D01*
X685234Y1808070D01*
X678984Y1810497D01*
X686484D01*
G01Y1817437D02*
Y1813703D01*
X678984D01*
Y1817437D01*
G01X682609Y1815943D02*
Y1813703D01*
G01X686484Y1820923D02*
X678984D01*
X686484Y1825217D01*
X678984D01*
G01X686484Y1828517D02*
X678984D01*
Y1830383D01*
X679359Y1831130D01*
X679859Y1831690D01*
X680609Y1832157D01*
X681484Y1832530D01*
X682734Y1832623D01*
X683984Y1832530D01*
X684859Y1832157D01*
X685609Y1831690D01*
X686109Y1831130D01*
X686484Y1830383D01*
Y1828517D01*
G01Y1839937D02*
Y1836203D01*
X678984D01*
Y1839937D01*
G01X682609Y1838443D02*
Y1836203D01*
G01X686484Y1843517D02*
X678984D01*
Y1845383D01*
X679359Y1846130D01*
X679859Y1846690D01*
X680609Y1847157D01*
X681484Y1847530D01*
X682734Y1847623D01*
X683984Y1847530D01*
X684859Y1847157D01*
X685609Y1846690D01*
X686109Y1846130D01*
X686484Y1845383D01*
Y1843517D01*
G01Y1858517D02*
X678984D01*
Y1860383D01*
X679359Y1861130D01*
X679859Y1861690D01*
X680609Y1862157D01*
X681484Y1862530D01*
X682734Y1862623D01*
X683984Y1862530D01*
X684859Y1862157D01*
X685609Y1861690D01*
X686109Y1861130D01*
X686484Y1860383D01*
Y1858517D01*
G01Y1866203D02*
X678984D01*
Y1868537D01*
X679359Y1869283D01*
X679859Y1869750D01*
X680859Y1869937D01*
X681859Y1869750D01*
X682484Y1869190D01*
X682859Y1868537D01*
Y1866203D01*
G01Y1868537D02*
X686484Y1869937D01*
G01X678984Y1874450D02*
Y1876690D01*
G01Y1875570D02*
X686484D01*
G01Y1874450D02*
Y1876690D01*
G01X678984Y1881203D02*
X686484D01*
Y1884937D01*
G01X678984Y1888703D02*
X686484D01*
Y1892437D01*
G01X685484Y1903610D02*
X686109Y1904357D01*
X686484Y1905197D01*
Y1905943D01*
X686109Y1906690D01*
X685484Y1907250D01*
X684609Y1907530D01*
X683734Y1907343D01*
X682984Y1906877D01*
X682484Y1906037D01*
X682234Y1904917D01*
X681734Y1904263D01*
X680859Y1903983D01*
X679984Y1904170D01*
X679359Y1904637D01*
X678984Y1905290D01*
Y1905943D01*
X679234Y1906597D01*
X679859Y1907157D01*
G01X678984Y1911950D02*
Y1914190D01*
G01Y1913070D02*
X686484D01*
G01Y1911950D02*
Y1914190D01*
G01X678984Y1918797D02*
Y1922343D01*
X686484Y1918797D01*
Y1922343D01*
G01Y1929937D02*
Y1926203D01*
X678984D01*
Y1929937D01*
G01X682609Y1928443D02*
Y1926203D01*
G01X686484Y1941297D02*
X678984D01*
Y1944843D01*
G01X682609Y1943537D02*
Y1941297D01*
G01X686484Y1950570D02*
X686359Y1949823D01*
X685859Y1949170D01*
X685109Y1948610D01*
X684234Y1948237D01*
X683234Y1948050D01*
X682234D01*
X681234Y1948237D01*
X680359Y1948610D01*
X679609Y1949170D01*
X679109Y1949823D01*
X678984Y1950570D01*
X679109Y1951317D01*
X679609Y1951970D01*
X680359Y1952530D01*
X681234Y1952903D01*
X682234Y1953090D01*
X683234D01*
X684234Y1952903D01*
X685109Y1952530D01*
X685859Y1951970D01*
X686359Y1951317D01*
X686484Y1950570D01*
G01Y1956203D02*
X678984D01*
Y1958537D01*
X679359Y1959283D01*
X679859Y1959750D01*
X680859Y1959937D01*
X681859Y1959750D01*
X682484Y1959190D01*
X682859Y1958537D01*
Y1956203D01*
G01Y1958537D02*
X686484Y1959937D01*
G01X678984Y1973070D02*
X679234Y1972323D01*
X679859Y1971763D01*
X680609Y1971390D01*
X681609Y1971110D01*
X682734Y1971017D01*
X683859Y1971110D01*
X684859Y1971390D01*
X685609Y1971763D01*
X686234Y1972323D01*
X686484Y1973070D01*
X686234Y1973817D01*
X685609Y1974377D01*
X684859Y1974750D01*
X683859Y1975030D01*
X682734Y1975123D01*
X681609Y1975030D01*
X680609Y1974750D01*
X679859Y1974377D01*
X679234Y1973817D01*
X678984Y1973070D01*
G01X686734Y1980570D02*
X686609Y1980383D01*
X686359D01*
X686234Y1980570D01*
X686359Y1980757D01*
X686609D01*
X686734Y1980570D01*
G01X684984Y1986017D02*
X685859Y1986577D01*
X686359Y1987323D01*
X686484Y1988163D01*
X686359Y1988910D01*
X685734Y1989657D01*
X684984Y1990123D01*
X684234Y1990217D01*
X683359Y1990030D01*
X682734Y1989377D01*
X682484Y1988723D01*
Y1987883D01*
G01Y1988723D02*
X682109Y1989283D01*
X681484Y1989750D01*
X680734Y1989937D01*
X679984Y1989750D01*
X679359Y1989283D01*
X678984Y1988443D01*
X679109Y1987603D01*
X679609Y1986763D01*
G01X686484Y1995570D02*
X678984D01*
X680484Y1994450D01*
G01X686484D02*
Y1996690D01*
G01Y2000643D02*
X678984D01*
X685234Y2003070D01*
X678984Y2005497D01*
X686484D01*
G01Y2008143D02*
X678984D01*
X685234Y2010570D01*
X678984Y2012997D01*
X686484D01*
G01Y2023797D02*
X678984D01*
Y2027343D01*
G01X682609Y2026037D02*
Y2023797D01*
G01X678984Y2031950D02*
Y2034190D01*
G01Y2033070D02*
X686484D01*
G01Y2031950D02*
Y2034190D01*
G01Y2038423D02*
X678984D01*
X686484Y2042717D01*
X678984D01*
G01Y2046950D02*
Y2049190D01*
G01Y2048070D02*
X686484D01*
G01Y2046950D02*
Y2049190D01*
G01X685484Y2053610D02*
X686109Y2054357D01*
X686484Y2055197D01*
Y2055943D01*
X686109Y2056690D01*
X685484Y2057250D01*
X684609Y2057530D01*
X683734Y2057343D01*
X682984Y2056877D01*
X682484Y2056037D01*
X682234Y2054917D01*
X681734Y2054263D01*
X680859Y2053983D01*
X679984Y2054170D01*
X679359Y2054637D01*
X678984Y2055290D01*
Y2055943D01*
X679234Y2056597D01*
X679859Y2057157D01*
G01X686484Y2061110D02*
X678984D01*
G01Y2065030D02*
X686484D01*
G01X682734D02*
Y2061110D01*
G01X686484Y2072437D02*
Y2068703D01*
X678984D01*
Y2072437D01*
G01X682609Y2070943D02*
Y2068703D01*
G01X686484Y2076017D02*
X678984D01*
Y2077883D01*
X679359Y2078630D01*
X679859Y2079190D01*
X680609Y2079657D01*
X681484Y2080030D01*
X682734Y2080123D01*
X683984Y2080030D01*
X684859Y2079657D01*
X685609Y2079190D01*
X686109Y2078630D01*
X686484Y2077883D01*
Y2076017D01*
G01Y2091203D02*
X678984D01*
Y2093443D01*
X679359Y2094190D01*
X680234Y2094750D01*
X681234Y2094937D01*
X682234Y2094750D01*
X682984Y2094283D01*
X683359Y2093443D01*
Y2091203D01*
G01X678984Y2100570D02*
X686484D01*
G01X678984Y2098423D02*
Y2102717D01*
G01X686484Y2106110D02*
X678984D01*
G01Y2110030D02*
X686484D01*
G01X682734D02*
Y2106110D01*
G01X678984Y2121950D02*
Y2124190D01*
G01Y2123070D02*
X686484D01*
G01Y2121950D02*
Y2124190D01*
G01X685484Y2128610D02*
X686109Y2129357D01*
X686484Y2130197D01*
Y2130943D01*
X686109Y2131690D01*
X685484Y2132250D01*
X684609Y2132530D01*
X683734Y2132343D01*
X682984Y2131877D01*
X682484Y2131037D01*
X682234Y2129917D01*
X681734Y2129263D01*
X680859Y2128983D01*
X679984Y2129170D01*
X679359Y2129637D01*
X678984Y2130290D01*
Y2130943D01*
X679234Y2131597D01*
X679859Y2132157D01*
G01X678984Y2145570D02*
X679234Y2144823D01*
X679859Y2144263D01*
X680609Y2143890D01*
X681609Y2143610D01*
X682734Y2143517D01*
X683859Y2143610D01*
X684859Y2143890D01*
X685609Y2144263D01*
X686234Y2144823D01*
X686484Y2145570D01*
X686234Y2146317D01*
X685609Y2146877D01*
X684859Y2147250D01*
X683859Y2147530D01*
X682734Y2147623D01*
X681609Y2147530D01*
X680609Y2147250D01*
X679859Y2146877D01*
X679234Y2146317D01*
X678984Y2145570D01*
G01X686734Y2153070D02*
X686609Y2152883D01*
X686359D01*
X686234Y2153070D01*
X686359Y2153257D01*
X686609D01*
X686734Y2153070D01*
G01X686484Y2161690D02*
X678984D01*
X684359Y2158237D01*
Y2162903D01*
G01X686484Y2165643D02*
X678984D01*
X685234Y2168070D01*
X678984Y2170497D01*
X686484D01*
G01Y2173143D02*
X678984D01*
X685234Y2175570D01*
X678984Y2177997D01*
X686484D01*
G01Y2188143D02*
X678984D01*
X685234Y2190570D01*
X678984Y2192997D01*
X686484D01*
G01Y2199937D02*
Y2196203D01*
X678984D01*
Y2199937D01*
G01X682609Y2198443D02*
Y2196203D01*
G01X678984Y2205570D02*
X686484D01*
G01X678984Y2203423D02*
Y2207717D01*
G01X686484Y2211203D02*
X678984D01*
Y2213537D01*
X679359Y2214283D01*
X679859Y2214750D01*
X680859Y2214937D01*
X681859Y2214750D01*
X682484Y2214190D01*
X682859Y2213537D01*
Y2211203D01*
G01Y2213537D02*
X686484Y2214937D01*
G01X678984Y2219450D02*
Y2221690D01*
G01Y2220570D02*
X686484D01*
G01Y2219450D02*
Y2221690D01*
G01X679609Y2230123D02*
X679234Y2229563D01*
X678984Y2228910D01*
Y2228163D01*
X679359Y2227323D01*
X679984Y2226670D01*
X680734Y2226203D01*
X681984Y2225830D01*
X683109Y2225737D01*
X684234Y2225923D01*
X684984Y2226203D01*
X685734Y2226763D01*
X686234Y2227417D01*
X686484Y2228070D01*
Y2228723D01*
X686234Y2229377D01*
X685859Y2229937D01*
X685359Y2230403D01*
G01X686484Y2241017D02*
X678984D01*
Y2242883D01*
X679359Y2243630D01*
X679859Y2244190D01*
X680609Y2244657D01*
X681484Y2245030D01*
X682734Y2245123D01*
X683984Y2245030D01*
X684859Y2244657D01*
X685609Y2244190D01*
X686109Y2243630D01*
X686484Y2242883D01*
Y2241017D01*
G01Y2248703D02*
X678984D01*
Y2251037D01*
X679359Y2251783D01*
X679859Y2252250D01*
X680859Y2252437D01*
X681859Y2252250D01*
X682484Y2251690D01*
X682859Y2251037D01*
Y2248703D01*
G01Y2251037D02*
X686484Y2252437D01*
G01X678984Y2256950D02*
Y2259190D01*
G01Y2258070D02*
X686484D01*
G01Y2256950D02*
Y2259190D01*
G01X678984Y2263703D02*
X686484D01*
Y2267437D01*
G01X678984Y2271203D02*
X686484D01*
Y2274937D01*
G01X688984Y2280103D02*
X687734Y2279170D01*
X686484Y2278703D01*
X681484D01*
X680234Y2279170D01*
X678984Y2280103D01*
G01Y2288070D02*
X679234Y2287323D01*
X679859Y2286763D01*
X680609Y2286390D01*
X681609Y2286110D01*
X682734Y2286017D01*
X683859Y2286110D01*
X684859Y2286390D01*
X685609Y2286763D01*
X686234Y2287323D01*
X686484Y2288070D01*
X686234Y2288817D01*
X685609Y2289377D01*
X684859Y2289750D01*
X683859Y2290030D01*
X682734Y2290123D01*
X681609Y2290030D01*
X680609Y2289750D01*
X679859Y2289377D01*
X679234Y2288817D01*
X678984Y2288070D01*
G01X686734Y2295570D02*
X686609Y2295383D01*
X686359D01*
X686234Y2295570D01*
X686359Y2295757D01*
X686609D01*
X686734Y2295570D01*
G01X678984Y2303070D02*
X679234Y2302323D01*
X679859Y2301763D01*
X680609Y2301390D01*
X681609Y2301110D01*
X682734Y2301017D01*
X683859Y2301110D01*
X684859Y2301390D01*
X685609Y2301763D01*
X686234Y2302323D01*
X686484Y2303070D01*
X686234Y2303817D01*
X685609Y2304377D01*
X684859Y2304750D01*
X683859Y2305030D01*
X682734Y2305123D01*
X681609Y2305030D01*
X680609Y2304750D01*
X679859Y2304377D01*
X679234Y2303817D01*
X678984Y2303070D01*
G01X686484Y2310570D02*
X678984D01*
X680484Y2309450D01*
G01X686484D02*
Y2311690D01*
G01X685359Y2316017D02*
X685984Y2316577D01*
X686359Y2317230D01*
X686484Y2318070D01*
X686234Y2318910D01*
X685734Y2319563D01*
X684859Y2320030D01*
X683859Y2320123D01*
X682859Y2319937D01*
X682234Y2319470D01*
X681734Y2318817D01*
X681609Y2318163D01*
X681734Y2317510D01*
X682234Y2316670D01*
X678984Y2316950D01*
Y2319470D01*
G01X686484Y2325383D02*
X684859Y2325570D01*
X683484Y2325850D01*
X682234Y2326223D01*
X680859Y2326690D01*
X678984Y2327437D01*
Y2323703D01*
G01X680609Y2332230D02*
X678984Y2332697D01*
G01Y2333910D02*
X680609Y2333443D01*
G01X688984Y2341037D02*
X687734Y2341970D01*
X686484Y2342437D01*
X681484D01*
X680234Y2341970D01*
X678984Y2341037D01*
G01X701310Y1453504D02*
G03I-2452J0D01*
G01X692649Y1457835D02*
G03I-2452J0D01*
G01X701310Y1468859D02*
G03I-2452J0D01*
G01X692649Y1473189D02*
G03I-2452J0D01*
G01X701310Y1499567D02*
G03I-2452J0D01*
G01Y1484213D02*
G03I-2452J0D01*
G01X692649Y1488544D02*
G03I-2452J0D01*
G01X701310Y1514922D02*
G03I-2452J0D01*
G01X692649Y1503898D02*
G03I-2452J0D01*
G01Y1519252D02*
G03I-2452J0D01*
G01X701310Y1555867D02*
G03I-2452J0D01*
G01X692649Y1560197D02*
G03I-2452J0D01*
G01X701310Y1571221D02*
G03I-2452J0D01*
G01X692649Y1575552D02*
G03I-2452J0D01*
G01X701310Y1586575D02*
G03I-2452J0D01*
G01X692649Y1590906D02*
G03I-2452J0D01*
G01X701310Y1601930D02*
G03I-2452J0D01*
G01X692649Y1606260D02*
G03I-2452J0D01*
G01X701310Y1617284D02*
G03I-2452J0D01*
G01X692649Y1621615D02*
G03I-2452J0D01*
G01X702616Y1701901D02*
X695116D01*
X701366Y1704328D01*
X695116Y1706755D01*
X702616D01*
G01Y1709495D02*
X695116Y1711828D01*
X702616Y1714161D01*
G01X699991Y1713321D02*
Y1710335D01*
G01X702616Y1717461D02*
X695116D01*
Y1719795D01*
X695491Y1720541D01*
X695991Y1721008D01*
X696991Y1721195D01*
X697991Y1721008D01*
X698616Y1720448D01*
X698991Y1719795D01*
Y1717461D01*
G01Y1719795D02*
X702616Y1721195D01*
G01Y1724775D02*
X695116D01*
G01Y1728321D02*
X699741Y1724775D01*
G01X702616Y1728881D02*
X697616Y1726361D01*
G01X702866Y1734328D02*
X702741Y1734141D01*
X702491D01*
X702366Y1734328D01*
X702491Y1734515D01*
X702741D01*
X702866Y1734328D01*
G01X699491D02*
X699366Y1734141D01*
X699116D01*
X698991Y1734328D01*
X699116Y1734515D01*
X699366D01*
X699491Y1734328D01*
G01X702616Y1739961D02*
X695116D01*
Y1742295D01*
X695491Y1743041D01*
X695991Y1743508D01*
X696991Y1743695D01*
X697991Y1743508D01*
X698616Y1742948D01*
X698991Y1742295D01*
Y1739961D01*
G01Y1742295D02*
X702616Y1743695D01*
G01Y1751195D02*
Y1747461D01*
X695116D01*
Y1751195D01*
G01X698741Y1749701D02*
Y1747461D01*
G01X695741Y1758881D02*
X695366Y1758321D01*
X695116Y1757668D01*
Y1756921D01*
X695491Y1756081D01*
X696116Y1755428D01*
X696866Y1754961D01*
X698116Y1754588D01*
X699241Y1754495D01*
X700366Y1754681D01*
X701116Y1754961D01*
X701866Y1755521D01*
X702366Y1756175D01*
X702616Y1756828D01*
Y1757481D01*
X702366Y1758135D01*
X701991Y1758695D01*
X701491Y1759161D01*
G01X702616Y1764328D02*
X702491Y1763581D01*
X701991Y1762928D01*
X701241Y1762368D01*
X700366Y1761995D01*
X699366Y1761808D01*
X698366D01*
X697366Y1761995D01*
X696491Y1762368D01*
X695741Y1762928D01*
X695241Y1763581D01*
X695116Y1764328D01*
X695241Y1765075D01*
X695741Y1765728D01*
X696491Y1766288D01*
X697366Y1766661D01*
X698366Y1766848D01*
X699366D01*
X700366Y1766661D01*
X701241Y1766288D01*
X701991Y1765728D01*
X702491Y1765075D01*
X702616Y1764328D01*
G01Y1769401D02*
X695116D01*
X701366Y1771828D01*
X695116Y1774255D01*
X702616D01*
G01Y1776901D02*
X695116D01*
X701366Y1779328D01*
X695116Y1781755D01*
X702616D01*
G01Y1788695D02*
Y1784961D01*
X695116D01*
Y1788695D01*
G01X698741Y1787201D02*
Y1784961D01*
G01X702616Y1792181D02*
X695116D01*
X702616Y1796475D01*
X695116D01*
G01X702616Y1799775D02*
X695116D01*
Y1801641D01*
X695491Y1802388D01*
X695991Y1802948D01*
X696741Y1803415D01*
X697616Y1803788D01*
X698866Y1803881D01*
X700116Y1803788D01*
X700991Y1803415D01*
X701741Y1802948D01*
X702241Y1802388D01*
X702616Y1801641D01*
Y1799775D01*
G01Y1811195D02*
Y1807461D01*
X695116D01*
Y1811195D01*
G01X698741Y1809701D02*
Y1807461D01*
G01X702616Y1814775D02*
X695116D01*
Y1816641D01*
X695491Y1817388D01*
X695991Y1817948D01*
X696741Y1818415D01*
X697616Y1818788D01*
X698866Y1818881D01*
X700116Y1818788D01*
X700991Y1818415D01*
X701741Y1817948D01*
X702241Y1817388D01*
X702616Y1816641D01*
Y1814775D01*
G01Y1829775D02*
X695116D01*
Y1831641D01*
X695491Y1832388D01*
X695991Y1832948D01*
X696741Y1833415D01*
X697616Y1833788D01*
X698866Y1833881D01*
X700116Y1833788D01*
X700991Y1833415D01*
X701741Y1832948D01*
X702241Y1832388D01*
X702616Y1831641D01*
Y1829775D01*
G01Y1837461D02*
X695116D01*
Y1839795D01*
X695491Y1840541D01*
X695991Y1841008D01*
X696991Y1841195D01*
X697991Y1841008D01*
X698616Y1840448D01*
X698991Y1839795D01*
Y1837461D01*
G01Y1839795D02*
X702616Y1841195D01*
G01X695116Y1845708D02*
Y1847948D01*
G01Y1846828D02*
X702616D01*
G01Y1845708D02*
Y1847948D01*
G01X695116Y1852461D02*
X702616D01*
Y1856195D01*
G01X695116Y1859961D02*
X702616D01*
Y1863695D01*
G01X701616Y1874868D02*
X702241Y1875615D01*
X702616Y1876455D01*
Y1877201D01*
X702241Y1877948D01*
X701616Y1878508D01*
X700741Y1878788D01*
X699866Y1878601D01*
X699116Y1878135D01*
X698616Y1877295D01*
X698366Y1876175D01*
X697866Y1875521D01*
X696991Y1875241D01*
X696116Y1875428D01*
X695491Y1875895D01*
X695116Y1876548D01*
Y1877201D01*
X695366Y1877855D01*
X695991Y1878415D01*
G01X695116Y1883208D02*
Y1885448D01*
G01Y1884328D02*
X702616D01*
G01Y1883208D02*
Y1885448D01*
G01X695116Y1890055D02*
Y1893601D01*
X702616Y1890055D01*
Y1893601D01*
G01Y1901195D02*
Y1897461D01*
X695116D01*
Y1901195D01*
G01X698741Y1899701D02*
Y1897461D01*
G01X702616Y1912555D02*
X695116D01*
Y1916101D01*
G01X698741Y1914795D02*
Y1912555D01*
G01X702616Y1921828D02*
X702491Y1921081D01*
X701991Y1920428D01*
X701241Y1919868D01*
X700366Y1919495D01*
X699366Y1919308D01*
X698366D01*
X697366Y1919495D01*
X696491Y1919868D01*
X695741Y1920428D01*
X695241Y1921081D01*
X695116Y1921828D01*
X695241Y1922575D01*
X695741Y1923228D01*
X696491Y1923788D01*
X697366Y1924161D01*
X698366Y1924348D01*
X699366D01*
X700366Y1924161D01*
X701241Y1923788D01*
X701991Y1923228D01*
X702491Y1922575D01*
X702616Y1921828D01*
G01Y1927461D02*
X695116D01*
Y1929795D01*
X695491Y1930541D01*
X695991Y1931008D01*
X696991Y1931195D01*
X697991Y1931008D01*
X698616Y1930448D01*
X698991Y1929795D01*
Y1927461D01*
G01Y1929795D02*
X702616Y1931195D01*
G01X695116Y1944328D02*
X695366Y1943581D01*
X695991Y1943021D01*
X696741Y1942648D01*
X697741Y1942368D01*
X698866Y1942275D01*
X699991Y1942368D01*
X700991Y1942648D01*
X701741Y1943021D01*
X702366Y1943581D01*
X702616Y1944328D01*
X702366Y1945075D01*
X701741Y1945635D01*
X700991Y1946008D01*
X699991Y1946288D01*
X698866Y1946381D01*
X697741Y1946288D01*
X696741Y1946008D01*
X695991Y1945635D01*
X695366Y1945075D01*
X695116Y1944328D01*
G01X702866Y1951828D02*
X702741Y1951641D01*
X702491D01*
X702366Y1951828D01*
X702491Y1952015D01*
X702741D01*
X702866Y1951828D01*
G01X701491Y1957275D02*
X702116Y1957835D01*
X702491Y1958488D01*
X702616Y1959328D01*
X702366Y1960168D01*
X701866Y1960821D01*
X700991Y1961288D01*
X699991Y1961381D01*
X698991Y1961195D01*
X698366Y1960728D01*
X697866Y1960075D01*
X697741Y1959421D01*
X697866Y1958768D01*
X698366Y1957928D01*
X695116Y1958208D01*
Y1960728D01*
G01X702616Y1964401D02*
X695116D01*
X701366Y1966828D01*
X695116Y1969255D01*
X702616D01*
G01Y1971901D02*
X695116D01*
X701366Y1974328D01*
X695116Y1976755D01*
X702616D01*
G01Y1987555D02*
X695116D01*
Y1991101D01*
G01X698741Y1989795D02*
Y1987555D01*
G01X695116Y1995708D02*
Y1997948D01*
G01Y1996828D02*
X702616D01*
G01Y1995708D02*
Y1997948D01*
G01Y2002181D02*
X695116D01*
X702616Y2006475D01*
X695116D01*
G01Y2010708D02*
Y2012948D01*
G01Y2011828D02*
X702616D01*
G01Y2010708D02*
Y2012948D01*
G01X701616Y2017368D02*
X702241Y2018115D01*
X702616Y2018955D01*
Y2019701D01*
X702241Y2020448D01*
X701616Y2021008D01*
X700741Y2021288D01*
X699866Y2021101D01*
X699116Y2020635D01*
X698616Y2019795D01*
X698366Y2018675D01*
X697866Y2018021D01*
X696991Y2017741D01*
X696116Y2017928D01*
X695491Y2018395D01*
X695116Y2019048D01*
Y2019701D01*
X695366Y2020355D01*
X695991Y2020915D01*
G01X702616Y2024868D02*
X695116D01*
G01Y2028788D02*
X702616D01*
G01X698866D02*
Y2024868D01*
G01X702616Y2036195D02*
Y2032461D01*
X695116D01*
Y2036195D01*
G01X698741Y2034701D02*
Y2032461D01*
G01X702616Y2039775D02*
X695116D01*
Y2041641D01*
X695491Y2042388D01*
X695991Y2042948D01*
X696741Y2043415D01*
X697616Y2043788D01*
X698866Y2043881D01*
X700116Y2043788D01*
X700991Y2043415D01*
X701741Y2042948D01*
X702241Y2042388D01*
X702616Y2041641D01*
Y2039775D01*
G01Y2054961D02*
X695116D01*
Y2057201D01*
X695491Y2057948D01*
X696366Y2058508D01*
X697366Y2058695D01*
X698366Y2058508D01*
X699116Y2058041D01*
X699491Y2057201D01*
Y2054961D01*
G01X695116Y2064328D02*
X702616D01*
G01X695116Y2062181D02*
Y2066475D01*
G01X702616Y2069868D02*
X695116D01*
G01Y2073788D02*
X702616D01*
G01X698866D02*
Y2069868D01*
G01X695116Y2085708D02*
Y2087948D01*
G01Y2086828D02*
X702616D01*
G01Y2085708D02*
Y2087948D01*
G01X701616Y2092368D02*
X702241Y2093115D01*
X702616Y2093955D01*
Y2094701D01*
X702241Y2095448D01*
X701616Y2096008D01*
X700741Y2096288D01*
X699866Y2096101D01*
X699116Y2095635D01*
X698616Y2094795D01*
X698366Y2093675D01*
X697866Y2093021D01*
X696991Y2092741D01*
X696116Y2092928D01*
X695491Y2093395D01*
X695116Y2094048D01*
Y2094701D01*
X695366Y2095355D01*
X695991Y2095915D01*
G01X695116Y2109328D02*
X695366Y2108581D01*
X695991Y2108021D01*
X696741Y2107648D01*
X697741Y2107368D01*
X698866Y2107275D01*
X699991Y2107368D01*
X700991Y2107648D01*
X701741Y2108021D01*
X702366Y2108581D01*
X702616Y2109328D01*
X702366Y2110075D01*
X701741Y2110635D01*
X700991Y2111008D01*
X699991Y2111288D01*
X698866Y2111381D01*
X697741Y2111288D01*
X696741Y2111008D01*
X695991Y2110635D01*
X695366Y2110075D01*
X695116Y2109328D01*
G01X702866Y2116828D02*
X702741Y2116641D01*
X702491D01*
X702366Y2116828D01*
X702491Y2117015D01*
X702741D01*
X702866Y2116828D01*
G01X699491Y2122555D02*
X698616Y2123208D01*
X698116Y2123768D01*
X697866Y2124515D01*
X698116Y2125168D01*
X698616Y2125635D01*
X699366Y2126008D01*
X700241Y2126101D01*
X700991Y2126008D01*
X701741Y2125635D01*
X702366Y2125075D01*
X702616Y2124421D01*
X702366Y2123675D01*
X701616Y2123021D01*
X700491Y2122648D01*
X699241Y2122555D01*
X697616Y2122741D01*
X696741Y2123021D01*
X695866Y2123488D01*
X695241Y2124141D01*
X695116Y2124795D01*
X695366Y2125448D01*
X695991Y2125915D01*
G01X702616Y2129401D02*
X695116D01*
X701366Y2131828D01*
X695116Y2134255D01*
X702616D01*
G01Y2136901D02*
X695116D01*
X701366Y2139328D01*
X695116Y2141755D01*
X702616D01*
G01Y2151901D02*
X695116D01*
X701366Y2154328D01*
X695116Y2156755D01*
X702616D01*
G01Y2163695D02*
Y2159961D01*
X695116D01*
Y2163695D01*
G01X698741Y2162201D02*
Y2159961D01*
G01X695116Y2169328D02*
X702616D01*
G01X695116Y2167181D02*
Y2171475D01*
G01X702616Y2174961D02*
X695116D01*
Y2177295D01*
X695491Y2178041D01*
X695991Y2178508D01*
X696991Y2178695D01*
X697991Y2178508D01*
X698616Y2177948D01*
X698991Y2177295D01*
Y2174961D01*
G01Y2177295D02*
X702616Y2178695D01*
G01X695116Y2183208D02*
Y2185448D01*
G01Y2184328D02*
X702616D01*
G01Y2183208D02*
Y2185448D01*
G01X695741Y2193881D02*
X695366Y2193321D01*
X695116Y2192668D01*
Y2191921D01*
X695491Y2191081D01*
X696116Y2190428D01*
X696866Y2189961D01*
X698116Y2189588D01*
X699241Y2189495D01*
X700366Y2189681D01*
X701116Y2189961D01*
X701866Y2190521D01*
X702366Y2191175D01*
X702616Y2191828D01*
Y2192481D01*
X702366Y2193135D01*
X701991Y2193695D01*
X701491Y2194161D01*
G01X702616Y2204775D02*
X695116D01*
Y2206641D01*
X695491Y2207388D01*
X695991Y2207948D01*
X696741Y2208415D01*
X697616Y2208788D01*
X698866Y2208881D01*
X700116Y2208788D01*
X700991Y2208415D01*
X701741Y2207948D01*
X702241Y2207388D01*
X702616Y2206641D01*
Y2204775D01*
G01Y2212461D02*
X695116D01*
Y2214795D01*
X695491Y2215541D01*
X695991Y2216008D01*
X696991Y2216195D01*
X697991Y2216008D01*
X698616Y2215448D01*
X698991Y2214795D01*
Y2212461D01*
G01Y2214795D02*
X702616Y2216195D01*
G01X695116Y2220708D02*
Y2222948D01*
G01Y2221828D02*
X702616D01*
G01Y2220708D02*
Y2222948D01*
G01X695116Y2227461D02*
X702616D01*
Y2231195D01*
G01X695116Y2234961D02*
X702616D01*
Y2238695D01*
G01X705116Y2243861D02*
X703866Y2242928D01*
X702616Y2242461D01*
X697616D01*
X696366Y2242928D01*
X695116Y2243861D01*
G01Y2251828D02*
X695366Y2251081D01*
X695991Y2250521D01*
X696741Y2250148D01*
X697741Y2249868D01*
X698866Y2249775D01*
X699991Y2249868D01*
X700991Y2250148D01*
X701741Y2250521D01*
X702366Y2251081D01*
X702616Y2251828D01*
X702366Y2252575D01*
X701741Y2253135D01*
X700991Y2253508D01*
X699991Y2253788D01*
X698866Y2253881D01*
X697741Y2253788D01*
X696741Y2253508D01*
X695991Y2253135D01*
X695366Y2252575D01*
X695116Y2251828D01*
G01X702866Y2259328D02*
X702741Y2259141D01*
X702491D01*
X702366Y2259328D01*
X702491Y2259515D01*
X702741D01*
X702866Y2259328D01*
G01X695116Y2266828D02*
X695366Y2266081D01*
X695991Y2265521D01*
X696741Y2265148D01*
X697741Y2264868D01*
X698866Y2264775D01*
X699991Y2264868D01*
X700991Y2265148D01*
X701741Y2265521D01*
X702366Y2266081D01*
X702616Y2266828D01*
X702366Y2267575D01*
X701741Y2268135D01*
X700991Y2268508D01*
X699991Y2268788D01*
X698866Y2268881D01*
X697741Y2268788D01*
X696741Y2268508D01*
X695991Y2268135D01*
X695366Y2267575D01*
X695116Y2266828D01*
G01X696366Y2272555D02*
X695616Y2273115D01*
X695241Y2273768D01*
X695116Y2274515D01*
X695366Y2275448D01*
X695991Y2276101D01*
X696741Y2276288D01*
X697491Y2276195D01*
X698116Y2275821D01*
X699366Y2273955D01*
X700241Y2273115D01*
X701491Y2272555D01*
X702616Y2272368D01*
Y2276288D01*
G01X701116Y2279775D02*
X701991Y2280335D01*
X702491Y2281081D01*
X702616Y2281921D01*
X702491Y2282668D01*
X701866Y2283415D01*
X701116Y2283881D01*
X700366Y2283975D01*
X699491Y2283788D01*
X698866Y2283135D01*
X698616Y2282481D01*
Y2281641D01*
G01Y2282481D02*
X698241Y2283041D01*
X697616Y2283508D01*
X696866Y2283695D01*
X696116Y2283508D01*
X695491Y2283041D01*
X695116Y2282201D01*
X695241Y2281361D01*
X695741Y2280521D01*
G01X699491Y2287555D02*
X698616Y2288208D01*
X698116Y2288768D01*
X697866Y2289515D01*
X698116Y2290168D01*
X698616Y2290635D01*
X699366Y2291008D01*
X700241Y2291101D01*
X700991Y2291008D01*
X701741Y2290635D01*
X702366Y2290075D01*
X702616Y2289421D01*
X702366Y2288675D01*
X701616Y2288021D01*
X700491Y2287648D01*
X699241Y2287555D01*
X697616Y2287741D01*
X696741Y2288021D01*
X695866Y2288488D01*
X695241Y2289141D01*
X695116Y2289795D01*
X695366Y2290448D01*
X695991Y2290915D01*
G01X696741Y2295988D02*
X695116Y2296455D01*
G01Y2297668D02*
X696741Y2297201D01*
G01X705116Y2304795D02*
X703866Y2305728D01*
X702616Y2306195D01*
X697616D01*
X696366Y2305728D01*
X695116Y2304795D01*
G01X709972Y1457835D02*
G03I-2452J0D01*
G01Y1473189D02*
G03I-2452J0D01*
G01Y1488544D02*
G03I-2452J0D01*
G01Y1503898D02*
G03I-2452J0D01*
G01Y1519252D02*
G03I-2452J0D01*
G01X709971Y1560197D02*
G03I-2451J0D01*
G01X709972Y1575552D02*
G03I-2452J0D01*
G01Y1590906D02*
G03I-2452J0D01*
G01X709971Y1606260D02*
G03I-2451J0D01*
G01X709972Y1621615D02*
G03I-2452J0D01*
G01X757073Y1854242D02*
Y1866742D01*
X755213Y1864242D01*
G01Y1854242D02*
X758933D01*
G01X769473D02*
X770558Y1854450D01*
X771798Y1855075D01*
X772573Y1856117D01*
X772883Y1857575D01*
X772573Y1859033D01*
X771643Y1860284D01*
X770248Y1860909D01*
X768698D01*
X767768Y1861325D01*
X766993Y1862367D01*
X766683Y1863825D01*
X767148Y1865284D01*
X768233Y1866325D01*
X769473Y1866742D01*
X770713Y1866325D01*
X771798Y1865284D01*
X772263Y1863825D01*
X771953Y1862367D01*
X771178Y1861325D01*
X770248Y1860909D01*
X768698D01*
X767303Y1860284D01*
X766373Y1859033D01*
X766063Y1857575D01*
X766373Y1856117D01*
X767148Y1855075D01*
X768388Y1854450D01*
X769473Y1854242D01*
G01X783733D02*
Y1866742D01*
X777998Y1857784D01*
X785748D01*
G01X794273Y1866742D02*
X793033Y1866325D01*
X792103Y1865284D01*
X791483Y1864034D01*
X791018Y1862367D01*
X790863Y1860492D01*
X791018Y1858617D01*
X791483Y1856950D01*
X792103Y1855700D01*
X793033Y1854659D01*
X794273Y1854242D01*
X795513Y1854659D01*
X796443Y1855700D01*
X797063Y1856950D01*
X797528Y1858617D01*
X797683Y1860492D01*
X797528Y1862367D01*
X797063Y1864034D01*
X796443Y1865284D01*
X795513Y1866325D01*
X794273Y1866742D01*
G01X804038Y1855700D02*
X805123Y1854659D01*
X806363Y1854242D01*
X807603Y1854659D01*
X808688Y1855908D01*
X809463Y1857784D01*
X809773Y1859659D01*
Y1861950D01*
X809463Y1863825D01*
X808688Y1865492D01*
X807758Y1866325D01*
X806673Y1866742D01*
X805433Y1866325D01*
X804503Y1865492D01*
X803883Y1864242D01*
X803573Y1862575D01*
X803883Y1861117D01*
X804658Y1859659D01*
X805588Y1858825D01*
X806673Y1858617D01*
X807913Y1859033D01*
X808843Y1860075D01*
X809773Y1861950D01*
G01X819073Y1853825D02*
X818763Y1854034D01*
Y1854450D01*
X819073Y1854659D01*
X819383Y1854450D01*
Y1854034D01*
X819073Y1853825D01*
G01X833333Y1854242D02*
Y1866742D01*
X827598Y1857784D01*
X835348D01*
G01X840463Y1856117D02*
X841393Y1855075D01*
X842478Y1854450D01*
X843873Y1854242D01*
X845268Y1854659D01*
X846353Y1855492D01*
X847128Y1856950D01*
X847283Y1858617D01*
X846973Y1860284D01*
X846198Y1861325D01*
X845113Y1862159D01*
X844028Y1862367D01*
X842943Y1862159D01*
X841548Y1861325D01*
X842013Y1866742D01*
X846198D01*
G01X777683Y1829242D02*
Y1841742D01*
X771948Y1832784D01*
X779698D01*
G01X785278Y1834450D02*
X786363Y1835909D01*
X787293Y1836742D01*
X788533Y1837159D01*
X789618Y1836742D01*
X790393Y1835909D01*
X791013Y1834659D01*
X791168Y1833200D01*
X791013Y1831950D01*
X790393Y1830700D01*
X789463Y1829659D01*
X788378Y1829242D01*
X787138Y1829659D01*
X786053Y1830908D01*
X785433Y1832784D01*
X785278Y1834867D01*
X785588Y1837575D01*
X786053Y1839034D01*
X786828Y1840492D01*
X787913Y1841534D01*
X788998Y1841742D01*
X790083Y1841325D01*
X790858Y1840284D01*
G01X800313Y1829242D02*
X800623Y1831950D01*
X801088Y1834242D01*
X801708Y1836325D01*
X802483Y1838617D01*
X803723Y1841742D01*
X797523D01*
G01X813023Y1828825D02*
X812713Y1829034D01*
Y1829450D01*
X813023Y1829659D01*
X813333Y1829450D01*
Y1829034D01*
X813023Y1828825D01*
G01X822478Y1834450D02*
X823563Y1835909D01*
X824493Y1836742D01*
X825733Y1837159D01*
X826818Y1836742D01*
X827593Y1835909D01*
X828213Y1834659D01*
X828368Y1833200D01*
X828213Y1831950D01*
X827593Y1830700D01*
X826663Y1829659D01*
X825578Y1829242D01*
X824338Y1829659D01*
X823253Y1830908D01*
X822633Y1832784D01*
X822478Y1834867D01*
X822788Y1837575D01*
X823253Y1839034D01*
X824028Y1840492D01*
X825113Y1841534D01*
X826198Y1841742D01*
X827283Y1841325D01*
X828058Y1840284D01*
G01X811566Y-436528D02*
X811358Y-435443D01*
X810733Y-434203D01*
X809691Y-433428D01*
X808233Y-433118D01*
X806775Y-433428D01*
X805524Y-434358D01*
X804899Y-435753D01*
Y-437303D01*
X804483Y-438233D01*
X803441Y-439008D01*
X801983Y-439318D01*
X800524Y-438853D01*
X799483Y-437768D01*
X799066Y-436528D01*
X799483Y-435288D01*
X800524Y-434203D01*
X801983Y-433738D01*
X803441Y-434048D01*
X804483Y-434823D01*
X804899Y-435753D01*
Y-437303D01*
X805524Y-438698D01*
X806775Y-439628D01*
X808233Y-439938D01*
X809691Y-439628D01*
X810733Y-438853D01*
X811358Y-437613D01*
X811566Y-436528D01*
G01Y-424128D02*
X799066D01*
X801566Y-425988D01*
G01X811566D02*
Y-422268D01*
G01X799066Y-411728D02*
X799483Y-412968D01*
X800524Y-413898D01*
X801774Y-414518D01*
X803441Y-414983D01*
X805316Y-415138D01*
X807191Y-414983D01*
X808858Y-414518D01*
X810108Y-413898D01*
X811149Y-412968D01*
X811566Y-411728D01*
X811149Y-410488D01*
X810108Y-409558D01*
X808858Y-408938D01*
X807191Y-408473D01*
X805316Y-408318D01*
X803441Y-408473D01*
X801774Y-408938D01*
X800524Y-409558D01*
X799483Y-410488D01*
X799066Y-411728D01*
G01Y-399328D02*
X799483Y-400568D01*
X800524Y-401498D01*
X801774Y-402118D01*
X803441Y-402583D01*
X805316Y-402738D01*
X807191Y-402583D01*
X808858Y-402118D01*
X810108Y-401498D01*
X811149Y-400568D01*
X811566Y-399328D01*
X811149Y-398088D01*
X810108Y-397158D01*
X808858Y-396538D01*
X807191Y-396073D01*
X805316Y-395918D01*
X803441Y-396073D01*
X801774Y-396538D01*
X800524Y-397158D01*
X799483Y-398088D01*
X799066Y-399328D01*
G01X811983Y-386928D02*
X811774Y-387238D01*
X811358D01*
X811149Y-386928D01*
X811358Y-386618D01*
X811774D01*
X811983Y-386928D01*
G01X809066Y-377938D02*
X810525Y-377008D01*
X811358Y-375768D01*
X811566Y-374373D01*
X811358Y-373133D01*
X810316Y-371893D01*
X809066Y-371118D01*
X807816Y-370963D01*
X806358Y-371273D01*
X805316Y-372358D01*
X804899Y-373443D01*
Y-374838D01*
G01Y-373443D02*
X804274Y-372513D01*
X803233Y-371738D01*
X801983Y-371428D01*
X800733Y-371738D01*
X799691Y-372513D01*
X799066Y-373908D01*
X799274Y-375303D01*
X800108Y-376698D01*
G01X811566Y-362128D02*
X811358Y-361043D01*
X810733Y-359803D01*
X809691Y-359028D01*
X808233Y-358718D01*
X806775Y-359028D01*
X805524Y-359958D01*
X804899Y-361353D01*
Y-362903D01*
X804483Y-363833D01*
X803441Y-364608D01*
X801983Y-364918D01*
X800524Y-364453D01*
X799483Y-363368D01*
X799066Y-362128D01*
X799483Y-360888D01*
X800524Y-359803D01*
X801983Y-359338D01*
X803441Y-359648D01*
X804483Y-360423D01*
X804899Y-361353D01*
Y-362903D01*
X805524Y-364298D01*
X806775Y-365228D01*
X808233Y-365538D01*
X809691Y-365228D01*
X810733Y-364453D01*
X811358Y-363213D01*
X811566Y-362128D01*
G01X826329Y-430757D02*
X826121Y-429672D01*
X825496Y-428432D01*
X824454Y-427657D01*
X822996Y-427347D01*
X821538Y-427657D01*
X820287Y-428587D01*
X819662Y-429982D01*
Y-431532D01*
X819246Y-432462D01*
X818204Y-433237D01*
X816746Y-433547D01*
X815287Y-433082D01*
X814246Y-431997D01*
X813829Y-430757D01*
X814246Y-429517D01*
X815287Y-428432D01*
X816746Y-427967D01*
X818204Y-428277D01*
X819246Y-429052D01*
X819662Y-429982D01*
Y-431532D01*
X820287Y-432927D01*
X821538Y-433857D01*
X822996Y-434167D01*
X824454Y-433857D01*
X825496Y-433082D01*
X826121Y-431842D01*
X826329Y-430757D01*
G01X815912Y-421302D02*
X814663Y-420372D01*
X814037Y-419287D01*
X813829Y-418047D01*
X814246Y-416497D01*
X815287Y-415412D01*
X816537Y-415102D01*
X817788Y-415257D01*
X818829Y-415877D01*
X820912Y-418977D01*
X822371Y-420372D01*
X824454Y-421302D01*
X826329Y-421612D01*
Y-415102D01*
G01X813829Y-405957D02*
X814246Y-407197D01*
X815287Y-408127D01*
X816537Y-408747D01*
X818204Y-409212D01*
X820079Y-409367D01*
X821954Y-409212D01*
X823621Y-408747D01*
X824871Y-408127D01*
X825912Y-407197D01*
X826329Y-405957D01*
X825912Y-404717D01*
X824871Y-403787D01*
X823621Y-403167D01*
X821954Y-402702D01*
X820079Y-402547D01*
X818204Y-402702D01*
X816537Y-403167D01*
X815287Y-403787D01*
X814246Y-404717D01*
X813829Y-405957D01*
G01Y-393557D02*
X814246Y-394797D01*
X815287Y-395727D01*
X816537Y-396347D01*
X818204Y-396812D01*
X820079Y-396967D01*
X821954Y-396812D01*
X823621Y-396347D01*
X824871Y-395727D01*
X825912Y-394797D01*
X826329Y-393557D01*
X825912Y-392317D01*
X824871Y-391387D01*
X823621Y-390767D01*
X821954Y-390302D01*
X820079Y-390147D01*
X818204Y-390302D01*
X816537Y-390767D01*
X815287Y-391387D01*
X814246Y-392317D01*
X813829Y-393557D01*
G01X826746Y-381157D02*
X826537Y-381467D01*
X826121D01*
X825912Y-381157D01*
X826121Y-380847D01*
X826537D01*
X826746Y-381157D01*
G01X826329Y-369067D02*
X823621Y-368757D01*
X821329Y-368292D01*
X819246Y-367672D01*
X816954Y-366897D01*
X813829Y-365657D01*
Y-371857D01*
G01X824871Y-358992D02*
X825912Y-357907D01*
X826329Y-356667D01*
X825912Y-355427D01*
X824663Y-354342D01*
X822787Y-353567D01*
X820912Y-353257D01*
X818621D01*
X816746Y-353567D01*
X815079Y-354342D01*
X814246Y-355272D01*
X813829Y-356357D01*
X814246Y-357597D01*
X815079Y-358527D01*
X816329Y-359147D01*
X817996Y-359457D01*
X819454Y-359147D01*
X820912Y-358372D01*
X821746Y-357442D01*
X821954Y-356357D01*
X821538Y-355117D01*
X820496Y-354187D01*
X818621Y-353257D01*
G01X815912Y-324702D02*
X814663Y-323772D01*
X814037Y-322687D01*
X813829Y-321447D01*
X814246Y-319897D01*
X815287Y-318812D01*
X816537Y-318502D01*
X817788Y-318657D01*
X818829Y-319277D01*
X820912Y-322377D01*
X822371Y-323772D01*
X824454Y-324702D01*
X826329Y-325012D01*
Y-318502D01*
G01X813829Y-309357D02*
X814246Y-310597D01*
X815287Y-311527D01*
X816537Y-312147D01*
X818204Y-312612D01*
X820079Y-312767D01*
X821954Y-312612D01*
X823621Y-312147D01*
X824871Y-311527D01*
X825912Y-310597D01*
X826329Y-309357D01*
X825912Y-308117D01*
X824871Y-307187D01*
X823621Y-306567D01*
X821954Y-306102D01*
X820079Y-305947D01*
X818204Y-306102D01*
X816537Y-306567D01*
X815287Y-307187D01*
X814246Y-308117D01*
X813829Y-309357D01*
G01X826329Y-296957D02*
X826121Y-295872D01*
X825496Y-294632D01*
X824454Y-293857D01*
X822996Y-293547D01*
X821538Y-293857D01*
X820287Y-294787D01*
X819662Y-296182D01*
Y-297732D01*
X819246Y-298662D01*
X818204Y-299437D01*
X816746Y-299747D01*
X815287Y-299282D01*
X814246Y-298197D01*
X813829Y-296957D01*
X814246Y-295717D01*
X815287Y-294632D01*
X816746Y-294167D01*
X818204Y-294477D01*
X819246Y-295252D01*
X819662Y-296182D01*
Y-297732D01*
X820287Y-299127D01*
X821538Y-300057D01*
X822996Y-300367D01*
X824454Y-300057D01*
X825496Y-299282D01*
X826121Y-298042D01*
X826329Y-296957D01*
G01X826746Y-284557D02*
X826537Y-284867D01*
X826121D01*
X825912Y-284557D01*
X826121Y-284247D01*
X826537D01*
X826746Y-284557D01*
G01X823829Y-275567D02*
X825288Y-274637D01*
X826121Y-273397D01*
X826329Y-272002D01*
X826121Y-270762D01*
X825079Y-269522D01*
X823829Y-268747D01*
X822579Y-268592D01*
X821121Y-268902D01*
X820079Y-269987D01*
X819662Y-271072D01*
Y-272467D01*
G01Y-271072D02*
X819037Y-270142D01*
X817996Y-269367D01*
X816746Y-269057D01*
X815496Y-269367D01*
X814454Y-270142D01*
X813829Y-271537D01*
X814037Y-272932D01*
X814871Y-274327D01*
G01X801149Y-330473D02*
X799900Y-329543D01*
X799274Y-328458D01*
X799066Y-327218D01*
X799483Y-325668D01*
X800524Y-324583D01*
X801774Y-324273D01*
X803025Y-324428D01*
X804066Y-325048D01*
X806149Y-328148D01*
X807608Y-329543D01*
X809691Y-330473D01*
X811566Y-330783D01*
Y-324273D01*
G01X799066Y-315128D02*
X799483Y-316368D01*
X800524Y-317298D01*
X801774Y-317918D01*
X803441Y-318383D01*
X805316Y-318538D01*
X807191Y-318383D01*
X808858Y-317918D01*
X810108Y-317298D01*
X811149Y-316368D01*
X811566Y-315128D01*
X811149Y-313888D01*
X810108Y-312958D01*
X808858Y-312338D01*
X807191Y-311873D01*
X805316Y-311718D01*
X803441Y-311873D01*
X801774Y-312338D01*
X800524Y-312958D01*
X799483Y-313888D01*
X799066Y-315128D01*
G01X809691Y-306138D02*
X810733Y-305208D01*
X811358Y-304123D01*
X811566Y-302728D01*
X811149Y-301333D01*
X810316Y-300248D01*
X808858Y-299473D01*
X807191Y-299318D01*
X805524Y-299628D01*
X804483Y-300403D01*
X803649Y-301488D01*
X803441Y-302573D01*
X803649Y-303658D01*
X804483Y-305053D01*
X799066Y-304588D01*
Y-300403D01*
G01X811983Y-290328D02*
X811774Y-290638D01*
X811358D01*
X811149Y-290328D01*
X811358Y-290018D01*
X811774D01*
X811983Y-290328D01*
G01X811566Y-278238D02*
X808858Y-277928D01*
X806566Y-277463D01*
X804483Y-276843D01*
X802191Y-276068D01*
X799066Y-274828D01*
Y-281028D01*
G01X809691Y-268938D02*
X810733Y-268008D01*
X811358Y-266923D01*
X811566Y-265528D01*
X811149Y-264133D01*
X810316Y-263048D01*
X808858Y-262273D01*
X807191Y-262118D01*
X805524Y-262428D01*
X804483Y-263203D01*
X803649Y-264288D01*
X803441Y-265373D01*
X803649Y-266458D01*
X804483Y-267853D01*
X799066Y-267388D01*
Y-263203D01*
G01X999323Y1649320D02*
X991823D01*
Y1651654D01*
X992198Y1652400D01*
X992698Y1652867D01*
X993698Y1653054D01*
X994698Y1652867D01*
X995323Y1652307D01*
X995698Y1651654D01*
Y1649320D01*
G01Y1651654D02*
X999323Y1653054D01*
G01Y1660554D02*
Y1656820D01*
X991823D01*
Y1660554D01*
G01X995448Y1659060D02*
Y1656820D01*
G01X992448Y1668240D02*
X992073Y1667680D01*
X991823Y1667027D01*
Y1666280D01*
X992198Y1665440D01*
X992823Y1664787D01*
X993573Y1664320D01*
X994823Y1663947D01*
X995948Y1663854D01*
X997073Y1664040D01*
X997823Y1664320D01*
X998573Y1664880D01*
X999073Y1665534D01*
X999323Y1666187D01*
Y1666840D01*
X999073Y1667494D01*
X998698Y1668054D01*
X998198Y1668520D01*
G01X999323Y1673687D02*
X999198Y1672940D01*
X998698Y1672287D01*
X997948Y1671727D01*
X997073Y1671354D01*
X996073Y1671167D01*
X995073D01*
X994073Y1671354D01*
X993198Y1671727D01*
X992448Y1672287D01*
X991948Y1672940D01*
X991823Y1673687D01*
X991948Y1674434D01*
X992448Y1675087D01*
X993198Y1675647D01*
X994073Y1676020D01*
X995073Y1676207D01*
X996073D01*
X997073Y1676020D01*
X997948Y1675647D01*
X998698Y1675087D01*
X999198Y1674434D01*
X999323Y1673687D01*
G01Y1678760D02*
X991823D01*
X998073Y1681187D01*
X991823Y1683614D01*
X999323D01*
G01Y1686260D02*
X991823D01*
X998073Y1688687D01*
X991823Y1691114D01*
X999323D01*
G01Y1698054D02*
Y1694320D01*
X991823D01*
Y1698054D01*
G01X995448Y1696560D02*
Y1694320D01*
G01X999323Y1701540D02*
X991823D01*
X999323Y1705834D01*
X991823D01*
G01X999323Y1709134D02*
X991823D01*
Y1711000D01*
X992198Y1711747D01*
X992698Y1712307D01*
X993448Y1712774D01*
X994323Y1713147D01*
X995573Y1713240D01*
X996823Y1713147D01*
X997698Y1712774D01*
X998448Y1712307D01*
X998948Y1711747D01*
X999323Y1711000D01*
Y1709134D01*
G01Y1720554D02*
Y1716820D01*
X991823D01*
Y1720554D01*
G01X995448Y1719060D02*
Y1716820D01*
G01X999323Y1724134D02*
X991823D01*
Y1726000D01*
X992198Y1726747D01*
X992698Y1727307D01*
X993448Y1727774D01*
X994323Y1728147D01*
X995573Y1728240D01*
X996823Y1728147D01*
X997698Y1727774D01*
X998448Y1727307D01*
X998948Y1726747D01*
X999323Y1726000D01*
Y1724134D01*
G01Y1739134D02*
X991823D01*
Y1741000D01*
X992198Y1741747D01*
X992698Y1742307D01*
X993448Y1742774D01*
X994323Y1743147D01*
X995573Y1743240D01*
X996823Y1743147D01*
X997698Y1742774D01*
X998448Y1742307D01*
X998948Y1741747D01*
X999323Y1741000D01*
Y1739134D01*
G01Y1746820D02*
X991823D01*
Y1749154D01*
X992198Y1749900D01*
X992698Y1750367D01*
X993698Y1750554D01*
X994698Y1750367D01*
X995323Y1749807D01*
X995698Y1749154D01*
Y1746820D01*
G01Y1749154D02*
X999323Y1750554D01*
G01X991823Y1755067D02*
Y1757307D01*
G01Y1756187D02*
X999323D01*
G01Y1755067D02*
Y1757307D01*
G01X991823Y1761820D02*
X999323D01*
Y1765554D01*
G01X991823Y1769320D02*
X999323D01*
Y1773054D01*
G01X998323Y1784227D02*
X998948Y1784974D01*
X999323Y1785814D01*
Y1786560D01*
X998948Y1787307D01*
X998323Y1787867D01*
X997448Y1788147D01*
X996573Y1787960D01*
X995823Y1787494D01*
X995323Y1786654D01*
X995073Y1785534D01*
X994573Y1784880D01*
X993698Y1784600D01*
X992823Y1784787D01*
X992198Y1785254D01*
X991823Y1785907D01*
Y1786560D01*
X992073Y1787214D01*
X992698Y1787774D01*
G01X991823Y1792567D02*
Y1794807D01*
G01Y1793687D02*
X999323D01*
G01Y1792567D02*
Y1794807D01*
G01X991823Y1799414D02*
Y1802960D01*
X999323Y1799414D01*
Y1802960D01*
G01Y1810554D02*
Y1806820D01*
X991823D01*
Y1810554D01*
G01X995448Y1809060D02*
Y1806820D01*
G01X999323Y1821914D02*
X991823D01*
Y1825460D01*
G01X995448Y1824154D02*
Y1821914D01*
G01X999323Y1831187D02*
X999198Y1830440D01*
X998698Y1829787D01*
X997948Y1829227D01*
X997073Y1828854D01*
X996073Y1828667D01*
X995073D01*
X994073Y1828854D01*
X993198Y1829227D01*
X992448Y1829787D01*
X991948Y1830440D01*
X991823Y1831187D01*
X991948Y1831934D01*
X992448Y1832587D01*
X993198Y1833147D01*
X994073Y1833520D01*
X995073Y1833707D01*
X996073D01*
X997073Y1833520D01*
X997948Y1833147D01*
X998698Y1832587D01*
X999198Y1831934D01*
X999323Y1831187D01*
G01Y1836820D02*
X991823D01*
Y1839154D01*
X992198Y1839900D01*
X992698Y1840367D01*
X993698Y1840554D01*
X994698Y1840367D01*
X995323Y1839807D01*
X995698Y1839154D01*
Y1836820D01*
G01Y1839154D02*
X999323Y1840554D01*
G01Y1853687D02*
X991823D01*
X993323Y1852567D01*
G01X999323D02*
Y1854807D01*
G01X999573Y1861187D02*
X999448Y1861000D01*
X999198D01*
X999073Y1861187D01*
X999198Y1861374D01*
X999448D01*
X999573Y1861187D01*
G01X991823Y1868687D02*
X992073Y1867940D01*
X992698Y1867380D01*
X993448Y1867007D01*
X994448Y1866727D01*
X995573Y1866634D01*
X996698Y1866727D01*
X997698Y1867007D01*
X998448Y1867380D01*
X999073Y1867940D01*
X999323Y1868687D01*
X999073Y1869434D01*
X998448Y1869994D01*
X997698Y1870367D01*
X996698Y1870647D01*
X995573Y1870740D01*
X994448Y1870647D01*
X993448Y1870367D01*
X992698Y1869994D01*
X992073Y1869434D01*
X991823Y1868687D01*
G01X999323Y1876187D02*
X991823D01*
X993323Y1875067D01*
G01X999323D02*
Y1877307D01*
G01X996198Y1881914D02*
X995323Y1882567D01*
X994823Y1883127D01*
X994573Y1883874D01*
X994823Y1884527D01*
X995323Y1884994D01*
X996073Y1885367D01*
X996948Y1885460D01*
X997698Y1885367D01*
X998448Y1884994D01*
X999073Y1884434D01*
X999323Y1883780D01*
X999073Y1883034D01*
X998323Y1882380D01*
X997198Y1882007D01*
X995948Y1881914D01*
X994323Y1882100D01*
X993448Y1882380D01*
X992573Y1882847D01*
X991948Y1883500D01*
X991823Y1884154D01*
X992073Y1884807D01*
X992698Y1885274D01*
G01X999323Y1888760D02*
X991823D01*
X998073Y1891187D01*
X991823Y1893614D01*
X999323D01*
G01Y1896260D02*
X991823D01*
X998073Y1898687D01*
X991823Y1901114D01*
X999323D01*
G01Y1911914D02*
X991823D01*
Y1915460D01*
G01X995448Y1914154D02*
Y1911914D01*
G01X991823Y1920067D02*
Y1922307D01*
G01Y1921187D02*
X999323D01*
G01Y1920067D02*
Y1922307D01*
G01Y1926540D02*
X991823D01*
X999323Y1930834D01*
X991823D01*
G01Y1935067D02*
Y1937307D01*
G01Y1936187D02*
X999323D01*
G01Y1935067D02*
Y1937307D01*
G01X998323Y1941727D02*
X998948Y1942474D01*
X999323Y1943314D01*
Y1944060D01*
X998948Y1944807D01*
X998323Y1945367D01*
X997448Y1945647D01*
X996573Y1945460D01*
X995823Y1944994D01*
X995323Y1944154D01*
X995073Y1943034D01*
X994573Y1942380D01*
X993698Y1942100D01*
X992823Y1942287D01*
X992198Y1942754D01*
X991823Y1943407D01*
Y1944060D01*
X992073Y1944714D01*
X992698Y1945274D01*
G01X999323Y1949227D02*
X991823D01*
G01Y1953147D02*
X999323D01*
G01X995573D02*
Y1949227D01*
G01X999323Y1960554D02*
Y1956820D01*
X991823D01*
Y1960554D01*
G01X995448Y1959060D02*
Y1956820D01*
G01X999323Y1964134D02*
X991823D01*
Y1966000D01*
X992198Y1966747D01*
X992698Y1967307D01*
X993448Y1967774D01*
X994323Y1968147D01*
X995573Y1968240D01*
X996823Y1968147D01*
X997698Y1967774D01*
X998448Y1967307D01*
X998948Y1966747D01*
X999323Y1966000D01*
Y1964134D01*
G01Y1979320D02*
X991823D01*
Y1981560D01*
X992198Y1982307D01*
X993073Y1982867D01*
X994073Y1983054D01*
X995073Y1982867D01*
X995823Y1982400D01*
X996198Y1981560D01*
Y1979320D01*
G01X991823Y1988687D02*
X999323D01*
G01X991823Y1986540D02*
Y1990834D01*
G01X999323Y1994227D02*
X991823D01*
G01Y1998147D02*
X999323D01*
G01X995573D02*
Y1994227D01*
G01X991823Y2010067D02*
Y2012307D01*
G01Y2011187D02*
X999323D01*
G01Y2010067D02*
Y2012307D01*
G01X998323Y2016727D02*
X998948Y2017474D01*
X999323Y2018314D01*
Y2019060D01*
X998948Y2019807D01*
X998323Y2020367D01*
X997448Y2020647D01*
X996573Y2020460D01*
X995823Y2019994D01*
X995323Y2019154D01*
X995073Y2018034D01*
X994573Y2017380D01*
X993698Y2017100D01*
X992823Y2017287D01*
X992198Y2017754D01*
X991823Y2018407D01*
Y2019060D01*
X992073Y2019714D01*
X992698Y2020274D01*
G01X999323Y2033687D02*
X991823D01*
X993323Y2032567D01*
G01X999323D02*
Y2034807D01*
G01X999573Y2041187D02*
X999448Y2041000D01*
X999198D01*
X999073Y2041187D01*
X999198Y2041374D01*
X999448D01*
X999573Y2041187D01*
G01X999323Y2048687D02*
X991823D01*
X993323Y2047567D01*
G01X999323D02*
Y2049807D01*
G01X998198Y2054134D02*
X998823Y2054694D01*
X999198Y2055347D01*
X999323Y2056187D01*
X999073Y2057027D01*
X998573Y2057680D01*
X997698Y2058147D01*
X996698Y2058240D01*
X995698Y2058054D01*
X995073Y2057587D01*
X994573Y2056934D01*
X994448Y2056280D01*
X994573Y2055627D01*
X995073Y2054787D01*
X991823Y2055067D01*
Y2057587D01*
G01X999323Y2063687D02*
X991823D01*
X993323Y2062567D01*
G01X999323D02*
Y2064807D01*
G01X996823Y2070160D02*
Y2072400D01*
G01X995198Y2071187D02*
X998448D01*
G01X999573Y2077007D02*
X991823Y2080367D01*
G01X996823Y2084974D02*
Y2087400D01*
G01X991823Y2093687D02*
X992073Y2092940D01*
X992698Y2092380D01*
X993448Y2092007D01*
X994448Y2091727D01*
X995573Y2091634D01*
X996698Y2091727D01*
X997698Y2092007D01*
X998448Y2092380D01*
X999073Y2092940D01*
X999323Y2093687D01*
X999073Y2094434D01*
X998448Y2094994D01*
X997698Y2095367D01*
X996698Y2095647D01*
X995573Y2095740D01*
X994448Y2095647D01*
X993448Y2095367D01*
X992698Y2094994D01*
X992073Y2094434D01*
X991823Y2093687D01*
G01X999573Y2101187D02*
X999448Y2101000D01*
X999198D01*
X999073Y2101187D01*
X999198Y2101374D01*
X999448D01*
X999573Y2101187D01*
G01X991823Y2108687D02*
X992073Y2107940D01*
X992698Y2107380D01*
X993448Y2107007D01*
X994448Y2106727D01*
X995573Y2106634D01*
X996698Y2106727D01*
X997698Y2107007D01*
X998448Y2107380D01*
X999073Y2107940D01*
X999323Y2108687D01*
X999073Y2109434D01*
X998448Y2109994D01*
X997698Y2110367D01*
X996698Y2110647D01*
X995573Y2110740D01*
X994448Y2110647D01*
X993448Y2110367D01*
X992698Y2109994D01*
X992073Y2109434D01*
X991823Y2108687D01*
G01X993073Y2114414D02*
X992323Y2114974D01*
X991948Y2115627D01*
X991823Y2116374D01*
X992073Y2117307D01*
X992698Y2117960D01*
X993448Y2118147D01*
X994198Y2118054D01*
X994823Y2117680D01*
X996073Y2115814D01*
X996948Y2114974D01*
X998198Y2114414D01*
X999323Y2114227D01*
Y2118147D01*
G01X998198Y2121634D02*
X998823Y2122194D01*
X999198Y2122847D01*
X999323Y2123687D01*
X999073Y2124527D01*
X998573Y2125180D01*
X997698Y2125647D01*
X996698Y2125740D01*
X995698Y2125554D01*
X995073Y2125087D01*
X994573Y2124434D01*
X994448Y2123780D01*
X994573Y2123127D01*
X995073Y2122287D01*
X991823Y2122567D01*
Y2125087D01*
G01X999323Y2128760D02*
X991823D01*
X998073Y2131187D01*
X991823Y2133614D01*
X999323D01*
G01Y2136260D02*
X991823D01*
X998073Y2138687D01*
X991823Y2141114D01*
X999323D01*
G01X1027116Y-435741D02*
X1014616D01*
X1017116Y-437601D01*
G01X1027116D02*
Y-433881D01*
G01X1014616Y-423341D02*
X1015033Y-424581D01*
X1016074Y-425511D01*
X1017324Y-426131D01*
X1018991Y-426596D01*
X1020866Y-426751D01*
X1022741Y-426596D01*
X1024408Y-426131D01*
X1025658Y-425511D01*
X1026699Y-424581D01*
X1027116Y-423341D01*
X1026699Y-422101D01*
X1025658Y-421171D01*
X1024408Y-420551D01*
X1022741Y-420086D01*
X1020866Y-419931D01*
X1018991Y-420086D01*
X1017324Y-420551D01*
X1016074Y-421171D01*
X1015033Y-422101D01*
X1014616Y-423341D01*
G01X1016699Y-413886D02*
X1015450Y-412956D01*
X1014824Y-411871D01*
X1014616Y-410631D01*
X1015033Y-409081D01*
X1016074Y-407996D01*
X1017324Y-407686D01*
X1018575Y-407841D01*
X1019616Y-408461D01*
X1021699Y-411561D01*
X1023158Y-412956D01*
X1025241Y-413886D01*
X1027116Y-414196D01*
Y-407686D01*
G01X1014616Y-398541D02*
X1015033Y-399781D01*
X1016074Y-400711D01*
X1017324Y-401331D01*
X1018991Y-401796D01*
X1020866Y-401951D01*
X1022741Y-401796D01*
X1024408Y-401331D01*
X1025658Y-400711D01*
X1026699Y-399781D01*
X1027116Y-398541D01*
X1026699Y-397301D01*
X1025658Y-396371D01*
X1024408Y-395751D01*
X1022741Y-395286D01*
X1020866Y-395131D01*
X1018991Y-395286D01*
X1017324Y-395751D01*
X1016074Y-396371D01*
X1015033Y-397301D01*
X1014616Y-398541D01*
G01X1027116Y-386141D02*
X1026908Y-385056D01*
X1026283Y-383816D01*
X1025241Y-383041D01*
X1023783Y-382731D01*
X1022325Y-383041D01*
X1021074Y-383971D01*
X1020449Y-385366D01*
Y-386916D01*
X1020033Y-387846D01*
X1018991Y-388621D01*
X1017533Y-388931D01*
X1016074Y-388466D01*
X1015033Y-387381D01*
X1014616Y-386141D01*
X1015033Y-384901D01*
X1016074Y-383816D01*
X1017533Y-383351D01*
X1018991Y-383661D01*
X1020033Y-384436D01*
X1020449Y-385366D01*
Y-386916D01*
X1021074Y-388311D01*
X1022325Y-389241D01*
X1023783Y-389551D01*
X1025241Y-389241D01*
X1026283Y-388466D01*
X1026908Y-387226D01*
X1027116Y-386141D01*
G01X1027533Y-373741D02*
X1027324Y-374051D01*
X1026908D01*
X1026699Y-373741D01*
X1026908Y-373431D01*
X1027324D01*
X1027533Y-373741D01*
G01X1021908Y-364286D02*
X1020449Y-363201D01*
X1019616Y-362271D01*
X1019199Y-361031D01*
X1019616Y-359946D01*
X1020449Y-359171D01*
X1021699Y-358551D01*
X1023158Y-358396D01*
X1024408Y-358551D01*
X1025658Y-359171D01*
X1026699Y-360101D01*
X1027116Y-361186D01*
X1026699Y-362426D01*
X1025450Y-363511D01*
X1023574Y-364131D01*
X1021491Y-364286D01*
X1018783Y-363976D01*
X1017324Y-363511D01*
X1015866Y-362736D01*
X1014824Y-361651D01*
X1014616Y-360566D01*
X1015033Y-359481D01*
X1016074Y-358706D01*
G01X1021908Y-351886D02*
X1020449Y-350801D01*
X1019616Y-349871D01*
X1019199Y-348631D01*
X1019616Y-347546D01*
X1020449Y-346771D01*
X1021699Y-346151D01*
X1023158Y-345996D01*
X1024408Y-346151D01*
X1025658Y-346771D01*
X1026699Y-347701D01*
X1027116Y-348786D01*
X1026699Y-350026D01*
X1025450Y-351111D01*
X1023574Y-351731D01*
X1021491Y-351886D01*
X1018783Y-351576D01*
X1017324Y-351111D01*
X1015866Y-350336D01*
X1014824Y-349251D01*
X1014616Y-348166D01*
X1015033Y-347081D01*
X1016074Y-346306D01*
G01X1016699Y-317286D02*
X1015450Y-316356D01*
X1014824Y-315271D01*
X1014616Y-314031D01*
X1015033Y-312481D01*
X1016074Y-311396D01*
X1017324Y-311086D01*
X1018575Y-311241D01*
X1019616Y-311861D01*
X1021699Y-314961D01*
X1023158Y-316356D01*
X1025241Y-317286D01*
X1027116Y-317596D01*
Y-311086D01*
G01X1025241Y-305351D02*
X1026283Y-304421D01*
X1026908Y-303336D01*
X1027116Y-301941D01*
X1026699Y-300546D01*
X1025866Y-299461D01*
X1024408Y-298686D01*
X1022741Y-298531D01*
X1021074Y-298841D01*
X1020033Y-299616D01*
X1019199Y-300701D01*
X1018991Y-301786D01*
X1019199Y-302871D01*
X1020033Y-304266D01*
X1014616Y-303801D01*
Y-299616D01*
G01X1025658Y-292176D02*
X1026699Y-291091D01*
X1027116Y-289851D01*
X1026699Y-288611D01*
X1025450Y-287526D01*
X1023574Y-286751D01*
X1021699Y-286441D01*
X1019408D01*
X1017533Y-286751D01*
X1015866Y-287526D01*
X1015033Y-288456D01*
X1014616Y-289541D01*
X1015033Y-290781D01*
X1015866Y-291711D01*
X1017116Y-292331D01*
X1018783Y-292641D01*
X1020241Y-292331D01*
X1021699Y-291556D01*
X1022533Y-290626D01*
X1022741Y-289541D01*
X1022325Y-288301D01*
X1021283Y-287371D01*
X1019408Y-286441D01*
G01X1027533Y-277141D02*
X1027324Y-277451D01*
X1026908D01*
X1026699Y-277141D01*
X1026908Y-276831D01*
X1027324D01*
X1027533Y-277141D01*
G01X1024616Y-268151D02*
X1026075Y-267221D01*
X1026908Y-265981D01*
X1027116Y-264586D01*
X1026908Y-263346D01*
X1025866Y-262106D01*
X1024616Y-261331D01*
X1023366Y-261176D01*
X1021908Y-261486D01*
X1020866Y-262571D01*
X1020449Y-263656D01*
Y-265051D01*
G01Y-263656D02*
X1019824Y-262726D01*
X1018783Y-261951D01*
X1017533Y-261641D01*
X1016283Y-261951D01*
X1015241Y-262726D01*
X1014616Y-264121D01*
X1014824Y-265516D01*
X1015658Y-266911D01*
G01X1044764Y-446811D02*
X1032264D01*
X1034764Y-448671D01*
G01X1044764D02*
Y-444951D01*
G01X1032264Y-434411D02*
X1032681Y-435651D01*
X1033722Y-436581D01*
X1034972Y-437201D01*
X1036639Y-437666D01*
X1038514Y-437821D01*
X1040389Y-437666D01*
X1042056Y-437201D01*
X1043306Y-436581D01*
X1044347Y-435651D01*
X1044764Y-434411D01*
X1044347Y-433171D01*
X1043306Y-432241D01*
X1042056Y-431621D01*
X1040389Y-431156D01*
X1038514Y-431001D01*
X1036639Y-431156D01*
X1034972Y-431621D01*
X1033722Y-432241D01*
X1032681Y-433171D01*
X1032264Y-434411D01*
G01X1042264Y-425421D02*
X1043723Y-424491D01*
X1044556Y-423251D01*
X1044764Y-421856D01*
X1044556Y-420616D01*
X1043514Y-419376D01*
X1042264Y-418601D01*
X1041014Y-418446D01*
X1039556Y-418756D01*
X1038514Y-419841D01*
X1038097Y-420926D01*
Y-422321D01*
G01Y-420926D02*
X1037472Y-419996D01*
X1036431Y-419221D01*
X1035181Y-418911D01*
X1033931Y-419221D01*
X1032889Y-419996D01*
X1032264Y-421391D01*
X1032472Y-422786D01*
X1033306Y-424181D01*
G01X1032264Y-409611D02*
X1032681Y-410851D01*
X1033722Y-411781D01*
X1034972Y-412401D01*
X1036639Y-412866D01*
X1038514Y-413021D01*
X1040389Y-412866D01*
X1042056Y-412401D01*
X1043306Y-411781D01*
X1044347Y-410851D01*
X1044764Y-409611D01*
X1044347Y-408371D01*
X1043306Y-407441D01*
X1042056Y-406821D01*
X1040389Y-406356D01*
X1038514Y-406201D01*
X1036639Y-406356D01*
X1034972Y-406821D01*
X1033722Y-407441D01*
X1032681Y-408371D01*
X1032264Y-409611D01*
G01X1043306Y-399846D02*
X1044347Y-398761D01*
X1044764Y-397521D01*
X1044347Y-396281D01*
X1043098Y-395196D01*
X1041222Y-394421D01*
X1039347Y-394111D01*
X1037056D01*
X1035181Y-394421D01*
X1033514Y-395196D01*
X1032681Y-396126D01*
X1032264Y-397211D01*
X1032681Y-398451D01*
X1033514Y-399381D01*
X1034764Y-400001D01*
X1036431Y-400311D01*
X1037889Y-400001D01*
X1039347Y-399226D01*
X1040181Y-398296D01*
X1040389Y-397211D01*
X1039973Y-395971D01*
X1038931Y-395041D01*
X1037056Y-394111D01*
G01X1045181Y-384811D02*
X1044972Y-385121D01*
X1044556D01*
X1044347Y-384811D01*
X1044556Y-384501D01*
X1044972D01*
X1045181Y-384811D01*
G01X1032264Y-372411D02*
X1032681Y-373651D01*
X1033722Y-374581D01*
X1034972Y-375201D01*
X1036639Y-375666D01*
X1038514Y-375821D01*
X1040389Y-375666D01*
X1042056Y-375201D01*
X1043306Y-374581D01*
X1044347Y-373651D01*
X1044764Y-372411D01*
X1044347Y-371171D01*
X1043306Y-370241D01*
X1042056Y-369621D01*
X1040389Y-369156D01*
X1038514Y-369001D01*
X1036639Y-369156D01*
X1034972Y-369621D01*
X1033722Y-370241D01*
X1032681Y-371171D01*
X1032264Y-372411D01*
G01X1042889Y-363421D02*
X1043931Y-362491D01*
X1044556Y-361406D01*
X1044764Y-360011D01*
X1044347Y-358616D01*
X1043514Y-357531D01*
X1042056Y-356756D01*
X1040389Y-356601D01*
X1038722Y-356911D01*
X1037681Y-357686D01*
X1036847Y-358771D01*
X1036639Y-359856D01*
X1036847Y-360941D01*
X1037681Y-362336D01*
X1032264Y-361871D01*
Y-357686D01*
G01X1034347Y-328356D02*
X1033098Y-327426D01*
X1032472Y-326341D01*
X1032264Y-325101D01*
X1032681Y-323551D01*
X1033722Y-322466D01*
X1034972Y-322156D01*
X1036223Y-322311D01*
X1037264Y-322931D01*
X1039347Y-326031D01*
X1040806Y-327426D01*
X1042889Y-328356D01*
X1044764Y-328666D01*
Y-322156D01*
G01X1039556Y-315956D02*
X1038097Y-314871D01*
X1037264Y-313941D01*
X1036847Y-312701D01*
X1037264Y-311616D01*
X1038097Y-310841D01*
X1039347Y-310221D01*
X1040806Y-310066D01*
X1042056Y-310221D01*
X1043306Y-310841D01*
X1044347Y-311771D01*
X1044764Y-312856D01*
X1044347Y-314096D01*
X1043098Y-315181D01*
X1041222Y-315801D01*
X1039139Y-315956D01*
X1036431Y-315646D01*
X1034972Y-315181D01*
X1033514Y-314406D01*
X1032472Y-313321D01*
X1032264Y-312236D01*
X1032681Y-311151D01*
X1033722Y-310376D01*
G01X1044764Y-300611D02*
X1032264D01*
X1034764Y-302471D01*
G01X1044764D02*
Y-298751D01*
G01X1045181Y-288211D02*
X1044972Y-288521D01*
X1044556D01*
X1044347Y-288211D01*
X1044556Y-287901D01*
X1044972D01*
X1045181Y-288211D01*
G01X1044764Y-275811D02*
X1044556Y-274726D01*
X1043931Y-273486D01*
X1042889Y-272711D01*
X1041431Y-272401D01*
X1039973Y-272711D01*
X1038722Y-273641D01*
X1038097Y-275036D01*
Y-276586D01*
X1037681Y-277516D01*
X1036639Y-278291D01*
X1035181Y-278601D01*
X1033722Y-278136D01*
X1032681Y-277051D01*
X1032264Y-275811D01*
X1032681Y-274571D01*
X1033722Y-273486D01*
X1035181Y-273021D01*
X1036639Y-273331D01*
X1037681Y-274106D01*
X1038097Y-275036D01*
Y-276586D01*
X1038722Y-277981D01*
X1039973Y-278911D01*
X1041431Y-279221D01*
X1042889Y-278911D01*
X1043931Y-278136D01*
X1044556Y-276896D01*
X1044764Y-275811D01*
G01X1042889Y-266821D02*
X1043931Y-265891D01*
X1044556Y-264806D01*
X1044764Y-263411D01*
X1044347Y-262016D01*
X1043514Y-260931D01*
X1042056Y-260156D01*
X1040389Y-260001D01*
X1038722Y-260311D01*
X1037681Y-261086D01*
X1036847Y-262171D01*
X1036639Y-263256D01*
X1036847Y-264341D01*
X1037681Y-265736D01*
X1032264Y-265271D01*
Y-261086D01*
G01X1134301Y1453504D02*
G03I-2451J0D01*
G01X1142963Y1457835D02*
G03I-2452J0D01*
G01X1134302Y1468859D02*
G03I-2452J0D01*
G01X1142963Y1473189D02*
G03I-2452J0D01*
G01X1134302Y1484213D02*
G03I-2452J0D01*
G01X1142963Y1488544D02*
G03I-2452J0D01*
G01X1134301Y1499567D02*
G03I-2451J0D01*
G01X1142963Y1503898D02*
G03I-2452J0D01*
G01X1134302Y1514922D02*
G03I-2452J0D01*
G01X1142963Y1519252D02*
G03I-2452J0D01*
G01Y1560197D02*
G03I-2452J0D01*
G01X1134302Y1555867D02*
G03I-2452J0D01*
G01Y1571221D02*
G03I-2452J0D01*
G01X1142963Y1575552D02*
G03I-2452J0D01*
G01X1134302Y1586575D02*
G03I-2452J0D01*
G01X1142963Y1590906D02*
G03I-2452J0D01*
G01X1134302Y1601930D02*
G03I-2452J0D01*
G01X1142963Y1606260D02*
G03I-2452J0D01*
G01X1134302Y1617284D02*
G03I-2452J0D01*
G01X1142963Y1621615D02*
G03I-2452J0D01*
G01X1136403Y1704236D02*
X1128903D01*
X1136403Y1708530D01*
X1128903D01*
G01X1136403Y1713883D02*
X1136278Y1713136D01*
X1135778Y1712483D01*
X1135028Y1711923D01*
X1134153Y1711550D01*
X1133153Y1711363D01*
X1132153D01*
X1131153Y1711550D01*
X1130278Y1711923D01*
X1129528Y1712483D01*
X1129028Y1713136D01*
X1128903Y1713883D01*
X1129028Y1714630D01*
X1129528Y1715283D01*
X1130278Y1715843D01*
X1131153Y1716216D01*
X1132153Y1716403D01*
X1133153D01*
X1134153Y1716216D01*
X1135028Y1715843D01*
X1135778Y1715283D01*
X1136278Y1714630D01*
X1136403Y1713883D01*
G01Y1719236D02*
X1128903D01*
X1136403Y1723530D01*
X1128903D01*
G01X1133903Y1727670D02*
Y1730096D01*
G01X1136403Y1733956D02*
X1128903D01*
X1135153Y1736383D01*
X1128903Y1738810D01*
X1136403D01*
G01Y1741550D02*
X1128903Y1743883D01*
X1136403Y1746216D01*
G01X1133778Y1745376D02*
Y1742390D01*
G01X1136403Y1749516D02*
X1128903D01*
Y1751850D01*
X1129278Y1752596D01*
X1129778Y1753063D01*
X1130778Y1753250D01*
X1131778Y1753063D01*
X1132403Y1752503D01*
X1132778Y1751850D01*
Y1749516D01*
G01Y1751850D02*
X1136403Y1753250D01*
G01Y1756830D02*
X1128903D01*
G01Y1760376D02*
X1133528Y1756830D01*
G01X1136403Y1760936D02*
X1131403Y1758416D01*
G01X1136653Y1766383D02*
X1136528Y1766196D01*
X1136278D01*
X1136153Y1766383D01*
X1136278Y1766570D01*
X1136528D01*
X1136653Y1766383D01*
G01X1133278D02*
X1133153Y1766196D01*
X1132903D01*
X1132778Y1766383D01*
X1132903Y1766570D01*
X1133153D01*
X1133278Y1766383D01*
G01X1136403Y1772016D02*
X1128903D01*
Y1774350D01*
X1129278Y1775096D01*
X1129778Y1775563D01*
X1130778Y1775750D01*
X1131778Y1775563D01*
X1132403Y1775003D01*
X1132778Y1774350D01*
Y1772016D01*
G01Y1774350D02*
X1136403Y1775750D01*
G01Y1783250D02*
Y1779516D01*
X1128903D01*
Y1783250D01*
G01X1132528Y1781756D02*
Y1779516D01*
G01X1129528Y1790936D02*
X1129153Y1790376D01*
X1128903Y1789723D01*
Y1788976D01*
X1129278Y1788136D01*
X1129903Y1787483D01*
X1130653Y1787016D01*
X1131903Y1786643D01*
X1133028Y1786550D01*
X1134153Y1786736D01*
X1134903Y1787016D01*
X1135653Y1787576D01*
X1136153Y1788230D01*
X1136403Y1788883D01*
Y1789536D01*
X1136153Y1790190D01*
X1135778Y1790750D01*
X1135278Y1791216D01*
G01X1136403Y1796383D02*
X1136278Y1795636D01*
X1135778Y1794983D01*
X1135028Y1794423D01*
X1134153Y1794050D01*
X1133153Y1793863D01*
X1132153D01*
X1131153Y1794050D01*
X1130278Y1794423D01*
X1129528Y1794983D01*
X1129028Y1795636D01*
X1128903Y1796383D01*
X1129028Y1797130D01*
X1129528Y1797783D01*
X1130278Y1798343D01*
X1131153Y1798716D01*
X1132153Y1798903D01*
X1133153D01*
X1134153Y1798716D01*
X1135028Y1798343D01*
X1135778Y1797783D01*
X1136278Y1797130D01*
X1136403Y1796383D01*
G01Y1801456D02*
X1128903D01*
X1135153Y1803883D01*
X1128903Y1806310D01*
X1136403D01*
G01Y1808956D02*
X1128903D01*
X1135153Y1811383D01*
X1128903Y1813810D01*
X1136403D01*
G01Y1820750D02*
Y1817016D01*
X1128903D01*
Y1820750D01*
G01X1132528Y1819256D02*
Y1817016D01*
G01X1136403Y1824236D02*
X1128903D01*
X1136403Y1828530D01*
X1128903D01*
G01X1136403Y1831830D02*
X1128903D01*
Y1833696D01*
X1129278Y1834443D01*
X1129778Y1835003D01*
X1130528Y1835470D01*
X1131403Y1835843D01*
X1132653Y1835936D01*
X1133903Y1835843D01*
X1134778Y1835470D01*
X1135528Y1835003D01*
X1136028Y1834443D01*
X1136403Y1833696D01*
Y1831830D01*
G01Y1843250D02*
Y1839516D01*
X1128903D01*
Y1843250D01*
G01X1132528Y1841756D02*
Y1839516D01*
G01X1136403Y1846830D02*
X1128903D01*
Y1848696D01*
X1129278Y1849443D01*
X1129778Y1850003D01*
X1130528Y1850470D01*
X1131403Y1850843D01*
X1132653Y1850936D01*
X1133903Y1850843D01*
X1134778Y1850470D01*
X1135528Y1850003D01*
X1136028Y1849443D01*
X1136403Y1848696D01*
Y1846830D01*
G01Y1861830D02*
X1128903D01*
Y1863696D01*
X1129278Y1864443D01*
X1129778Y1865003D01*
X1130528Y1865470D01*
X1131403Y1865843D01*
X1132653Y1865936D01*
X1133903Y1865843D01*
X1134778Y1865470D01*
X1135528Y1865003D01*
X1136028Y1864443D01*
X1136403Y1863696D01*
Y1861830D01*
G01Y1869516D02*
X1128903D01*
Y1871850D01*
X1129278Y1872596D01*
X1129778Y1873063D01*
X1130778Y1873250D01*
X1131778Y1873063D01*
X1132403Y1872503D01*
X1132778Y1871850D01*
Y1869516D01*
G01Y1871850D02*
X1136403Y1873250D01*
G01X1128903Y1877763D02*
Y1880003D01*
G01Y1878883D02*
X1136403D01*
G01Y1877763D02*
Y1880003D01*
G01X1128903Y1884516D02*
X1136403D01*
Y1888250D01*
G01X1128903Y1892016D02*
X1136403D01*
Y1895750D01*
G01X1135403Y1906923D02*
X1136028Y1907670D01*
X1136403Y1908510D01*
Y1909256D01*
X1136028Y1910003D01*
X1135403Y1910563D01*
X1134528Y1910843D01*
X1133653Y1910656D01*
X1132903Y1910190D01*
X1132403Y1909350D01*
X1132153Y1908230D01*
X1131653Y1907576D01*
X1130778Y1907296D01*
X1129903Y1907483D01*
X1129278Y1907950D01*
X1128903Y1908603D01*
Y1909256D01*
X1129153Y1909910D01*
X1129778Y1910470D01*
G01X1128903Y1915263D02*
Y1917503D01*
G01Y1916383D02*
X1136403D01*
G01Y1915263D02*
Y1917503D01*
G01X1128903Y1922110D02*
Y1925656D01*
X1136403Y1922110D01*
Y1925656D01*
G01Y1933250D02*
Y1929516D01*
X1128903D01*
Y1933250D01*
G01X1132528Y1931756D02*
Y1929516D01*
G01X1136403Y1944610D02*
X1128903D01*
Y1948156D01*
G01X1132528Y1946850D02*
Y1944610D01*
G01X1136403Y1953883D02*
X1136278Y1953136D01*
X1135778Y1952483D01*
X1135028Y1951923D01*
X1134153Y1951550D01*
X1133153Y1951363D01*
X1132153D01*
X1131153Y1951550D01*
X1130278Y1951923D01*
X1129528Y1952483D01*
X1129028Y1953136D01*
X1128903Y1953883D01*
X1129028Y1954630D01*
X1129528Y1955283D01*
X1130278Y1955843D01*
X1131153Y1956216D01*
X1132153Y1956403D01*
X1133153D01*
X1134153Y1956216D01*
X1135028Y1955843D01*
X1135778Y1955283D01*
X1136278Y1954630D01*
X1136403Y1953883D01*
G01Y1959516D02*
X1128903D01*
Y1961850D01*
X1129278Y1962596D01*
X1129778Y1963063D01*
X1130778Y1963250D01*
X1131778Y1963063D01*
X1132403Y1962503D01*
X1132778Y1961850D01*
Y1959516D01*
G01Y1961850D02*
X1136403Y1963250D01*
G01X1128903Y1976383D02*
X1129153Y1975636D01*
X1129778Y1975076D01*
X1130528Y1974703D01*
X1131528Y1974423D01*
X1132653Y1974330D01*
X1133778Y1974423D01*
X1134778Y1974703D01*
X1135528Y1975076D01*
X1136153Y1975636D01*
X1136403Y1976383D01*
X1136153Y1977130D01*
X1135528Y1977690D01*
X1134778Y1978063D01*
X1133778Y1978343D01*
X1132653Y1978436D01*
X1131528Y1978343D01*
X1130528Y1978063D01*
X1129778Y1977690D01*
X1129153Y1977130D01*
X1128903Y1976383D01*
G01X1136653Y1983883D02*
X1136528Y1983696D01*
X1136278D01*
X1136153Y1983883D01*
X1136278Y1984070D01*
X1136528D01*
X1136653Y1983883D01*
G01X1134903Y1989330D02*
X1135778Y1989890D01*
X1136278Y1990636D01*
X1136403Y1991476D01*
X1136278Y1992223D01*
X1135653Y1992970D01*
X1134903Y1993436D01*
X1134153Y1993530D01*
X1133278Y1993343D01*
X1132653Y1992690D01*
X1132403Y1992036D01*
Y1991196D01*
G01Y1992036D02*
X1132028Y1992596D01*
X1131403Y1993063D01*
X1130653Y1993250D01*
X1129903Y1993063D01*
X1129278Y1992596D01*
X1128903Y1991756D01*
X1129028Y1990916D01*
X1129528Y1990076D01*
G01X1136403Y1998883D02*
X1128903D01*
X1130403Y1997763D01*
G01X1136403D02*
Y2000003D01*
G01Y2003956D02*
X1128903D01*
X1135153Y2006383D01*
X1128903Y2008810D01*
X1136403D01*
G01Y2011456D02*
X1128903D01*
X1135153Y2013883D01*
X1128903Y2016310D01*
X1136403D01*
G01Y2027110D02*
X1128903D01*
Y2030656D01*
G01X1132528Y2029350D02*
Y2027110D01*
G01X1128903Y2035263D02*
Y2037503D01*
G01Y2036383D02*
X1136403D01*
G01Y2035263D02*
Y2037503D01*
G01Y2041736D02*
X1128903D01*
X1136403Y2046030D01*
X1128903D01*
G01Y2050263D02*
Y2052503D01*
G01Y2051383D02*
X1136403D01*
G01Y2050263D02*
Y2052503D01*
G01X1135403Y2056923D02*
X1136028Y2057670D01*
X1136403Y2058510D01*
Y2059256D01*
X1136028Y2060003D01*
X1135403Y2060563D01*
X1134528Y2060843D01*
X1133653Y2060656D01*
X1132903Y2060190D01*
X1132403Y2059350D01*
X1132153Y2058230D01*
X1131653Y2057576D01*
X1130778Y2057296D01*
X1129903Y2057483D01*
X1129278Y2057950D01*
X1128903Y2058603D01*
Y2059256D01*
X1129153Y2059910D01*
X1129778Y2060470D01*
G01X1136403Y2064423D02*
X1128903D01*
G01Y2068343D02*
X1136403D01*
G01X1132653D02*
Y2064423D01*
G01X1136403Y2075750D02*
Y2072016D01*
X1128903D01*
Y2075750D01*
G01X1132528Y2074256D02*
Y2072016D01*
G01X1136403Y2079330D02*
X1128903D01*
Y2081196D01*
X1129278Y2081943D01*
X1129778Y2082503D01*
X1130528Y2082970D01*
X1131403Y2083343D01*
X1132653Y2083436D01*
X1133903Y2083343D01*
X1134778Y2082970D01*
X1135528Y2082503D01*
X1136028Y2081943D01*
X1136403Y2081196D01*
Y2079330D01*
G01Y2094516D02*
X1128903D01*
Y2096756D01*
X1129278Y2097503D01*
X1130153Y2098063D01*
X1131153Y2098250D01*
X1132153Y2098063D01*
X1132903Y2097596D01*
X1133278Y2096756D01*
Y2094516D01*
G01X1128903Y2103883D02*
X1136403D01*
G01X1128903Y2101736D02*
Y2106030D01*
G01X1136403Y2109423D02*
X1128903D01*
G01Y2113343D02*
X1136403D01*
G01X1132653D02*
Y2109423D01*
G01X1128903Y2125263D02*
Y2127503D01*
G01Y2126383D02*
X1136403D01*
G01Y2125263D02*
Y2127503D01*
G01X1135403Y2131923D02*
X1136028Y2132670D01*
X1136403Y2133510D01*
Y2134256D01*
X1136028Y2135003D01*
X1135403Y2135563D01*
X1134528Y2135843D01*
X1133653Y2135656D01*
X1132903Y2135190D01*
X1132403Y2134350D01*
X1132153Y2133230D01*
X1131653Y2132576D01*
X1130778Y2132296D01*
X1129903Y2132483D01*
X1129278Y2132950D01*
X1128903Y2133603D01*
Y2134256D01*
X1129153Y2134910D01*
X1129778Y2135470D01*
G01X1128903Y2148883D02*
X1129153Y2148136D01*
X1129778Y2147576D01*
X1130528Y2147203D01*
X1131528Y2146923D01*
X1132653Y2146830D01*
X1133778Y2146923D01*
X1134778Y2147203D01*
X1135528Y2147576D01*
X1136153Y2148136D01*
X1136403Y2148883D01*
X1136153Y2149630D01*
X1135528Y2150190D01*
X1134778Y2150563D01*
X1133778Y2150843D01*
X1132653Y2150936D01*
X1131528Y2150843D01*
X1130528Y2150563D01*
X1129778Y2150190D01*
X1129153Y2149630D01*
X1128903Y2148883D01*
G01X1136653Y2156383D02*
X1136528Y2156196D01*
X1136278D01*
X1136153Y2156383D01*
X1136278Y2156570D01*
X1136528D01*
X1136653Y2156383D01*
G01X1136403Y2165003D02*
X1128903D01*
X1134278Y2161550D01*
Y2166216D01*
G01X1136403Y2168956D02*
X1128903D01*
X1135153Y2171383D01*
X1128903Y2173810D01*
X1136403D01*
G01Y2176456D02*
X1128903D01*
X1135153Y2178883D01*
X1128903Y2181310D01*
X1136403D01*
G01Y2191456D02*
X1128903D01*
X1135153Y2193883D01*
X1128903Y2196310D01*
X1136403D01*
G01Y2203250D02*
Y2199516D01*
X1128903D01*
Y2203250D01*
G01X1132528Y2201756D02*
Y2199516D01*
G01X1128903Y2208883D02*
X1136403D01*
G01X1128903Y2206736D02*
Y2211030D01*
G01X1136403Y2214516D02*
X1128903D01*
Y2216850D01*
X1129278Y2217596D01*
X1129778Y2218063D01*
X1130778Y2218250D01*
X1131778Y2218063D01*
X1132403Y2217503D01*
X1132778Y2216850D01*
Y2214516D01*
G01Y2216850D02*
X1136403Y2218250D01*
G01X1128903Y2222763D02*
Y2225003D01*
G01Y2223883D02*
X1136403D01*
G01Y2222763D02*
Y2225003D01*
G01X1129528Y2233436D02*
X1129153Y2232876D01*
X1128903Y2232223D01*
Y2231476D01*
X1129278Y2230636D01*
X1129903Y2229983D01*
X1130653Y2229516D01*
X1131903Y2229143D01*
X1133028Y2229050D01*
X1134153Y2229236D01*
X1134903Y2229516D01*
X1135653Y2230076D01*
X1136153Y2230730D01*
X1136403Y2231383D01*
Y2232036D01*
X1136153Y2232690D01*
X1135778Y2233250D01*
X1135278Y2233716D01*
G01X1136403Y2244330D02*
X1128903D01*
Y2246196D01*
X1129278Y2246943D01*
X1129778Y2247503D01*
X1130528Y2247970D01*
X1131403Y2248343D01*
X1132653Y2248436D01*
X1133903Y2248343D01*
X1134778Y2247970D01*
X1135528Y2247503D01*
X1136028Y2246943D01*
X1136403Y2246196D01*
Y2244330D01*
G01Y2252016D02*
X1128903D01*
Y2254350D01*
X1129278Y2255096D01*
X1129778Y2255563D01*
X1130778Y2255750D01*
X1131778Y2255563D01*
X1132403Y2255003D01*
X1132778Y2254350D01*
Y2252016D01*
G01Y2254350D02*
X1136403Y2255750D01*
G01X1128903Y2260263D02*
Y2262503D01*
G01Y2261383D02*
X1136403D01*
G01Y2260263D02*
Y2262503D01*
G01X1128903Y2267016D02*
X1136403D01*
Y2270750D01*
G01X1128903Y2274516D02*
X1136403D01*
Y2278250D01*
G01X1138903Y2283416D02*
X1137653Y2282483D01*
X1136403Y2282016D01*
X1131403D01*
X1130153Y2282483D01*
X1128903Y2283416D01*
G01Y2291383D02*
X1129153Y2290636D01*
X1129778Y2290076D01*
X1130528Y2289703D01*
X1131528Y2289423D01*
X1132653Y2289330D01*
X1133778Y2289423D01*
X1134778Y2289703D01*
X1135528Y2290076D01*
X1136153Y2290636D01*
X1136403Y2291383D01*
X1136153Y2292130D01*
X1135528Y2292690D01*
X1134778Y2293063D01*
X1133778Y2293343D01*
X1132653Y2293436D01*
X1131528Y2293343D01*
X1130528Y2293063D01*
X1129778Y2292690D01*
X1129153Y2292130D01*
X1128903Y2291383D01*
G01X1136653Y2298883D02*
X1136528Y2298696D01*
X1136278D01*
X1136153Y2298883D01*
X1136278Y2299070D01*
X1136528D01*
X1136653Y2298883D01*
G01X1128903Y2306383D02*
X1129153Y2305636D01*
X1129778Y2305076D01*
X1130528Y2304703D01*
X1131528Y2304423D01*
X1132653Y2304330D01*
X1133778Y2304423D01*
X1134778Y2304703D01*
X1135528Y2305076D01*
X1136153Y2305636D01*
X1136403Y2306383D01*
X1136153Y2307130D01*
X1135528Y2307690D01*
X1134778Y2308063D01*
X1133778Y2308343D01*
X1132653Y2308436D01*
X1131528Y2308343D01*
X1130528Y2308063D01*
X1129778Y2307690D01*
X1129153Y2307130D01*
X1128903Y2306383D01*
G01X1136403Y2313883D02*
X1128903D01*
X1130403Y2312763D01*
G01X1136403D02*
Y2315003D01*
G01X1135278Y2319330D02*
X1135903Y2319890D01*
X1136278Y2320543D01*
X1136403Y2321383D01*
X1136153Y2322223D01*
X1135653Y2322876D01*
X1134778Y2323343D01*
X1133778Y2323436D01*
X1132778Y2323250D01*
X1132153Y2322783D01*
X1131653Y2322130D01*
X1131528Y2321476D01*
X1131653Y2320823D01*
X1132153Y2319983D01*
X1128903Y2320263D01*
Y2322783D01*
G01X1136403Y2328696D02*
X1134778Y2328883D01*
X1133403Y2329163D01*
X1132153Y2329536D01*
X1130778Y2330003D01*
X1128903Y2330750D01*
Y2327016D01*
G01X1130528Y2335543D02*
X1128903Y2336010D01*
G01Y2337223D02*
X1130528Y2336756D01*
G01X1138903Y2344350D02*
X1137653Y2345283D01*
X1136403Y2345750D01*
X1131403D01*
X1130153Y2345283D01*
X1128903Y2344350D01*
G01X1151624Y1453504D02*
G03I-2451J0D01*
G01X1160286Y1457835D02*
G03I-2452J0D01*
G01X1151625Y1468859D02*
G03I-2452J0D01*
G01X1160286Y1473189D02*
G03I-2452J0D01*
G01X1151625Y1484213D02*
G03I-2452J0D01*
G01X1160286Y1488544D02*
G03I-2452J0D01*
G01X1151624Y1499567D02*
G03I-2451J0D01*
G01X1160286Y1503898D02*
G03I-2452J0D01*
G01X1151625Y1514922D02*
G03I-2452J0D01*
G01X1160286Y1519252D02*
G03I-2452J0D01*
G01X1151625Y1555867D02*
G03I-2452J0D01*
G01X1160286Y1560197D02*
G03I-2452J0D01*
G01X1151625Y1571221D02*
G03I-2452J0D01*
G01X1160286Y1575552D02*
G03I-2452J0D01*
G01X1151625Y1586575D02*
G03I-2452J0D01*
G01X1160286Y1590906D02*
G03I-2452J0D01*
G01X1151625Y1601930D02*
G03I-2452J0D01*
G01X1160286Y1606260D02*
G03I-2452J0D01*
G01X1151625Y1617284D02*
G03I-2452J0D01*
G01X1160286Y1621615D02*
G03I-2452J0D01*
G01X1150787Y1704531D02*
X1143287D01*
X1149537Y1706958D01*
X1143287Y1709385D01*
X1150787D01*
G01Y1712125D02*
X1143287Y1714458D01*
X1150787Y1716791D01*
G01X1148162Y1715951D02*
Y1712965D01*
G01X1150787Y1720091D02*
X1143287D01*
Y1722425D01*
X1143662Y1723171D01*
X1144162Y1723638D01*
X1145162Y1723825D01*
X1146162Y1723638D01*
X1146787Y1723078D01*
X1147162Y1722425D01*
Y1720091D01*
G01Y1722425D02*
X1150787Y1723825D01*
G01Y1727405D02*
X1143287D01*
G01Y1730951D02*
X1147912Y1727405D01*
G01X1150787Y1731511D02*
X1145787Y1728991D01*
G01X1151037Y1736958D02*
X1150912Y1736771D01*
X1150662D01*
X1150537Y1736958D01*
X1150662Y1737145D01*
X1150912D01*
X1151037Y1736958D01*
G01X1147662D02*
X1147537Y1736771D01*
X1147287D01*
X1147162Y1736958D01*
X1147287Y1737145D01*
X1147537D01*
X1147662Y1736958D01*
G01X1150787Y1742591D02*
X1143287D01*
Y1744925D01*
X1143662Y1745671D01*
X1144162Y1746138D01*
X1145162Y1746325D01*
X1146162Y1746138D01*
X1146787Y1745578D01*
X1147162Y1744925D01*
Y1742591D01*
G01Y1744925D02*
X1150787Y1746325D01*
G01Y1753825D02*
Y1750091D01*
X1143287D01*
Y1753825D01*
G01X1146912Y1752331D02*
Y1750091D01*
G01X1143912Y1761511D02*
X1143537Y1760951D01*
X1143287Y1760298D01*
Y1759551D01*
X1143662Y1758711D01*
X1144287Y1758058D01*
X1145037Y1757591D01*
X1146287Y1757218D01*
X1147412Y1757125D01*
X1148537Y1757311D01*
X1149287Y1757591D01*
X1150037Y1758151D01*
X1150537Y1758805D01*
X1150787Y1759458D01*
Y1760111D01*
X1150537Y1760765D01*
X1150162Y1761325D01*
X1149662Y1761791D01*
G01X1150787Y1766958D02*
X1150662Y1766211D01*
X1150162Y1765558D01*
X1149412Y1764998D01*
X1148537Y1764625D01*
X1147537Y1764438D01*
X1146537D01*
X1145537Y1764625D01*
X1144662Y1764998D01*
X1143912Y1765558D01*
X1143412Y1766211D01*
X1143287Y1766958D01*
X1143412Y1767705D01*
X1143912Y1768358D01*
X1144662Y1768918D01*
X1145537Y1769291D01*
X1146537Y1769478D01*
X1147537D01*
X1148537Y1769291D01*
X1149412Y1768918D01*
X1150162Y1768358D01*
X1150662Y1767705D01*
X1150787Y1766958D01*
G01Y1772031D02*
X1143287D01*
X1149537Y1774458D01*
X1143287Y1776885D01*
X1150787D01*
G01Y1779531D02*
X1143287D01*
X1149537Y1781958D01*
X1143287Y1784385D01*
X1150787D01*
G01Y1791325D02*
Y1787591D01*
X1143287D01*
Y1791325D01*
G01X1146912Y1789831D02*
Y1787591D01*
G01X1150787Y1794811D02*
X1143287D01*
X1150787Y1799105D01*
X1143287D01*
G01X1150787Y1802405D02*
X1143287D01*
Y1804271D01*
X1143662Y1805018D01*
X1144162Y1805578D01*
X1144912Y1806045D01*
X1145787Y1806418D01*
X1147037Y1806511D01*
X1148287Y1806418D01*
X1149162Y1806045D01*
X1149912Y1805578D01*
X1150412Y1805018D01*
X1150787Y1804271D01*
Y1802405D01*
G01Y1813825D02*
Y1810091D01*
X1143287D01*
Y1813825D01*
G01X1146912Y1812331D02*
Y1810091D01*
G01X1150787Y1817405D02*
X1143287D01*
Y1819271D01*
X1143662Y1820018D01*
X1144162Y1820578D01*
X1144912Y1821045D01*
X1145787Y1821418D01*
X1147037Y1821511D01*
X1148287Y1821418D01*
X1149162Y1821045D01*
X1149912Y1820578D01*
X1150412Y1820018D01*
X1150787Y1819271D01*
Y1817405D01*
G01Y1832405D02*
X1143287D01*
Y1834271D01*
X1143662Y1835018D01*
X1144162Y1835578D01*
X1144912Y1836045D01*
X1145787Y1836418D01*
X1147037Y1836511D01*
X1148287Y1836418D01*
X1149162Y1836045D01*
X1149912Y1835578D01*
X1150412Y1835018D01*
X1150787Y1834271D01*
Y1832405D01*
G01Y1840091D02*
X1143287D01*
Y1842425D01*
X1143662Y1843171D01*
X1144162Y1843638D01*
X1145162Y1843825D01*
X1146162Y1843638D01*
X1146787Y1843078D01*
X1147162Y1842425D01*
Y1840091D01*
G01Y1842425D02*
X1150787Y1843825D01*
G01X1143287Y1848338D02*
Y1850578D01*
G01Y1849458D02*
X1150787D01*
G01Y1848338D02*
Y1850578D01*
G01X1143287Y1855091D02*
X1150787D01*
Y1858825D01*
G01X1143287Y1862591D02*
X1150787D01*
Y1866325D01*
G01X1149787Y1877498D02*
X1150412Y1878245D01*
X1150787Y1879085D01*
Y1879831D01*
X1150412Y1880578D01*
X1149787Y1881138D01*
X1148912Y1881418D01*
X1148037Y1881231D01*
X1147287Y1880765D01*
X1146787Y1879925D01*
X1146537Y1878805D01*
X1146037Y1878151D01*
X1145162Y1877871D01*
X1144287Y1878058D01*
X1143662Y1878525D01*
X1143287Y1879178D01*
Y1879831D01*
X1143537Y1880485D01*
X1144162Y1881045D01*
G01X1143287Y1885838D02*
Y1888078D01*
G01Y1886958D02*
X1150787D01*
G01Y1885838D02*
Y1888078D01*
G01X1143287Y1892685D02*
Y1896231D01*
X1150787Y1892685D01*
Y1896231D01*
G01Y1903825D02*
Y1900091D01*
X1143287D01*
Y1903825D01*
G01X1146912Y1902331D02*
Y1900091D01*
G01X1150787Y1915185D02*
X1143287D01*
Y1918731D01*
G01X1146912Y1917425D02*
Y1915185D01*
G01X1150787Y1924458D02*
X1150662Y1923711D01*
X1150162Y1923058D01*
X1149412Y1922498D01*
X1148537Y1922125D01*
X1147537Y1921938D01*
X1146537D01*
X1145537Y1922125D01*
X1144662Y1922498D01*
X1143912Y1923058D01*
X1143412Y1923711D01*
X1143287Y1924458D01*
X1143412Y1925205D01*
X1143912Y1925858D01*
X1144662Y1926418D01*
X1145537Y1926791D01*
X1146537Y1926978D01*
X1147537D01*
X1148537Y1926791D01*
X1149412Y1926418D01*
X1150162Y1925858D01*
X1150662Y1925205D01*
X1150787Y1924458D01*
G01Y1930091D02*
X1143287D01*
Y1932425D01*
X1143662Y1933171D01*
X1144162Y1933638D01*
X1145162Y1933825D01*
X1146162Y1933638D01*
X1146787Y1933078D01*
X1147162Y1932425D01*
Y1930091D01*
G01Y1932425D02*
X1150787Y1933825D01*
G01X1143287Y1946958D02*
X1143537Y1946211D01*
X1144162Y1945651D01*
X1144912Y1945278D01*
X1145912Y1944998D01*
X1147037Y1944905D01*
X1148162Y1944998D01*
X1149162Y1945278D01*
X1149912Y1945651D01*
X1150537Y1946211D01*
X1150787Y1946958D01*
X1150537Y1947705D01*
X1149912Y1948265D01*
X1149162Y1948638D01*
X1148162Y1948918D01*
X1147037Y1949011D01*
X1145912Y1948918D01*
X1144912Y1948638D01*
X1144162Y1948265D01*
X1143537Y1947705D01*
X1143287Y1946958D01*
G01X1151037Y1954458D02*
X1150912Y1954271D01*
X1150662D01*
X1150537Y1954458D01*
X1150662Y1954645D01*
X1150912D01*
X1151037Y1954458D01*
G01X1149662Y1959905D02*
X1150287Y1960465D01*
X1150662Y1961118D01*
X1150787Y1961958D01*
X1150537Y1962798D01*
X1150037Y1963451D01*
X1149162Y1963918D01*
X1148162Y1964011D01*
X1147162Y1963825D01*
X1146537Y1963358D01*
X1146037Y1962705D01*
X1145912Y1962051D01*
X1146037Y1961398D01*
X1146537Y1960558D01*
X1143287Y1960838D01*
Y1963358D01*
G01X1150787Y1967031D02*
X1143287D01*
X1149537Y1969458D01*
X1143287Y1971885D01*
X1150787D01*
G01Y1974531D02*
X1143287D01*
X1149537Y1976958D01*
X1143287Y1979385D01*
X1150787D01*
G01Y1990185D02*
X1143287D01*
Y1993731D01*
G01X1146912Y1992425D02*
Y1990185D01*
G01X1143287Y1998338D02*
Y2000578D01*
G01Y1999458D02*
X1150787D01*
G01Y1998338D02*
Y2000578D01*
G01Y2004811D02*
X1143287D01*
X1150787Y2009105D01*
X1143287D01*
G01Y2013338D02*
Y2015578D01*
G01Y2014458D02*
X1150787D01*
G01Y2013338D02*
Y2015578D01*
G01X1149787Y2019998D02*
X1150412Y2020745D01*
X1150787Y2021585D01*
Y2022331D01*
X1150412Y2023078D01*
X1149787Y2023638D01*
X1148912Y2023918D01*
X1148037Y2023731D01*
X1147287Y2023265D01*
X1146787Y2022425D01*
X1146537Y2021305D01*
X1146037Y2020651D01*
X1145162Y2020371D01*
X1144287Y2020558D01*
X1143662Y2021025D01*
X1143287Y2021678D01*
Y2022331D01*
X1143537Y2022985D01*
X1144162Y2023545D01*
G01X1150787Y2027498D02*
X1143287D01*
G01Y2031418D02*
X1150787D01*
G01X1147037D02*
Y2027498D01*
G01X1150787Y2038825D02*
Y2035091D01*
X1143287D01*
Y2038825D01*
G01X1146912Y2037331D02*
Y2035091D01*
G01X1150787Y2042405D02*
X1143287D01*
Y2044271D01*
X1143662Y2045018D01*
X1144162Y2045578D01*
X1144912Y2046045D01*
X1145787Y2046418D01*
X1147037Y2046511D01*
X1148287Y2046418D01*
X1149162Y2046045D01*
X1149912Y2045578D01*
X1150412Y2045018D01*
X1150787Y2044271D01*
Y2042405D01*
G01Y2057591D02*
X1143287D01*
Y2059831D01*
X1143662Y2060578D01*
X1144537Y2061138D01*
X1145537Y2061325D01*
X1146537Y2061138D01*
X1147287Y2060671D01*
X1147662Y2059831D01*
Y2057591D01*
G01X1143287Y2066958D02*
X1150787D01*
G01X1143287Y2064811D02*
Y2069105D01*
G01X1150787Y2072498D02*
X1143287D01*
G01Y2076418D02*
X1150787D01*
G01X1147037D02*
Y2072498D01*
G01X1143287Y2088338D02*
Y2090578D01*
G01Y2089458D02*
X1150787D01*
G01Y2088338D02*
Y2090578D01*
G01X1149787Y2094998D02*
X1150412Y2095745D01*
X1150787Y2096585D01*
Y2097331D01*
X1150412Y2098078D01*
X1149787Y2098638D01*
X1148912Y2098918D01*
X1148037Y2098731D01*
X1147287Y2098265D01*
X1146787Y2097425D01*
X1146537Y2096305D01*
X1146037Y2095651D01*
X1145162Y2095371D01*
X1144287Y2095558D01*
X1143662Y2096025D01*
X1143287Y2096678D01*
Y2097331D01*
X1143537Y2097985D01*
X1144162Y2098545D01*
G01X1143287Y2111958D02*
X1143537Y2111211D01*
X1144162Y2110651D01*
X1144912Y2110278D01*
X1145912Y2109998D01*
X1147037Y2109905D01*
X1148162Y2109998D01*
X1149162Y2110278D01*
X1149912Y2110651D01*
X1150537Y2111211D01*
X1150787Y2111958D01*
X1150537Y2112705D01*
X1149912Y2113265D01*
X1149162Y2113638D01*
X1148162Y2113918D01*
X1147037Y2114011D01*
X1145912Y2113918D01*
X1144912Y2113638D01*
X1144162Y2113265D01*
X1143537Y2112705D01*
X1143287Y2111958D01*
G01X1151037Y2119458D02*
X1150912Y2119271D01*
X1150662D01*
X1150537Y2119458D01*
X1150662Y2119645D01*
X1150912D01*
X1151037Y2119458D01*
G01X1147662Y2125185D02*
X1146787Y2125838D01*
X1146287Y2126398D01*
X1146037Y2127145D01*
X1146287Y2127798D01*
X1146787Y2128265D01*
X1147537Y2128638D01*
X1148412Y2128731D01*
X1149162Y2128638D01*
X1149912Y2128265D01*
X1150537Y2127705D01*
X1150787Y2127051D01*
X1150537Y2126305D01*
X1149787Y2125651D01*
X1148662Y2125278D01*
X1147412Y2125185D01*
X1145787Y2125371D01*
X1144912Y2125651D01*
X1144037Y2126118D01*
X1143412Y2126771D01*
X1143287Y2127425D01*
X1143537Y2128078D01*
X1144162Y2128545D01*
G01X1150787Y2132031D02*
X1143287D01*
X1149537Y2134458D01*
X1143287Y2136885D01*
X1150787D01*
G01Y2139531D02*
X1143287D01*
X1149537Y2141958D01*
X1143287Y2144385D01*
X1150787D01*
G01Y2154531D02*
X1143287D01*
X1149537Y2156958D01*
X1143287Y2159385D01*
X1150787D01*
G01Y2166325D02*
Y2162591D01*
X1143287D01*
Y2166325D01*
G01X1146912Y2164831D02*
Y2162591D01*
G01X1143287Y2171958D02*
X1150787D01*
G01X1143287Y2169811D02*
Y2174105D01*
G01X1150787Y2177591D02*
X1143287D01*
Y2179925D01*
X1143662Y2180671D01*
X1144162Y2181138D01*
X1145162Y2181325D01*
X1146162Y2181138D01*
X1146787Y2180578D01*
X1147162Y2179925D01*
Y2177591D01*
G01Y2179925D02*
X1150787Y2181325D01*
G01X1143287Y2185838D02*
Y2188078D01*
G01Y2186958D02*
X1150787D01*
G01Y2185838D02*
Y2188078D01*
G01X1143912Y2196511D02*
X1143537Y2195951D01*
X1143287Y2195298D01*
Y2194551D01*
X1143662Y2193711D01*
X1144287Y2193058D01*
X1145037Y2192591D01*
X1146287Y2192218D01*
X1147412Y2192125D01*
X1148537Y2192311D01*
X1149287Y2192591D01*
X1150037Y2193151D01*
X1150537Y2193805D01*
X1150787Y2194458D01*
Y2195111D01*
X1150537Y2195765D01*
X1150162Y2196325D01*
X1149662Y2196791D01*
G01X1150787Y2207405D02*
X1143287D01*
Y2209271D01*
X1143662Y2210018D01*
X1144162Y2210578D01*
X1144912Y2211045D01*
X1145787Y2211418D01*
X1147037Y2211511D01*
X1148287Y2211418D01*
X1149162Y2211045D01*
X1149912Y2210578D01*
X1150412Y2210018D01*
X1150787Y2209271D01*
Y2207405D01*
G01Y2215091D02*
X1143287D01*
Y2217425D01*
X1143662Y2218171D01*
X1144162Y2218638D01*
X1145162Y2218825D01*
X1146162Y2218638D01*
X1146787Y2218078D01*
X1147162Y2217425D01*
Y2215091D01*
G01Y2217425D02*
X1150787Y2218825D01*
G01X1143287Y2223338D02*
Y2225578D01*
G01Y2224458D02*
X1150787D01*
G01Y2223338D02*
Y2225578D01*
G01X1143287Y2230091D02*
X1150787D01*
Y2233825D01*
G01X1143287Y2237591D02*
X1150787D01*
Y2241325D01*
G01X1153287Y2246491D02*
X1152037Y2245558D01*
X1150787Y2245091D01*
X1145787D01*
X1144537Y2245558D01*
X1143287Y2246491D01*
G01Y2254458D02*
X1143537Y2253711D01*
X1144162Y2253151D01*
X1144912Y2252778D01*
X1145912Y2252498D01*
X1147037Y2252405D01*
X1148162Y2252498D01*
X1149162Y2252778D01*
X1149912Y2253151D01*
X1150537Y2253711D01*
X1150787Y2254458D01*
X1150537Y2255205D01*
X1149912Y2255765D01*
X1149162Y2256138D01*
X1148162Y2256418D01*
X1147037Y2256511D01*
X1145912Y2256418D01*
X1144912Y2256138D01*
X1144162Y2255765D01*
X1143537Y2255205D01*
X1143287Y2254458D01*
G01X1151037Y2261958D02*
X1150912Y2261771D01*
X1150662D01*
X1150537Y2261958D01*
X1150662Y2262145D01*
X1150912D01*
X1151037Y2261958D01*
G01X1143287Y2269458D02*
X1143537Y2268711D01*
X1144162Y2268151D01*
X1144912Y2267778D01*
X1145912Y2267498D01*
X1147037Y2267405D01*
X1148162Y2267498D01*
X1149162Y2267778D01*
X1149912Y2268151D01*
X1150537Y2268711D01*
X1150787Y2269458D01*
X1150537Y2270205D01*
X1149912Y2270765D01*
X1149162Y2271138D01*
X1148162Y2271418D01*
X1147037Y2271511D01*
X1145912Y2271418D01*
X1144912Y2271138D01*
X1144162Y2270765D01*
X1143537Y2270205D01*
X1143287Y2269458D01*
G01X1144537Y2275185D02*
X1143787Y2275745D01*
X1143412Y2276398D01*
X1143287Y2277145D01*
X1143537Y2278078D01*
X1144162Y2278731D01*
X1144912Y2278918D01*
X1145662Y2278825D01*
X1146287Y2278451D01*
X1147537Y2276585D01*
X1148412Y2275745D01*
X1149662Y2275185D01*
X1150787Y2274998D01*
Y2278918D01*
G01X1149287Y2282405D02*
X1150162Y2282965D01*
X1150662Y2283711D01*
X1150787Y2284551D01*
X1150662Y2285298D01*
X1150037Y2286045D01*
X1149287Y2286511D01*
X1148537Y2286605D01*
X1147662Y2286418D01*
X1147037Y2285765D01*
X1146787Y2285111D01*
Y2284271D01*
G01Y2285111D02*
X1146412Y2285671D01*
X1145787Y2286138D01*
X1145037Y2286325D01*
X1144287Y2286138D01*
X1143662Y2285671D01*
X1143287Y2284831D01*
X1143412Y2283991D01*
X1143912Y2283151D01*
G01X1147662Y2290185D02*
X1146787Y2290838D01*
X1146287Y2291398D01*
X1146037Y2292145D01*
X1146287Y2292798D01*
X1146787Y2293265D01*
X1147537Y2293638D01*
X1148412Y2293731D01*
X1149162Y2293638D01*
X1149912Y2293265D01*
X1150537Y2292705D01*
X1150787Y2292051D01*
X1150537Y2291305D01*
X1149787Y2290651D01*
X1148662Y2290278D01*
X1147412Y2290185D01*
X1145787Y2290371D01*
X1144912Y2290651D01*
X1144037Y2291118D01*
X1143412Y2291771D01*
X1143287Y2292425D01*
X1143537Y2293078D01*
X1144162Y2293545D01*
G01X1144912Y2298618D02*
X1143287Y2299085D01*
G01Y2300298D02*
X1144912Y2299831D01*
G01X1153287Y2307425D02*
X1152037Y2308358D01*
X1150787Y2308825D01*
X1145787D01*
X1144537Y2308358D01*
X1143287Y2307425D01*
G01X1168947Y1453504D02*
G03I-2451J0D01*
G01X1168948Y1468859D02*
G03I-2452J0D01*
G01Y1484213D02*
G03I-2452J0D01*
G01X1168947Y1499567D02*
G03I-2451J0D01*
G01X1168948Y1514922D02*
G03I-2452J0D01*
G01Y1555867D02*
G03I-2452J0D01*
G01Y1571221D02*
G03I-2452J0D01*
G01X1168947Y1586575D02*
G03I-2451J0D01*
G01X1168948Y1601930D02*
G03I-2452J0D01*
G01Y1617284D02*
G03I-2452J0D01*
G01X1177609Y1457835D02*
G03I-2452J0D01*
G01X1186270Y1453504D02*
G03I-2452J0D01*
G01X1177609Y1473189D02*
G03I-2452J0D01*
G01X1186270Y1468859D02*
G03I-2452J0D01*
G01X1177609Y1488544D02*
G03I-2452J0D01*
G01X1186270Y1484213D02*
G03I-2452J0D01*
G01Y1499567D02*
G03I-2452J0D01*
G01X1177609Y1503898D02*
G03I-2452J0D01*
G01X1186270Y1514922D02*
G03I-2452J0D01*
G01X1177609Y1519252D02*
G03I-2452J0D01*
G01Y1560197D02*
G03I-2452J0D01*
G01X1186270Y1555867D02*
G03I-2452J0D01*
G01X1177609Y1575552D02*
G03I-2452J0D01*
G01X1186270Y1571221D02*
G03I-2452J0D01*
G01X1177609Y1590906D02*
G03I-2452J0D01*
G01X1186270Y1586575D02*
G03I-2452J0D01*
G01X1177609Y1606260D02*
G03I-2452J0D01*
G01X1186270Y1601930D02*
G03I-2452J0D01*
G01X1177609Y1621615D02*
G03I-2452J0D01*
G01X1186270Y1617284D02*
G03I-2452J0D01*
G01X1194932Y1457835D02*
G03I-2452J0D01*
G01X1203593Y1453504D02*
G03I-2452J0D01*
G01X1194932Y1473189D02*
G03I-2452J0D01*
G01X1203593Y1468859D02*
G03I-2452J0D01*
G01X1194932Y1488544D02*
G03I-2452J0D01*
G01X1203593Y1484213D02*
G03I-2452J0D01*
G01Y1499567D02*
G03I-2452J0D01*
G01X1194932Y1503898D02*
G03I-2452J0D01*
G01X1203593Y1514922D02*
G03I-2452J0D01*
G01X1194932Y1519252D02*
G03I-2452J0D01*
G01Y1560197D02*
G03I-2452J0D01*
G01X1203593Y1555867D02*
G03I-2452J0D01*
G01X1194932Y1575552D02*
G03I-2452J0D01*
G01X1203593Y1571221D02*
G03I-2452J0D01*
G01X1194932Y1590906D02*
G03I-2452J0D01*
G01X1203593Y1586575D02*
G03I-2452J0D01*
G01X1194932Y1606260D02*
G03I-2452J0D01*
G01X1203593Y1601930D02*
G03I-2452J0D01*
G01X1194932Y1621615D02*
G03I-2452J0D01*
G01X1203593Y1617284D02*
G03I-2452J0D01*
G01X1212255Y1457835D02*
G03I-2452J0D01*
G01Y1473189D02*
G03I-2452J0D01*
G01Y1488544D02*
G03I-2452J0D01*
G01Y1503898D02*
G03I-2452J0D01*
G01Y1519252D02*
G03I-2452J0D01*
G01X1212254Y1560197D02*
G03I-2451J0D01*
G01X1212255Y1575552D02*
G03I-2452J0D01*
G01Y1590906D02*
G03I-2452J0D01*
G01X1212254Y1606260D02*
G03I-2451J0D01*
G01X1212255Y1621615D02*
G03I-2452J0D01*
G01X1273375Y-442724D02*
X1260875D01*
X1263375Y-444584D01*
G01X1273375D02*
Y-440864D01*
G01X1262958Y-433269D02*
X1261709Y-432339D01*
X1261083Y-431254D01*
X1260875Y-430014D01*
X1261292Y-428464D01*
X1262333Y-427379D01*
X1263583Y-427069D01*
X1264834Y-427224D01*
X1265875Y-427844D01*
X1267958Y-430944D01*
X1269417Y-432339D01*
X1271500Y-433269D01*
X1273375Y-433579D01*
Y-427069D01*
G01X1268167Y-420869D02*
X1266708Y-419784D01*
X1265875Y-418854D01*
X1265458Y-417614D01*
X1265875Y-416529D01*
X1266708Y-415754D01*
X1267958Y-415134D01*
X1269417Y-414979D01*
X1270667Y-415134D01*
X1271917Y-415754D01*
X1272958Y-416684D01*
X1273375Y-417769D01*
X1272958Y-419009D01*
X1271709Y-420094D01*
X1269833Y-420714D01*
X1267750Y-420869D01*
X1265042Y-420559D01*
X1263583Y-420094D01*
X1262125Y-419319D01*
X1261083Y-418234D01*
X1260875Y-417149D01*
X1261292Y-416064D01*
X1262333Y-415289D01*
G01X1273375Y-405834D02*
X1270667Y-405524D01*
X1268375Y-405059D01*
X1266292Y-404439D01*
X1264000Y-403664D01*
X1260875Y-402424D01*
Y-408624D01*
G01X1273375Y-393124D02*
X1260875D01*
X1263375Y-394984D01*
G01X1273375D02*
Y-391264D01*
G01X1273792Y-380724D02*
X1273583Y-381034D01*
X1273167D01*
X1272958Y-380724D01*
X1273167Y-380414D01*
X1273583D01*
X1273792Y-380724D01*
G01X1262958Y-371269D02*
X1261709Y-370339D01*
X1261083Y-369254D01*
X1260875Y-368014D01*
X1261292Y-366464D01*
X1262333Y-365379D01*
X1263583Y-365069D01*
X1264834Y-365224D01*
X1265875Y-365844D01*
X1267958Y-368944D01*
X1269417Y-370339D01*
X1271500Y-371269D01*
X1273375Y-371579D01*
Y-365069D01*
G01X1271500Y-359334D02*
X1272542Y-358404D01*
X1273167Y-357319D01*
X1273375Y-355924D01*
X1272958Y-354529D01*
X1272125Y-353444D01*
X1270667Y-352669D01*
X1269000Y-352514D01*
X1267333Y-352824D01*
X1266292Y-353599D01*
X1265458Y-354684D01*
X1265250Y-355769D01*
X1265458Y-356854D01*
X1266292Y-358249D01*
X1260875Y-357784D01*
Y-353599D01*
G01X1270875Y-324734D02*
X1272334Y-323804D01*
X1273167Y-322564D01*
X1273375Y-321169D01*
X1273167Y-319929D01*
X1272125Y-318689D01*
X1270875Y-317914D01*
X1269625Y-317759D01*
X1268167Y-318069D01*
X1267125Y-319154D01*
X1266708Y-320239D01*
Y-321634D01*
G01Y-320239D02*
X1266083Y-319309D01*
X1265042Y-318534D01*
X1263792Y-318224D01*
X1262542Y-318534D01*
X1261500Y-319309D01*
X1260875Y-320704D01*
X1261083Y-322099D01*
X1261917Y-323494D01*
G01X1262958Y-311869D02*
X1261709Y-310939D01*
X1261083Y-309854D01*
X1260875Y-308614D01*
X1261292Y-307064D01*
X1262333Y-305979D01*
X1263583Y-305669D01*
X1264834Y-305824D01*
X1265875Y-306444D01*
X1267958Y-309544D01*
X1269417Y-310939D01*
X1271500Y-311869D01*
X1273375Y-312179D01*
Y-305669D01*
G01Y-296524D02*
X1260875D01*
X1263375Y-298384D01*
G01X1273375D02*
Y-294664D01*
G01X1273792Y-284124D02*
X1273583Y-284434D01*
X1273167D01*
X1272958Y-284124D01*
X1273167Y-283814D01*
X1273583D01*
X1273792Y-284124D01*
G01X1273375Y-271724D02*
X1273167Y-270639D01*
X1272542Y-269399D01*
X1271500Y-268624D01*
X1270042Y-268314D01*
X1268584Y-268624D01*
X1267333Y-269554D01*
X1266708Y-270949D01*
Y-272499D01*
X1266292Y-273429D01*
X1265250Y-274204D01*
X1263792Y-274514D01*
X1262333Y-274049D01*
X1261292Y-272964D01*
X1260875Y-271724D01*
X1261292Y-270484D01*
X1262333Y-269399D01*
X1263792Y-268934D01*
X1265250Y-269244D01*
X1266292Y-270019D01*
X1266708Y-270949D01*
Y-272499D01*
X1267333Y-273894D01*
X1268584Y-274824D01*
X1270042Y-275134D01*
X1271500Y-274824D01*
X1272542Y-274049D01*
X1273167Y-272809D01*
X1273375Y-271724D01*
G01X1271500Y-262734D02*
X1272542Y-261804D01*
X1273167Y-260719D01*
X1273375Y-259324D01*
X1272958Y-257929D01*
X1272125Y-256844D01*
X1270667Y-256069D01*
X1269000Y-255914D01*
X1267333Y-256224D01*
X1266292Y-256999D01*
X1265458Y-258084D01*
X1265250Y-259169D01*
X1265458Y-260254D01*
X1266292Y-261649D01*
X1260875Y-261184D01*
Y-256999D01*
G01X1316192Y1457835D02*
G03I-2452J0D01*
G01X1307530Y1453504D02*
G03I-2451J0D01*
G01X1316192Y1473189D02*
G03I-2452J0D01*
G01X1307531Y1468859D02*
G03I-2452J0D01*
G01X1307530Y1499567D02*
G03I-2451J0D01*
G01X1316192Y1488544D02*
G03I-2452J0D01*
G01X1307531Y1484213D02*
G03I-2452J0D01*
G01Y1514922D02*
G03I-2452J0D01*
G01X1316192Y1503898D02*
G03I-2452J0D01*
G01Y1519252D02*
G03I-2452J0D01*
G01X1307531Y1555867D02*
G03I-2452J0D01*
G01X1316192Y1560197D02*
G03I-2452J0D01*
G01Y1575552D02*
G03I-2452J0D01*
G01X1307531Y1571221D02*
G03I-2452J0D01*
G01X1316192Y1590906D02*
G03I-2452J0D01*
G01X1307531Y1586575D02*
G03I-2452J0D01*
G01X1316192Y1606260D02*
G03I-2452J0D01*
G01X1307531Y1601930D02*
G03I-2452J0D01*
G01X1316192Y1621615D02*
G03I-2452J0D01*
G01X1307531Y1617284D02*
G03I-2452J0D01*
G01X1333515Y1457835D02*
G03I-2452J0D01*
G01X1324853Y1453504D02*
G03I-2451J0D01*
G01X1333515Y1473189D02*
G03I-2452J0D01*
G01X1324854Y1468859D02*
G03I-2452J0D01*
G01X1324853Y1499567D02*
G03I-2451J0D01*
G01X1333515Y1488544D02*
G03I-2452J0D01*
G01X1324854Y1484213D02*
G03I-2452J0D01*
G01Y1514922D02*
G03I-2452J0D01*
G01X1333515Y1503898D02*
G03I-2452J0D01*
G01Y1519252D02*
G03I-2452J0D01*
G01Y1560197D02*
G03I-2452J0D01*
G01X1324854Y1555867D02*
G03I-2452J0D01*
G01X1333515Y1575552D02*
G03I-2452J0D01*
G01X1324854Y1571221D02*
G03I-2452J0D01*
G01X1333515Y1590906D02*
G03I-2452J0D01*
G01X1324854Y1586575D02*
G03I-2452J0D01*
G01X1333515Y1606260D02*
G03I-2452J0D01*
G01X1324854Y1601930D02*
G03I-2452J0D01*
G01X1333515Y1621615D02*
G03I-2452J0D01*
G01X1324854Y1617284D02*
G03I-2452J0D01*
G01X1350838Y1457835D02*
G03I-2452J0D01*
G01X1342176Y1453504D02*
G03I-2451J0D01*
G01X1350838Y1473189D02*
G03I-2452J0D01*
G01X1342177Y1468859D02*
G03I-2452J0D01*
G01X1342176Y1499567D02*
G03I-2451J0D01*
G01X1350838Y1488544D02*
G03I-2452J0D01*
G01X1342177Y1484213D02*
G03I-2452J0D01*
G01Y1514922D02*
G03I-2452J0D01*
G01X1350838Y1503898D02*
G03I-2452J0D01*
G01Y1519252D02*
G03I-2452J0D01*
G01Y1560197D02*
G03I-2452J0D01*
G01X1342177Y1555867D02*
G03I-2452J0D01*
G01X1350838Y1575552D02*
G03I-2452J0D01*
G01X1342177Y1571221D02*
G03I-2452J0D01*
G01X1350838Y1590906D02*
G03I-2452J0D01*
G01X1342176Y1586575D02*
G03I-2451J0D01*
G01X1350838Y1606260D02*
G03I-2452J0D01*
G01X1342177Y1601930D02*
G03I-2452J0D01*
G01X1350838Y1621615D02*
G03I-2452J0D01*
G01X1342177Y1617284D02*
G03I-2452J0D01*
G01X1352696Y1703177D02*
X1345196D01*
X1352696Y1707471D01*
X1345196D01*
G01X1352696Y1712824D02*
X1352571Y1712077D01*
X1352071Y1711424D01*
X1351321Y1710864D01*
X1350446Y1710491D01*
X1349446Y1710304D01*
X1348446D01*
X1347446Y1710491D01*
X1346571Y1710864D01*
X1345821Y1711424D01*
X1345321Y1712077D01*
X1345196Y1712824D01*
X1345321Y1713571D01*
X1345821Y1714224D01*
X1346571Y1714784D01*
X1347446Y1715157D01*
X1348446Y1715344D01*
X1349446D01*
X1350446Y1715157D01*
X1351321Y1714784D01*
X1352071Y1714224D01*
X1352571Y1713571D01*
X1352696Y1712824D01*
G01Y1718177D02*
X1345196D01*
X1352696Y1722471D01*
X1345196D01*
G01X1350196Y1726611D02*
Y1729037D01*
G01X1352696Y1732897D02*
X1345196D01*
X1351446Y1735324D01*
X1345196Y1737751D01*
X1352696D01*
G01Y1740491D02*
X1345196Y1742824D01*
X1352696Y1745157D01*
G01X1350071Y1744317D02*
Y1741331D01*
G01X1352696Y1748457D02*
X1345196D01*
Y1750791D01*
X1345571Y1751537D01*
X1346071Y1752004D01*
X1347071Y1752191D01*
X1348071Y1752004D01*
X1348696Y1751444D01*
X1349071Y1750791D01*
Y1748457D01*
G01Y1750791D02*
X1352696Y1752191D01*
G01Y1755771D02*
X1345196D01*
G01Y1759317D02*
X1349821Y1755771D01*
G01X1352696Y1759877D02*
X1347696Y1757357D01*
G01X1352946Y1765324D02*
X1352821Y1765137D01*
X1352571D01*
X1352446Y1765324D01*
X1352571Y1765511D01*
X1352821D01*
X1352946Y1765324D01*
G01X1349571D02*
X1349446Y1765137D01*
X1349196D01*
X1349071Y1765324D01*
X1349196Y1765511D01*
X1349446D01*
X1349571Y1765324D01*
G01X1352696Y1770957D02*
X1345196D01*
Y1773291D01*
X1345571Y1774037D01*
X1346071Y1774504D01*
X1347071Y1774691D01*
X1348071Y1774504D01*
X1348696Y1773944D01*
X1349071Y1773291D01*
Y1770957D01*
G01Y1773291D02*
X1352696Y1774691D01*
G01Y1782191D02*
Y1778457D01*
X1345196D01*
Y1782191D01*
G01X1348821Y1780697D02*
Y1778457D01*
G01X1345821Y1789877D02*
X1345446Y1789317D01*
X1345196Y1788664D01*
Y1787917D01*
X1345571Y1787077D01*
X1346196Y1786424D01*
X1346946Y1785957D01*
X1348196Y1785584D01*
X1349321Y1785491D01*
X1350446Y1785677D01*
X1351196Y1785957D01*
X1351946Y1786517D01*
X1352446Y1787171D01*
X1352696Y1787824D01*
Y1788477D01*
X1352446Y1789131D01*
X1352071Y1789691D01*
X1351571Y1790157D01*
G01X1352696Y1795324D02*
X1352571Y1794577D01*
X1352071Y1793924D01*
X1351321Y1793364D01*
X1350446Y1792991D01*
X1349446Y1792804D01*
X1348446D01*
X1347446Y1792991D01*
X1346571Y1793364D01*
X1345821Y1793924D01*
X1345321Y1794577D01*
X1345196Y1795324D01*
X1345321Y1796071D01*
X1345821Y1796724D01*
X1346571Y1797284D01*
X1347446Y1797657D01*
X1348446Y1797844D01*
X1349446D01*
X1350446Y1797657D01*
X1351321Y1797284D01*
X1352071Y1796724D01*
X1352571Y1796071D01*
X1352696Y1795324D01*
G01Y1800397D02*
X1345196D01*
X1351446Y1802824D01*
X1345196Y1805251D01*
X1352696D01*
G01Y1807897D02*
X1345196D01*
X1351446Y1810324D01*
X1345196Y1812751D01*
X1352696D01*
G01Y1819691D02*
Y1815957D01*
X1345196D01*
Y1819691D01*
G01X1348821Y1818197D02*
Y1815957D01*
G01X1352696Y1823177D02*
X1345196D01*
X1352696Y1827471D01*
X1345196D01*
G01X1352696Y1830771D02*
X1345196D01*
Y1832637D01*
X1345571Y1833384D01*
X1346071Y1833944D01*
X1346821Y1834411D01*
X1347696Y1834784D01*
X1348946Y1834877D01*
X1350196Y1834784D01*
X1351071Y1834411D01*
X1351821Y1833944D01*
X1352321Y1833384D01*
X1352696Y1832637D01*
Y1830771D01*
G01Y1842191D02*
Y1838457D01*
X1345196D01*
Y1842191D01*
G01X1348821Y1840697D02*
Y1838457D01*
G01X1352696Y1845771D02*
X1345196D01*
Y1847637D01*
X1345571Y1848384D01*
X1346071Y1848944D01*
X1346821Y1849411D01*
X1347696Y1849784D01*
X1348946Y1849877D01*
X1350196Y1849784D01*
X1351071Y1849411D01*
X1351821Y1848944D01*
X1352321Y1848384D01*
X1352696Y1847637D01*
Y1845771D01*
G01Y1860771D02*
X1345196D01*
Y1862637D01*
X1345571Y1863384D01*
X1346071Y1863944D01*
X1346821Y1864411D01*
X1347696Y1864784D01*
X1348946Y1864877D01*
X1350196Y1864784D01*
X1351071Y1864411D01*
X1351821Y1863944D01*
X1352321Y1863384D01*
X1352696Y1862637D01*
Y1860771D01*
G01Y1868457D02*
X1345196D01*
Y1870791D01*
X1345571Y1871537D01*
X1346071Y1872004D01*
X1347071Y1872191D01*
X1348071Y1872004D01*
X1348696Y1871444D01*
X1349071Y1870791D01*
Y1868457D01*
G01Y1870791D02*
X1352696Y1872191D01*
G01X1345196Y1876704D02*
Y1878944D01*
G01Y1877824D02*
X1352696D01*
G01Y1876704D02*
Y1878944D01*
G01X1345196Y1883457D02*
X1352696D01*
Y1887191D01*
G01X1345196Y1890957D02*
X1352696D01*
Y1894691D01*
G01X1351696Y1905864D02*
X1352321Y1906611D01*
X1352696Y1907451D01*
Y1908197D01*
X1352321Y1908944D01*
X1351696Y1909504D01*
X1350821Y1909784D01*
X1349946Y1909597D01*
X1349196Y1909131D01*
X1348696Y1908291D01*
X1348446Y1907171D01*
X1347946Y1906517D01*
X1347071Y1906237D01*
X1346196Y1906424D01*
X1345571Y1906891D01*
X1345196Y1907544D01*
Y1908197D01*
X1345446Y1908851D01*
X1346071Y1909411D01*
G01X1345196Y1914204D02*
Y1916444D01*
G01Y1915324D02*
X1352696D01*
G01Y1914204D02*
Y1916444D01*
G01X1345196Y1921051D02*
Y1924597D01*
X1352696Y1921051D01*
Y1924597D01*
G01Y1932191D02*
Y1928457D01*
X1345196D01*
Y1932191D01*
G01X1348821Y1930697D02*
Y1928457D01*
G01X1352696Y1943551D02*
X1345196D01*
Y1947097D01*
G01X1348821Y1945791D02*
Y1943551D01*
G01X1352696Y1952824D02*
X1352571Y1952077D01*
X1352071Y1951424D01*
X1351321Y1950864D01*
X1350446Y1950491D01*
X1349446Y1950304D01*
X1348446D01*
X1347446Y1950491D01*
X1346571Y1950864D01*
X1345821Y1951424D01*
X1345321Y1952077D01*
X1345196Y1952824D01*
X1345321Y1953571D01*
X1345821Y1954224D01*
X1346571Y1954784D01*
X1347446Y1955157D01*
X1348446Y1955344D01*
X1349446D01*
X1350446Y1955157D01*
X1351321Y1954784D01*
X1352071Y1954224D01*
X1352571Y1953571D01*
X1352696Y1952824D01*
G01Y1958457D02*
X1345196D01*
Y1960791D01*
X1345571Y1961537D01*
X1346071Y1962004D01*
X1347071Y1962191D01*
X1348071Y1962004D01*
X1348696Y1961444D01*
X1349071Y1960791D01*
Y1958457D01*
G01Y1960791D02*
X1352696Y1962191D01*
G01X1345196Y1975324D02*
X1345446Y1974577D01*
X1346071Y1974017D01*
X1346821Y1973644D01*
X1347821Y1973364D01*
X1348946Y1973271D01*
X1350071Y1973364D01*
X1351071Y1973644D01*
X1351821Y1974017D01*
X1352446Y1974577D01*
X1352696Y1975324D01*
X1352446Y1976071D01*
X1351821Y1976631D01*
X1351071Y1977004D01*
X1350071Y1977284D01*
X1348946Y1977377D01*
X1347821Y1977284D01*
X1346821Y1977004D01*
X1346071Y1976631D01*
X1345446Y1976071D01*
X1345196Y1975324D01*
G01X1352946Y1982824D02*
X1352821Y1982637D01*
X1352571D01*
X1352446Y1982824D01*
X1352571Y1983011D01*
X1352821D01*
X1352946Y1982824D01*
G01X1351196Y1988271D02*
X1352071Y1988831D01*
X1352571Y1989577D01*
X1352696Y1990417D01*
X1352571Y1991164D01*
X1351946Y1991911D01*
X1351196Y1992377D01*
X1350446Y1992471D01*
X1349571Y1992284D01*
X1348946Y1991631D01*
X1348696Y1990977D01*
Y1990137D01*
G01Y1990977D02*
X1348321Y1991537D01*
X1347696Y1992004D01*
X1346946Y1992191D01*
X1346196Y1992004D01*
X1345571Y1991537D01*
X1345196Y1990697D01*
X1345321Y1989857D01*
X1345821Y1989017D01*
G01X1352696Y1997824D02*
X1345196D01*
X1346696Y1996704D01*
G01X1352696D02*
Y1998944D01*
G01Y2002897D02*
X1345196D01*
X1351446Y2005324D01*
X1345196Y2007751D01*
X1352696D01*
G01Y2010397D02*
X1345196D01*
X1351446Y2012824D01*
X1345196Y2015251D01*
X1352696D01*
G01Y2026051D02*
X1345196D01*
Y2029597D01*
G01X1348821Y2028291D02*
Y2026051D01*
G01X1345196Y2034204D02*
Y2036444D01*
G01Y2035324D02*
X1352696D01*
G01Y2034204D02*
Y2036444D01*
G01Y2040677D02*
X1345196D01*
X1352696Y2044971D01*
X1345196D01*
G01Y2049204D02*
Y2051444D01*
G01Y2050324D02*
X1352696D01*
G01Y2049204D02*
Y2051444D01*
G01X1351696Y2055864D02*
X1352321Y2056611D01*
X1352696Y2057451D01*
Y2058197D01*
X1352321Y2058944D01*
X1351696Y2059504D01*
X1350821Y2059784D01*
X1349946Y2059597D01*
X1349196Y2059131D01*
X1348696Y2058291D01*
X1348446Y2057171D01*
X1347946Y2056517D01*
X1347071Y2056237D01*
X1346196Y2056424D01*
X1345571Y2056891D01*
X1345196Y2057544D01*
Y2058197D01*
X1345446Y2058851D01*
X1346071Y2059411D01*
G01X1352696Y2063364D02*
X1345196D01*
G01Y2067284D02*
X1352696D01*
G01X1348946D02*
Y2063364D01*
G01X1352696Y2074691D02*
Y2070957D01*
X1345196D01*
Y2074691D01*
G01X1348821Y2073197D02*
Y2070957D01*
G01X1352696Y2078271D02*
X1345196D01*
Y2080137D01*
X1345571Y2080884D01*
X1346071Y2081444D01*
X1346821Y2081911D01*
X1347696Y2082284D01*
X1348946Y2082377D01*
X1350196Y2082284D01*
X1351071Y2081911D01*
X1351821Y2081444D01*
X1352321Y2080884D01*
X1352696Y2080137D01*
Y2078271D01*
G01Y2093457D02*
X1345196D01*
Y2095697D01*
X1345571Y2096444D01*
X1346446Y2097004D01*
X1347446Y2097191D01*
X1348446Y2097004D01*
X1349196Y2096537D01*
X1349571Y2095697D01*
Y2093457D01*
G01X1345196Y2102824D02*
X1352696D01*
G01X1345196Y2100677D02*
Y2104971D01*
G01X1352696Y2108364D02*
X1345196D01*
G01Y2112284D02*
X1352696D01*
G01X1348946D02*
Y2108364D01*
G01X1345196Y2124204D02*
Y2126444D01*
G01Y2125324D02*
X1352696D01*
G01Y2124204D02*
Y2126444D01*
G01X1351696Y2130864D02*
X1352321Y2131611D01*
X1352696Y2132451D01*
Y2133197D01*
X1352321Y2133944D01*
X1351696Y2134504D01*
X1350821Y2134784D01*
X1349946Y2134597D01*
X1349196Y2134131D01*
X1348696Y2133291D01*
X1348446Y2132171D01*
X1347946Y2131517D01*
X1347071Y2131237D01*
X1346196Y2131424D01*
X1345571Y2131891D01*
X1345196Y2132544D01*
Y2133197D01*
X1345446Y2133851D01*
X1346071Y2134411D01*
G01X1345196Y2147824D02*
X1345446Y2147077D01*
X1346071Y2146517D01*
X1346821Y2146144D01*
X1347821Y2145864D01*
X1348946Y2145771D01*
X1350071Y2145864D01*
X1351071Y2146144D01*
X1351821Y2146517D01*
X1352446Y2147077D01*
X1352696Y2147824D01*
X1352446Y2148571D01*
X1351821Y2149131D01*
X1351071Y2149504D01*
X1350071Y2149784D01*
X1348946Y2149877D01*
X1347821Y2149784D01*
X1346821Y2149504D01*
X1346071Y2149131D01*
X1345446Y2148571D01*
X1345196Y2147824D01*
G01X1352946Y2155324D02*
X1352821Y2155137D01*
X1352571D01*
X1352446Y2155324D01*
X1352571Y2155511D01*
X1352821D01*
X1352946Y2155324D01*
G01X1352696Y2163944D02*
X1345196D01*
X1350571Y2160491D01*
Y2165157D01*
G01X1352696Y2167897D02*
X1345196D01*
X1351446Y2170324D01*
X1345196Y2172751D01*
X1352696D01*
G01Y2175397D02*
X1345196D01*
X1351446Y2177824D01*
X1345196Y2180251D01*
X1352696D01*
G01Y2190397D02*
X1345196D01*
X1351446Y2192824D01*
X1345196Y2195251D01*
X1352696D01*
G01Y2202191D02*
Y2198457D01*
X1345196D01*
Y2202191D01*
G01X1348821Y2200697D02*
Y2198457D01*
G01X1345196Y2207824D02*
X1352696D01*
G01X1345196Y2205677D02*
Y2209971D01*
G01X1352696Y2213457D02*
X1345196D01*
Y2215791D01*
X1345571Y2216537D01*
X1346071Y2217004D01*
X1347071Y2217191D01*
X1348071Y2217004D01*
X1348696Y2216444D01*
X1349071Y2215791D01*
Y2213457D01*
G01Y2215791D02*
X1352696Y2217191D01*
G01X1345196Y2221704D02*
Y2223944D01*
G01Y2222824D02*
X1352696D01*
G01Y2221704D02*
Y2223944D01*
G01X1345821Y2232377D02*
X1345446Y2231817D01*
X1345196Y2231164D01*
Y2230417D01*
X1345571Y2229577D01*
X1346196Y2228924D01*
X1346946Y2228457D01*
X1348196Y2228084D01*
X1349321Y2227991D01*
X1350446Y2228177D01*
X1351196Y2228457D01*
X1351946Y2229017D01*
X1352446Y2229671D01*
X1352696Y2230324D01*
Y2230977D01*
X1352446Y2231631D01*
X1352071Y2232191D01*
X1351571Y2232657D01*
G01X1352696Y2243271D02*
X1345196D01*
Y2245137D01*
X1345571Y2245884D01*
X1346071Y2246444D01*
X1346821Y2246911D01*
X1347696Y2247284D01*
X1348946Y2247377D01*
X1350196Y2247284D01*
X1351071Y2246911D01*
X1351821Y2246444D01*
X1352321Y2245884D01*
X1352696Y2245137D01*
Y2243271D01*
G01Y2250957D02*
X1345196D01*
Y2253291D01*
X1345571Y2254037D01*
X1346071Y2254504D01*
X1347071Y2254691D01*
X1348071Y2254504D01*
X1348696Y2253944D01*
X1349071Y2253291D01*
Y2250957D01*
G01Y2253291D02*
X1352696Y2254691D01*
G01X1345196Y2259204D02*
Y2261444D01*
G01Y2260324D02*
X1352696D01*
G01Y2259204D02*
Y2261444D01*
G01X1345196Y2265957D02*
X1352696D01*
Y2269691D01*
G01X1345196Y2273457D02*
X1352696D01*
Y2277191D01*
G01X1355196Y2282357D02*
X1353946Y2281424D01*
X1352696Y2280957D01*
X1347696D01*
X1346446Y2281424D01*
X1345196Y2282357D01*
G01Y2290324D02*
X1345446Y2289577D01*
X1346071Y2289017D01*
X1346821Y2288644D01*
X1347821Y2288364D01*
X1348946Y2288271D01*
X1350071Y2288364D01*
X1351071Y2288644D01*
X1351821Y2289017D01*
X1352446Y2289577D01*
X1352696Y2290324D01*
X1352446Y2291071D01*
X1351821Y2291631D01*
X1351071Y2292004D01*
X1350071Y2292284D01*
X1348946Y2292377D01*
X1347821Y2292284D01*
X1346821Y2292004D01*
X1346071Y2291631D01*
X1345446Y2291071D01*
X1345196Y2290324D01*
G01X1352946Y2297824D02*
X1352821Y2297637D01*
X1352571D01*
X1352446Y2297824D01*
X1352571Y2298011D01*
X1352821D01*
X1352946Y2297824D01*
G01X1345196Y2305324D02*
X1345446Y2304577D01*
X1346071Y2304017D01*
X1346821Y2303644D01*
X1347821Y2303364D01*
X1348946Y2303271D01*
X1350071Y2303364D01*
X1351071Y2303644D01*
X1351821Y2304017D01*
X1352446Y2304577D01*
X1352696Y2305324D01*
X1352446Y2306071D01*
X1351821Y2306631D01*
X1351071Y2307004D01*
X1350071Y2307284D01*
X1348946Y2307377D01*
X1347821Y2307284D01*
X1346821Y2307004D01*
X1346071Y2306631D01*
X1345446Y2306071D01*
X1345196Y2305324D01*
G01X1352696Y2312824D02*
X1345196D01*
X1346696Y2311704D01*
G01X1352696D02*
Y2313944D01*
G01X1351571Y2318271D02*
X1352196Y2318831D01*
X1352571Y2319484D01*
X1352696Y2320324D01*
X1352446Y2321164D01*
X1351946Y2321817D01*
X1351071Y2322284D01*
X1350071Y2322377D01*
X1349071Y2322191D01*
X1348446Y2321724D01*
X1347946Y2321071D01*
X1347821Y2320417D01*
X1347946Y2319764D01*
X1348446Y2318924D01*
X1345196Y2319204D01*
Y2321724D01*
G01X1352696Y2327637D02*
X1351071Y2327824D01*
X1349696Y2328104D01*
X1348446Y2328477D01*
X1347071Y2328944D01*
X1345196Y2329691D01*
Y2325957D01*
G01X1346821Y2334484D02*
X1345196Y2334951D01*
G01Y2336164D02*
X1346821Y2335697D01*
G01X1355196Y2343291D02*
X1353946Y2344224D01*
X1352696Y2344691D01*
X1347696D01*
X1346446Y2344224D01*
X1345196Y2343291D01*
G01X1368161Y1457835D02*
G03I-2452J0D01*
G01X1359499Y1453504D02*
G03I-2451J0D01*
G01X1368161Y1473189D02*
G03I-2452J0D01*
G01X1359499Y1468859D02*
G03I-2451J0D01*
G01Y1499567D02*
G03I-2451J0D01*
G01X1368161Y1488544D02*
G03I-2452J0D01*
G01X1359499Y1484213D02*
G03I-2451J0D01*
G01Y1514922D02*
G03I-2451J0D01*
G01X1368161Y1503898D02*
G03I-2452J0D01*
G01Y1519252D02*
G03I-2452J0D01*
G01Y1560197D02*
G03I-2452J0D01*
G01X1359499Y1555867D02*
G03I-2451J0D01*
G01X1368161Y1575552D02*
G03I-2452J0D01*
G01X1359499Y1571221D02*
G03I-2451J0D01*
G01X1368161Y1590906D02*
G03I-2452J0D01*
G01X1359499Y1586575D02*
G03I-2451J0D01*
G01X1368161Y1606260D02*
G03I-2452J0D01*
G01X1359499Y1601930D02*
G03I-2451J0D01*
G01X1368161Y1621615D02*
G03I-2452J0D01*
G01X1359499Y1617284D02*
G03I-2451J0D01*
G01X1363628Y1702321D02*
X1356128D01*
X1362378Y1704748D01*
X1356128Y1707175D01*
X1363628D01*
G01Y1709915D02*
X1356128Y1712248D01*
X1363628Y1714581D01*
G01X1361003Y1713741D02*
Y1710755D01*
G01X1363628Y1717881D02*
X1356128D01*
Y1720215D01*
X1356503Y1720961D01*
X1357003Y1721428D01*
X1358003Y1721615D01*
X1359003Y1721428D01*
X1359628Y1720868D01*
X1360003Y1720215D01*
Y1717881D01*
G01Y1720215D02*
X1363628Y1721615D01*
G01Y1725195D02*
X1356128D01*
G01Y1728741D02*
X1360753Y1725195D01*
G01X1363628Y1729301D02*
X1358628Y1726781D01*
G01X1363878Y1734748D02*
X1363753Y1734561D01*
X1363503D01*
X1363378Y1734748D01*
X1363503Y1734935D01*
X1363753D01*
X1363878Y1734748D01*
G01X1360503D02*
X1360378Y1734561D01*
X1360128D01*
X1360003Y1734748D01*
X1360128Y1734935D01*
X1360378D01*
X1360503Y1734748D01*
G01X1363628Y1740381D02*
X1356128D01*
Y1742715D01*
X1356503Y1743461D01*
X1357003Y1743928D01*
X1358003Y1744115D01*
X1359003Y1743928D01*
X1359628Y1743368D01*
X1360003Y1742715D01*
Y1740381D01*
G01Y1742715D02*
X1363628Y1744115D01*
G01Y1751615D02*
Y1747881D01*
X1356128D01*
Y1751615D01*
G01X1359753Y1750121D02*
Y1747881D01*
G01X1356753Y1759301D02*
X1356378Y1758741D01*
X1356128Y1758088D01*
Y1757341D01*
X1356503Y1756501D01*
X1357128Y1755848D01*
X1357878Y1755381D01*
X1359128Y1755008D01*
X1360253Y1754915D01*
X1361378Y1755101D01*
X1362128Y1755381D01*
X1362878Y1755941D01*
X1363378Y1756595D01*
X1363628Y1757248D01*
Y1757901D01*
X1363378Y1758555D01*
X1363003Y1759115D01*
X1362503Y1759581D01*
G01X1363628Y1764748D02*
X1363503Y1764001D01*
X1363003Y1763348D01*
X1362253Y1762788D01*
X1361378Y1762415D01*
X1360378Y1762228D01*
X1359378D01*
X1358378Y1762415D01*
X1357503Y1762788D01*
X1356753Y1763348D01*
X1356253Y1764001D01*
X1356128Y1764748D01*
X1356253Y1765495D01*
X1356753Y1766148D01*
X1357503Y1766708D01*
X1358378Y1767081D01*
X1359378Y1767268D01*
X1360378D01*
X1361378Y1767081D01*
X1362253Y1766708D01*
X1363003Y1766148D01*
X1363503Y1765495D01*
X1363628Y1764748D01*
G01Y1769821D02*
X1356128D01*
X1362378Y1772248D01*
X1356128Y1774675D01*
X1363628D01*
G01Y1777321D02*
X1356128D01*
X1362378Y1779748D01*
X1356128Y1782175D01*
X1363628D01*
G01Y1789115D02*
Y1785381D01*
X1356128D01*
Y1789115D01*
G01X1359753Y1787621D02*
Y1785381D01*
G01X1363628Y1792601D02*
X1356128D01*
X1363628Y1796895D01*
X1356128D01*
G01X1363628Y1800195D02*
X1356128D01*
Y1802061D01*
X1356503Y1802808D01*
X1357003Y1803368D01*
X1357753Y1803835D01*
X1358628Y1804208D01*
X1359878Y1804301D01*
X1361128Y1804208D01*
X1362003Y1803835D01*
X1362753Y1803368D01*
X1363253Y1802808D01*
X1363628Y1802061D01*
Y1800195D01*
G01Y1811615D02*
Y1807881D01*
X1356128D01*
Y1811615D01*
G01X1359753Y1810121D02*
Y1807881D01*
G01X1363628Y1815195D02*
X1356128D01*
Y1817061D01*
X1356503Y1817808D01*
X1357003Y1818368D01*
X1357753Y1818835D01*
X1358628Y1819208D01*
X1359878Y1819301D01*
X1361128Y1819208D01*
X1362003Y1818835D01*
X1362753Y1818368D01*
X1363253Y1817808D01*
X1363628Y1817061D01*
Y1815195D01*
G01Y1830195D02*
X1356128D01*
Y1832061D01*
X1356503Y1832808D01*
X1357003Y1833368D01*
X1357753Y1833835D01*
X1358628Y1834208D01*
X1359878Y1834301D01*
X1361128Y1834208D01*
X1362003Y1833835D01*
X1362753Y1833368D01*
X1363253Y1832808D01*
X1363628Y1832061D01*
Y1830195D01*
G01Y1837881D02*
X1356128D01*
Y1840215D01*
X1356503Y1840961D01*
X1357003Y1841428D01*
X1358003Y1841615D01*
X1359003Y1841428D01*
X1359628Y1840868D01*
X1360003Y1840215D01*
Y1837881D01*
G01Y1840215D02*
X1363628Y1841615D01*
G01X1356128Y1846128D02*
Y1848368D01*
G01Y1847248D02*
X1363628D01*
G01Y1846128D02*
Y1848368D01*
G01X1356128Y1852881D02*
X1363628D01*
Y1856615D01*
G01X1356128Y1860381D02*
X1363628D01*
Y1864115D01*
G01X1362628Y1875288D02*
X1363253Y1876035D01*
X1363628Y1876875D01*
Y1877621D01*
X1363253Y1878368D01*
X1362628Y1878928D01*
X1361753Y1879208D01*
X1360878Y1879021D01*
X1360128Y1878555D01*
X1359628Y1877715D01*
X1359378Y1876595D01*
X1358878Y1875941D01*
X1358003Y1875661D01*
X1357128Y1875848D01*
X1356503Y1876315D01*
X1356128Y1876968D01*
Y1877621D01*
X1356378Y1878275D01*
X1357003Y1878835D01*
G01X1356128Y1883628D02*
Y1885868D01*
G01Y1884748D02*
X1363628D01*
G01Y1883628D02*
Y1885868D01*
G01X1356128Y1890475D02*
Y1894021D01*
X1363628Y1890475D01*
Y1894021D01*
G01Y1901615D02*
Y1897881D01*
X1356128D01*
Y1901615D01*
G01X1359753Y1900121D02*
Y1897881D01*
G01X1363628Y1912975D02*
X1356128D01*
Y1916521D01*
G01X1359753Y1915215D02*
Y1912975D01*
G01X1363628Y1922248D02*
X1363503Y1921501D01*
X1363003Y1920848D01*
X1362253Y1920288D01*
X1361378Y1919915D01*
X1360378Y1919728D01*
X1359378D01*
X1358378Y1919915D01*
X1357503Y1920288D01*
X1356753Y1920848D01*
X1356253Y1921501D01*
X1356128Y1922248D01*
X1356253Y1922995D01*
X1356753Y1923648D01*
X1357503Y1924208D01*
X1358378Y1924581D01*
X1359378Y1924768D01*
X1360378D01*
X1361378Y1924581D01*
X1362253Y1924208D01*
X1363003Y1923648D01*
X1363503Y1922995D01*
X1363628Y1922248D01*
G01Y1927881D02*
X1356128D01*
Y1930215D01*
X1356503Y1930961D01*
X1357003Y1931428D01*
X1358003Y1931615D01*
X1359003Y1931428D01*
X1359628Y1930868D01*
X1360003Y1930215D01*
Y1927881D01*
G01Y1930215D02*
X1363628Y1931615D01*
G01X1356128Y1944748D02*
X1356378Y1944001D01*
X1357003Y1943441D01*
X1357753Y1943068D01*
X1358753Y1942788D01*
X1359878Y1942695D01*
X1361003Y1942788D01*
X1362003Y1943068D01*
X1362753Y1943441D01*
X1363378Y1944001D01*
X1363628Y1944748D01*
X1363378Y1945495D01*
X1362753Y1946055D01*
X1362003Y1946428D01*
X1361003Y1946708D01*
X1359878Y1946801D01*
X1358753Y1946708D01*
X1357753Y1946428D01*
X1357003Y1946055D01*
X1356378Y1945495D01*
X1356128Y1944748D01*
G01X1363878Y1952248D02*
X1363753Y1952061D01*
X1363503D01*
X1363378Y1952248D01*
X1363503Y1952435D01*
X1363753D01*
X1363878Y1952248D01*
G01X1362503Y1957695D02*
X1363128Y1958255D01*
X1363503Y1958908D01*
X1363628Y1959748D01*
X1363378Y1960588D01*
X1362878Y1961241D01*
X1362003Y1961708D01*
X1361003Y1961801D01*
X1360003Y1961615D01*
X1359378Y1961148D01*
X1358878Y1960495D01*
X1358753Y1959841D01*
X1358878Y1959188D01*
X1359378Y1958348D01*
X1356128Y1958628D01*
Y1961148D01*
G01X1363628Y1964821D02*
X1356128D01*
X1362378Y1967248D01*
X1356128Y1969675D01*
X1363628D01*
G01Y1972321D02*
X1356128D01*
X1362378Y1974748D01*
X1356128Y1977175D01*
X1363628D01*
G01Y1987975D02*
X1356128D01*
Y1991521D01*
G01X1359753Y1990215D02*
Y1987975D01*
G01X1356128Y1996128D02*
Y1998368D01*
G01Y1997248D02*
X1363628D01*
G01Y1996128D02*
Y1998368D01*
G01Y2002601D02*
X1356128D01*
X1363628Y2006895D01*
X1356128D01*
G01Y2011128D02*
Y2013368D01*
G01Y2012248D02*
X1363628D01*
G01Y2011128D02*
Y2013368D01*
G01X1362628Y2017788D02*
X1363253Y2018535D01*
X1363628Y2019375D01*
Y2020121D01*
X1363253Y2020868D01*
X1362628Y2021428D01*
X1361753Y2021708D01*
X1360878Y2021521D01*
X1360128Y2021055D01*
X1359628Y2020215D01*
X1359378Y2019095D01*
X1358878Y2018441D01*
X1358003Y2018161D01*
X1357128Y2018348D01*
X1356503Y2018815D01*
X1356128Y2019468D01*
Y2020121D01*
X1356378Y2020775D01*
X1357003Y2021335D01*
G01X1363628Y2025288D02*
X1356128D01*
G01Y2029208D02*
X1363628D01*
G01X1359878D02*
Y2025288D01*
G01X1363628Y2036615D02*
Y2032881D01*
X1356128D01*
Y2036615D01*
G01X1359753Y2035121D02*
Y2032881D01*
G01X1363628Y2040195D02*
X1356128D01*
Y2042061D01*
X1356503Y2042808D01*
X1357003Y2043368D01*
X1357753Y2043835D01*
X1358628Y2044208D01*
X1359878Y2044301D01*
X1361128Y2044208D01*
X1362003Y2043835D01*
X1362753Y2043368D01*
X1363253Y2042808D01*
X1363628Y2042061D01*
Y2040195D01*
G01Y2055381D02*
X1356128D01*
Y2057621D01*
X1356503Y2058368D01*
X1357378Y2058928D01*
X1358378Y2059115D01*
X1359378Y2058928D01*
X1360128Y2058461D01*
X1360503Y2057621D01*
Y2055381D01*
G01X1356128Y2064748D02*
X1363628D01*
G01X1356128Y2062601D02*
Y2066895D01*
G01X1363628Y2070288D02*
X1356128D01*
G01Y2074208D02*
X1363628D01*
G01X1359878D02*
Y2070288D01*
G01X1356128Y2086128D02*
Y2088368D01*
G01Y2087248D02*
X1363628D01*
G01Y2086128D02*
Y2088368D01*
G01X1362628Y2092788D02*
X1363253Y2093535D01*
X1363628Y2094375D01*
Y2095121D01*
X1363253Y2095868D01*
X1362628Y2096428D01*
X1361753Y2096708D01*
X1360878Y2096521D01*
X1360128Y2096055D01*
X1359628Y2095215D01*
X1359378Y2094095D01*
X1358878Y2093441D01*
X1358003Y2093161D01*
X1357128Y2093348D01*
X1356503Y2093815D01*
X1356128Y2094468D01*
Y2095121D01*
X1356378Y2095775D01*
X1357003Y2096335D01*
G01X1356128Y2109748D02*
X1356378Y2109001D01*
X1357003Y2108441D01*
X1357753Y2108068D01*
X1358753Y2107788D01*
X1359878Y2107695D01*
X1361003Y2107788D01*
X1362003Y2108068D01*
X1362753Y2108441D01*
X1363378Y2109001D01*
X1363628Y2109748D01*
X1363378Y2110495D01*
X1362753Y2111055D01*
X1362003Y2111428D01*
X1361003Y2111708D01*
X1359878Y2111801D01*
X1358753Y2111708D01*
X1357753Y2111428D01*
X1357003Y2111055D01*
X1356378Y2110495D01*
X1356128Y2109748D01*
G01X1363878Y2117248D02*
X1363753Y2117061D01*
X1363503D01*
X1363378Y2117248D01*
X1363503Y2117435D01*
X1363753D01*
X1363878Y2117248D01*
G01X1360503Y2122975D02*
X1359628Y2123628D01*
X1359128Y2124188D01*
X1358878Y2124935D01*
X1359128Y2125588D01*
X1359628Y2126055D01*
X1360378Y2126428D01*
X1361253Y2126521D01*
X1362003Y2126428D01*
X1362753Y2126055D01*
X1363378Y2125495D01*
X1363628Y2124841D01*
X1363378Y2124095D01*
X1362628Y2123441D01*
X1361503Y2123068D01*
X1360253Y2122975D01*
X1358628Y2123161D01*
X1357753Y2123441D01*
X1356878Y2123908D01*
X1356253Y2124561D01*
X1356128Y2125215D01*
X1356378Y2125868D01*
X1357003Y2126335D01*
G01X1363628Y2129821D02*
X1356128D01*
X1362378Y2132248D01*
X1356128Y2134675D01*
X1363628D01*
G01Y2137321D02*
X1356128D01*
X1362378Y2139748D01*
X1356128Y2142175D01*
X1363628D01*
G01Y2152321D02*
X1356128D01*
X1362378Y2154748D01*
X1356128Y2157175D01*
X1363628D01*
G01Y2164115D02*
Y2160381D01*
X1356128D01*
Y2164115D01*
G01X1359753Y2162621D02*
Y2160381D01*
G01X1356128Y2169748D02*
X1363628D01*
G01X1356128Y2167601D02*
Y2171895D01*
G01X1363628Y2175381D02*
X1356128D01*
Y2177715D01*
X1356503Y2178461D01*
X1357003Y2178928D01*
X1358003Y2179115D01*
X1359003Y2178928D01*
X1359628Y2178368D01*
X1360003Y2177715D01*
Y2175381D01*
G01Y2177715D02*
X1363628Y2179115D01*
G01X1356128Y2183628D02*
Y2185868D01*
G01Y2184748D02*
X1363628D01*
G01Y2183628D02*
Y2185868D01*
G01X1356753Y2194301D02*
X1356378Y2193741D01*
X1356128Y2193088D01*
Y2192341D01*
X1356503Y2191501D01*
X1357128Y2190848D01*
X1357878Y2190381D01*
X1359128Y2190008D01*
X1360253Y2189915D01*
X1361378Y2190101D01*
X1362128Y2190381D01*
X1362878Y2190941D01*
X1363378Y2191595D01*
X1363628Y2192248D01*
Y2192901D01*
X1363378Y2193555D01*
X1363003Y2194115D01*
X1362503Y2194581D01*
G01X1363628Y2205195D02*
X1356128D01*
Y2207061D01*
X1356503Y2207808D01*
X1357003Y2208368D01*
X1357753Y2208835D01*
X1358628Y2209208D01*
X1359878Y2209301D01*
X1361128Y2209208D01*
X1362003Y2208835D01*
X1362753Y2208368D01*
X1363253Y2207808D01*
X1363628Y2207061D01*
Y2205195D01*
G01Y2212881D02*
X1356128D01*
Y2215215D01*
X1356503Y2215961D01*
X1357003Y2216428D01*
X1358003Y2216615D01*
X1359003Y2216428D01*
X1359628Y2215868D01*
X1360003Y2215215D01*
Y2212881D01*
G01Y2215215D02*
X1363628Y2216615D01*
G01X1356128Y2221128D02*
Y2223368D01*
G01Y2222248D02*
X1363628D01*
G01Y2221128D02*
Y2223368D01*
G01X1356128Y2227881D02*
X1363628D01*
Y2231615D01*
G01X1356128Y2235381D02*
X1363628D01*
Y2239115D01*
G01X1366128Y2244281D02*
X1364878Y2243348D01*
X1363628Y2242881D01*
X1358628D01*
X1357378Y2243348D01*
X1356128Y2244281D01*
G01Y2252248D02*
X1356378Y2251501D01*
X1357003Y2250941D01*
X1357753Y2250568D01*
X1358753Y2250288D01*
X1359878Y2250195D01*
X1361003Y2250288D01*
X1362003Y2250568D01*
X1362753Y2250941D01*
X1363378Y2251501D01*
X1363628Y2252248D01*
X1363378Y2252995D01*
X1362753Y2253555D01*
X1362003Y2253928D01*
X1361003Y2254208D01*
X1359878Y2254301D01*
X1358753Y2254208D01*
X1357753Y2253928D01*
X1357003Y2253555D01*
X1356378Y2252995D01*
X1356128Y2252248D01*
G01X1363878Y2259748D02*
X1363753Y2259561D01*
X1363503D01*
X1363378Y2259748D01*
X1363503Y2259935D01*
X1363753D01*
X1363878Y2259748D01*
G01X1356128Y2267248D02*
X1356378Y2266501D01*
X1357003Y2265941D01*
X1357753Y2265568D01*
X1358753Y2265288D01*
X1359878Y2265195D01*
X1361003Y2265288D01*
X1362003Y2265568D01*
X1362753Y2265941D01*
X1363378Y2266501D01*
X1363628Y2267248D01*
X1363378Y2267995D01*
X1362753Y2268555D01*
X1362003Y2268928D01*
X1361003Y2269208D01*
X1359878Y2269301D01*
X1358753Y2269208D01*
X1357753Y2268928D01*
X1357003Y2268555D01*
X1356378Y2267995D01*
X1356128Y2267248D01*
G01X1357378Y2272975D02*
X1356628Y2273535D01*
X1356253Y2274188D01*
X1356128Y2274935D01*
X1356378Y2275868D01*
X1357003Y2276521D01*
X1357753Y2276708D01*
X1358503Y2276615D01*
X1359128Y2276241D01*
X1360378Y2274375D01*
X1361253Y2273535D01*
X1362503Y2272975D01*
X1363628Y2272788D01*
Y2276708D01*
G01X1362128Y2280195D02*
X1363003Y2280755D01*
X1363503Y2281501D01*
X1363628Y2282341D01*
X1363503Y2283088D01*
X1362878Y2283835D01*
X1362128Y2284301D01*
X1361378Y2284395D01*
X1360503Y2284208D01*
X1359878Y2283555D01*
X1359628Y2282901D01*
Y2282061D01*
G01Y2282901D02*
X1359253Y2283461D01*
X1358628Y2283928D01*
X1357878Y2284115D01*
X1357128Y2283928D01*
X1356503Y2283461D01*
X1356128Y2282621D01*
X1356253Y2281781D01*
X1356753Y2280941D01*
G01X1360503Y2287975D02*
X1359628Y2288628D01*
X1359128Y2289188D01*
X1358878Y2289935D01*
X1359128Y2290588D01*
X1359628Y2291055D01*
X1360378Y2291428D01*
X1361253Y2291521D01*
X1362003Y2291428D01*
X1362753Y2291055D01*
X1363378Y2290495D01*
X1363628Y2289841D01*
X1363378Y2289095D01*
X1362628Y2288441D01*
X1361503Y2288068D01*
X1360253Y2287975D01*
X1358628Y2288161D01*
X1357753Y2288441D01*
X1356878Y2288908D01*
X1356253Y2289561D01*
X1356128Y2290215D01*
X1356378Y2290868D01*
X1357003Y2291335D01*
G01X1357753Y2296408D02*
X1356128Y2296875D01*
G01Y2298088D02*
X1357753Y2297621D01*
G01X1366128Y2305215D02*
X1364878Y2306148D01*
X1363628Y2306615D01*
X1358628D01*
X1357378Y2306148D01*
X1356128Y2305215D01*
G01X1385484Y1457835D02*
G03I-2452J0D01*
G01X1376822Y1453504D02*
G03I-2452J0D01*
G01X1385484Y1473189D02*
G03I-2452J0D01*
G01X1376822Y1468859D02*
G03I-2452J0D01*
G01Y1499567D02*
G03I-2452J0D01*
G01X1385484Y1488544D02*
G03I-2452J0D01*
G01X1376822Y1484213D02*
G03I-2452J0D01*
G01Y1514922D02*
G03I-2452J0D01*
G01X1385484Y1503898D02*
G03I-2452J0D01*
G01Y1519252D02*
G03I-2452J0D01*
G01X1385483Y1560197D02*
G03I-2451J0D01*
G01X1376822Y1555867D02*
G03I-2452J0D01*
G01X1385484Y1575552D02*
G03I-2452J0D01*
G01X1376822Y1571221D02*
G03I-2452J0D01*
G01X1385484Y1590906D02*
G03I-2452J0D01*
G01X1376822Y1586575D02*
G03I-2452J0D01*
G01X1385483Y1606260D02*
G03I-2451J0D01*
G01X1376822Y1601930D02*
G03I-2452J0D01*
G01X1385484Y1621615D02*
G03I-2452J0D01*
G01X1376822Y1617284D02*
G03I-2452J0D01*
G01X1480758Y1453504D02*
G03I-2451J0D01*
G01X1480759Y1468859D02*
G03I-2452J0D01*
G01X1480758Y1499567D02*
G03I-2451J0D01*
G01X1480759Y1484213D02*
G03I-2452J0D01*
G01Y1514922D02*
G03I-2452J0D01*
G01Y1555867D02*
G03I-2452J0D01*
G01Y1571221D02*
G03I-2452J0D01*
G01Y1586575D02*
G03I-2452J0D01*
G01Y1601930D02*
G03I-2452J0D01*
G01Y1617284D02*
G03I-2452J0D01*
G01X1494241Y-442724D02*
X1481741D01*
X1484241Y-444584D01*
G01X1494241D02*
Y-440864D01*
G01Y-428464D02*
X1481741D01*
X1490699Y-434199D01*
Y-426449D01*
G01X1494241Y-417924D02*
X1494033Y-416839D01*
X1493408Y-415599D01*
X1492366Y-414824D01*
X1490908Y-414514D01*
X1489450Y-414824D01*
X1488199Y-415754D01*
X1487574Y-417149D01*
Y-418699D01*
X1487158Y-419629D01*
X1486116Y-420404D01*
X1484658Y-420714D01*
X1483199Y-420249D01*
X1482158Y-419164D01*
X1481741Y-417924D01*
X1482158Y-416684D01*
X1483199Y-415599D01*
X1484658Y-415134D01*
X1486116Y-415444D01*
X1487158Y-416219D01*
X1487574Y-417149D01*
Y-418699D01*
X1488199Y-420094D01*
X1489450Y-421024D01*
X1490908Y-421334D01*
X1492366Y-421024D01*
X1493408Y-420249D01*
X1494033Y-419009D01*
X1494241Y-417924D01*
G01Y-405834D02*
X1491533Y-405524D01*
X1489241Y-405059D01*
X1487158Y-404439D01*
X1484866Y-403664D01*
X1481741Y-402424D01*
Y-408624D01*
G01X1492783Y-395759D02*
X1493824Y-394674D01*
X1494241Y-393434D01*
X1493824Y-392194D01*
X1492575Y-391109D01*
X1490699Y-390334D01*
X1488824Y-390024D01*
X1486533D01*
X1484658Y-390334D01*
X1482991Y-391109D01*
X1482158Y-392039D01*
X1481741Y-393124D01*
X1482158Y-394364D01*
X1482991Y-395294D01*
X1484241Y-395914D01*
X1485908Y-396224D01*
X1487366Y-395914D01*
X1488824Y-395139D01*
X1489658Y-394209D01*
X1489866Y-393124D01*
X1489450Y-391884D01*
X1488408Y-390954D01*
X1486533Y-390024D01*
G01X1494658Y-380724D02*
X1494449Y-381034D01*
X1494033D01*
X1493824Y-380724D01*
X1494033Y-380414D01*
X1494449D01*
X1494658Y-380724D01*
G01X1492783Y-370959D02*
X1493824Y-369874D01*
X1494241Y-368634D01*
X1493824Y-367394D01*
X1492575Y-366309D01*
X1490699Y-365534D01*
X1488824Y-365224D01*
X1486533D01*
X1484658Y-365534D01*
X1482991Y-366309D01*
X1482158Y-367239D01*
X1481741Y-368324D01*
X1482158Y-369564D01*
X1482991Y-370494D01*
X1484241Y-371114D01*
X1485908Y-371424D01*
X1487366Y-371114D01*
X1488824Y-370339D01*
X1489658Y-369409D01*
X1489866Y-368324D01*
X1489450Y-367084D01*
X1488408Y-366154D01*
X1486533Y-365224D01*
G01X1494241Y-355924D02*
X1481741D01*
X1484241Y-357784D01*
G01X1494241D02*
Y-354064D01*
G01X1491741Y-324734D02*
X1493200Y-323804D01*
X1494033Y-322564D01*
X1494241Y-321169D01*
X1494033Y-319929D01*
X1492991Y-318689D01*
X1491741Y-317914D01*
X1490491Y-317759D01*
X1489033Y-318069D01*
X1487991Y-319154D01*
X1487574Y-320239D01*
Y-321634D01*
G01Y-320239D02*
X1486949Y-319309D01*
X1485908Y-318534D01*
X1484658Y-318224D01*
X1483408Y-318534D01*
X1482366Y-319309D01*
X1481741Y-320704D01*
X1481949Y-322099D01*
X1482783Y-323494D01*
G01X1494241Y-309234D02*
X1491533Y-308924D01*
X1489241Y-308459D01*
X1487158Y-307839D01*
X1484866Y-307064D01*
X1481741Y-305824D01*
Y-312024D01*
G01X1494241Y-296834D02*
X1491533Y-296524D01*
X1489241Y-296059D01*
X1487158Y-295439D01*
X1484866Y-294664D01*
X1481741Y-293424D01*
Y-299624D01*
G01X1494658Y-284124D02*
X1494449Y-284434D01*
X1494033D01*
X1493824Y-284124D01*
X1494033Y-283814D01*
X1494449D01*
X1494658Y-284124D01*
G01X1492783Y-274359D02*
X1493824Y-273274D01*
X1494241Y-272034D01*
X1493824Y-270794D01*
X1492575Y-269709D01*
X1490699Y-268934D01*
X1488824Y-268624D01*
X1486533D01*
X1484658Y-268934D01*
X1482991Y-269709D01*
X1482158Y-270639D01*
X1481741Y-271724D01*
X1482158Y-272964D01*
X1482991Y-273894D01*
X1484241Y-274514D01*
X1485908Y-274824D01*
X1487366Y-274514D01*
X1488824Y-273739D01*
X1489658Y-272809D01*
X1489866Y-271724D01*
X1489450Y-270484D01*
X1488408Y-269554D01*
X1486533Y-268624D01*
G01X1492366Y-262734D02*
X1493408Y-261804D01*
X1494033Y-260719D01*
X1494241Y-259324D01*
X1493824Y-257929D01*
X1492991Y-256844D01*
X1491533Y-256069D01*
X1489866Y-255914D01*
X1488199Y-256224D01*
X1487158Y-256999D01*
X1486324Y-258084D01*
X1486116Y-259169D01*
X1486324Y-260254D01*
X1487158Y-261649D01*
X1481741Y-261184D01*
Y-256999D01*
G01X1498081Y1453504D02*
G03I-2451J0D01*
G01X1489420Y1457835D02*
G03I-2452J0D01*
G01X1498082Y1468859D02*
G03I-2452J0D01*
G01X1489420Y1473189D02*
G03I-2452J0D01*
G01X1498081Y1499567D02*
G03I-2451J0D01*
G01X1498082Y1484213D02*
G03I-2452J0D01*
G01X1489420Y1488544D02*
G03I-2452J0D01*
G01X1498082Y1514922D02*
G03I-2452J0D01*
G01X1489420Y1503898D02*
G03I-2452J0D01*
G01Y1519252D02*
G03I-2452J0D01*
G01X1498082Y1555867D02*
G03I-2452J0D01*
G01X1489420Y1560197D02*
G03I-2452J0D01*
G01X1498082Y1571221D02*
G03I-2452J0D01*
G01X1489420Y1575552D02*
G03I-2452J0D01*
G01X1498082Y1586575D02*
G03I-2452J0D01*
G01X1489420Y1590906D02*
G03I-2452J0D01*
G01X1498082Y1601930D02*
G03I-2452J0D01*
G01X1489420Y1606260D02*
G03I-2452J0D01*
G01X1498082Y1617284D02*
G03I-2452J0D01*
G01X1489420Y1621615D02*
G03I-2452J0D01*
G01X1515404Y1453504D02*
G03I-2451J0D01*
G01X1506743Y1457835D02*
G03I-2452J0D01*
G01X1515405Y1468859D02*
G03I-2452J0D01*
G01X1506743Y1473189D02*
G03I-2452J0D01*
G01X1515404Y1499567D02*
G03I-2451J0D01*
G01X1515405Y1484213D02*
G03I-2452J0D01*
G01X1506743Y1488544D02*
G03I-2452J0D01*
G01X1515405Y1514922D02*
G03I-2452J0D01*
G01X1506743Y1503898D02*
G03I-2452J0D01*
G01Y1519252D02*
G03I-2452J0D01*
G01X1515405Y1555867D02*
G03I-2452J0D01*
G01X1506743Y1560197D02*
G03I-2452J0D01*
G01X1515405Y1571221D02*
G03I-2452J0D01*
G01X1506743Y1575552D02*
G03I-2452J0D01*
G01X1515404Y1586575D02*
G03I-2451J0D01*
G01X1506743Y1590906D02*
G03I-2452J0D01*
G01X1515405Y1601930D02*
G03I-2452J0D01*
G01X1506743Y1606260D02*
G03I-2452J0D01*
G01X1515405Y1617284D02*
G03I-2452J0D01*
G01X1506743Y1621615D02*
G03I-2452J0D01*
G01X1532727Y1453504D02*
G03I-2452J0D01*
G01X1524066Y1457835D02*
G03I-2452J0D01*
G01X1532727Y1468859D02*
G03I-2452J0D01*
G01X1524066Y1473189D02*
G03I-2452J0D01*
G01X1532727Y1499567D02*
G03I-2452J0D01*
G01Y1484213D02*
G03I-2452J0D01*
G01X1524066Y1488544D02*
G03I-2452J0D01*
G01X1532727Y1514922D02*
G03I-2452J0D01*
G01X1524066Y1503898D02*
G03I-2452J0D01*
G01Y1519252D02*
G03I-2452J0D01*
G01X1532727Y1555867D02*
G03I-2452J0D01*
G01X1524066Y1560197D02*
G03I-2452J0D01*
G01X1532727Y1571221D02*
G03I-2452J0D01*
G01X1524066Y1575552D02*
G03I-2452J0D01*
G01X1532727Y1586575D02*
G03I-2452J0D01*
G01X1524066Y1590906D02*
G03I-2452J0D01*
G01X1532727Y1601930D02*
G03I-2452J0D01*
G01X1524066Y1606260D02*
G03I-2452J0D01*
G01X1532727Y1617284D02*
G03I-2452J0D01*
G01X1524066Y1621615D02*
G03I-2452J0D01*
G01X1524157Y1701450D02*
X1516657D01*
X1524157Y1705744D01*
X1516657D01*
G01X1524157Y1711097D02*
X1524032Y1710350D01*
X1523532Y1709697D01*
X1522782Y1709137D01*
X1521907Y1708764D01*
X1520907Y1708577D01*
X1519907D01*
X1518907Y1708764D01*
X1518032Y1709137D01*
X1517282Y1709697D01*
X1516782Y1710350D01*
X1516657Y1711097D01*
X1516782Y1711844D01*
X1517282Y1712497D01*
X1518032Y1713057D01*
X1518907Y1713430D01*
X1519907Y1713617D01*
X1520907D01*
X1521907Y1713430D01*
X1522782Y1713057D01*
X1523532Y1712497D01*
X1524032Y1711844D01*
X1524157Y1711097D01*
G01Y1716450D02*
X1516657D01*
X1524157Y1720744D01*
X1516657D01*
G01X1521657Y1724884D02*
Y1727310D01*
G01X1524157Y1731170D02*
X1516657D01*
X1522907Y1733597D01*
X1516657Y1736024D01*
X1524157D01*
G01Y1738764D02*
X1516657Y1741097D01*
X1524157Y1743430D01*
G01X1521532Y1742590D02*
Y1739604D01*
G01X1524157Y1746730D02*
X1516657D01*
Y1749064D01*
X1517032Y1749810D01*
X1517532Y1750277D01*
X1518532Y1750464D01*
X1519532Y1750277D01*
X1520157Y1749717D01*
X1520532Y1749064D01*
Y1746730D01*
G01Y1749064D02*
X1524157Y1750464D01*
G01Y1754044D02*
X1516657D01*
G01Y1757590D02*
X1521282Y1754044D01*
G01X1524157Y1758150D02*
X1519157Y1755630D01*
G01X1524407Y1763597D02*
X1524282Y1763410D01*
X1524032D01*
X1523907Y1763597D01*
X1524032Y1763784D01*
X1524282D01*
X1524407Y1763597D01*
G01X1521032D02*
X1520907Y1763410D01*
X1520657D01*
X1520532Y1763597D01*
X1520657Y1763784D01*
X1520907D01*
X1521032Y1763597D01*
G01X1524157Y1769230D02*
X1516657D01*
Y1771564D01*
X1517032Y1772310D01*
X1517532Y1772777D01*
X1518532Y1772964D01*
X1519532Y1772777D01*
X1520157Y1772217D01*
X1520532Y1771564D01*
Y1769230D01*
G01Y1771564D02*
X1524157Y1772964D01*
G01Y1780464D02*
Y1776730D01*
X1516657D01*
Y1780464D01*
G01X1520282Y1778970D02*
Y1776730D01*
G01X1517282Y1788150D02*
X1516907Y1787590D01*
X1516657Y1786937D01*
Y1786190D01*
X1517032Y1785350D01*
X1517657Y1784697D01*
X1518407Y1784230D01*
X1519657Y1783857D01*
X1520782Y1783764D01*
X1521907Y1783950D01*
X1522657Y1784230D01*
X1523407Y1784790D01*
X1523907Y1785444D01*
X1524157Y1786097D01*
Y1786750D01*
X1523907Y1787404D01*
X1523532Y1787964D01*
X1523032Y1788430D01*
G01X1524157Y1793597D02*
X1524032Y1792850D01*
X1523532Y1792197D01*
X1522782Y1791637D01*
X1521907Y1791264D01*
X1520907Y1791077D01*
X1519907D01*
X1518907Y1791264D01*
X1518032Y1791637D01*
X1517282Y1792197D01*
X1516782Y1792850D01*
X1516657Y1793597D01*
X1516782Y1794344D01*
X1517282Y1794997D01*
X1518032Y1795557D01*
X1518907Y1795930D01*
X1519907Y1796117D01*
X1520907D01*
X1521907Y1795930D01*
X1522782Y1795557D01*
X1523532Y1794997D01*
X1524032Y1794344D01*
X1524157Y1793597D01*
G01Y1798670D02*
X1516657D01*
X1522907Y1801097D01*
X1516657Y1803524D01*
X1524157D01*
G01Y1806170D02*
X1516657D01*
X1522907Y1808597D01*
X1516657Y1811024D01*
X1524157D01*
G01Y1817964D02*
Y1814230D01*
X1516657D01*
Y1817964D01*
G01X1520282Y1816470D02*
Y1814230D01*
G01X1524157Y1821450D02*
X1516657D01*
X1524157Y1825744D01*
X1516657D01*
G01X1524157Y1829044D02*
X1516657D01*
Y1830910D01*
X1517032Y1831657D01*
X1517532Y1832217D01*
X1518282Y1832684D01*
X1519157Y1833057D01*
X1520407Y1833150D01*
X1521657Y1833057D01*
X1522532Y1832684D01*
X1523282Y1832217D01*
X1523782Y1831657D01*
X1524157Y1830910D01*
Y1829044D01*
G01Y1840464D02*
Y1836730D01*
X1516657D01*
Y1840464D01*
G01X1520282Y1838970D02*
Y1836730D01*
G01X1524157Y1844044D02*
X1516657D01*
Y1845910D01*
X1517032Y1846657D01*
X1517532Y1847217D01*
X1518282Y1847684D01*
X1519157Y1848057D01*
X1520407Y1848150D01*
X1521657Y1848057D01*
X1522532Y1847684D01*
X1523282Y1847217D01*
X1523782Y1846657D01*
X1524157Y1845910D01*
Y1844044D01*
G01Y1859044D02*
X1516657D01*
Y1860910D01*
X1517032Y1861657D01*
X1517532Y1862217D01*
X1518282Y1862684D01*
X1519157Y1863057D01*
X1520407Y1863150D01*
X1521657Y1863057D01*
X1522532Y1862684D01*
X1523282Y1862217D01*
X1523782Y1861657D01*
X1524157Y1860910D01*
Y1859044D01*
G01Y1866730D02*
X1516657D01*
Y1869064D01*
X1517032Y1869810D01*
X1517532Y1870277D01*
X1518532Y1870464D01*
X1519532Y1870277D01*
X1520157Y1869717D01*
X1520532Y1869064D01*
Y1866730D01*
G01Y1869064D02*
X1524157Y1870464D01*
G01X1516657Y1874977D02*
Y1877217D01*
G01Y1876097D02*
X1524157D01*
G01Y1874977D02*
Y1877217D01*
G01X1516657Y1881730D02*
X1524157D01*
Y1885464D01*
G01X1516657Y1889230D02*
X1524157D01*
Y1892964D01*
G01X1523157Y1904137D02*
X1523782Y1904884D01*
X1524157Y1905724D01*
Y1906470D01*
X1523782Y1907217D01*
X1523157Y1907777D01*
X1522282Y1908057D01*
X1521407Y1907870D01*
X1520657Y1907404D01*
X1520157Y1906564D01*
X1519907Y1905444D01*
X1519407Y1904790D01*
X1518532Y1904510D01*
X1517657Y1904697D01*
X1517032Y1905164D01*
X1516657Y1905817D01*
Y1906470D01*
X1516907Y1907124D01*
X1517532Y1907684D01*
G01X1516657Y1912477D02*
Y1914717D01*
G01Y1913597D02*
X1524157D01*
G01Y1912477D02*
Y1914717D01*
G01X1516657Y1919324D02*
Y1922870D01*
X1524157Y1919324D01*
Y1922870D01*
G01Y1930464D02*
Y1926730D01*
X1516657D01*
Y1930464D01*
G01X1520282Y1928970D02*
Y1926730D01*
G01X1524157Y1941824D02*
X1516657D01*
Y1945370D01*
G01X1520282Y1944064D02*
Y1941824D01*
G01X1524157Y1951097D02*
X1524032Y1950350D01*
X1523532Y1949697D01*
X1522782Y1949137D01*
X1521907Y1948764D01*
X1520907Y1948577D01*
X1519907D01*
X1518907Y1948764D01*
X1518032Y1949137D01*
X1517282Y1949697D01*
X1516782Y1950350D01*
X1516657Y1951097D01*
X1516782Y1951844D01*
X1517282Y1952497D01*
X1518032Y1953057D01*
X1518907Y1953430D01*
X1519907Y1953617D01*
X1520907D01*
X1521907Y1953430D01*
X1522782Y1953057D01*
X1523532Y1952497D01*
X1524032Y1951844D01*
X1524157Y1951097D01*
G01Y1956730D02*
X1516657D01*
Y1959064D01*
X1517032Y1959810D01*
X1517532Y1960277D01*
X1518532Y1960464D01*
X1519532Y1960277D01*
X1520157Y1959717D01*
X1520532Y1959064D01*
Y1956730D01*
G01Y1959064D02*
X1524157Y1960464D01*
G01X1516657Y1973597D02*
X1516907Y1972850D01*
X1517532Y1972290D01*
X1518282Y1971917D01*
X1519282Y1971637D01*
X1520407Y1971544D01*
X1521532Y1971637D01*
X1522532Y1971917D01*
X1523282Y1972290D01*
X1523907Y1972850D01*
X1524157Y1973597D01*
X1523907Y1974344D01*
X1523282Y1974904D01*
X1522532Y1975277D01*
X1521532Y1975557D01*
X1520407Y1975650D01*
X1519282Y1975557D01*
X1518282Y1975277D01*
X1517532Y1974904D01*
X1516907Y1974344D01*
X1516657Y1973597D01*
G01X1524407Y1981097D02*
X1524282Y1980910D01*
X1524032D01*
X1523907Y1981097D01*
X1524032Y1981284D01*
X1524282D01*
X1524407Y1981097D01*
G01X1522657Y1986544D02*
X1523532Y1987104D01*
X1524032Y1987850D01*
X1524157Y1988690D01*
X1524032Y1989437D01*
X1523407Y1990184D01*
X1522657Y1990650D01*
X1521907Y1990744D01*
X1521032Y1990557D01*
X1520407Y1989904D01*
X1520157Y1989250D01*
Y1988410D01*
G01Y1989250D02*
X1519782Y1989810D01*
X1519157Y1990277D01*
X1518407Y1990464D01*
X1517657Y1990277D01*
X1517032Y1989810D01*
X1516657Y1988970D01*
X1516782Y1988130D01*
X1517282Y1987290D01*
G01X1524157Y1996097D02*
X1516657D01*
X1518157Y1994977D01*
G01X1524157D02*
Y1997217D01*
G01Y2001170D02*
X1516657D01*
X1522907Y2003597D01*
X1516657Y2006024D01*
X1524157D01*
G01Y2008670D02*
X1516657D01*
X1522907Y2011097D01*
X1516657Y2013524D01*
X1524157D01*
G01Y2024324D02*
X1516657D01*
Y2027870D01*
G01X1520282Y2026564D02*
Y2024324D01*
G01X1516657Y2032477D02*
Y2034717D01*
G01Y2033597D02*
X1524157D01*
G01Y2032477D02*
Y2034717D01*
G01Y2038950D02*
X1516657D01*
X1524157Y2043244D01*
X1516657D01*
G01Y2047477D02*
Y2049717D01*
G01Y2048597D02*
X1524157D01*
G01Y2047477D02*
Y2049717D01*
G01X1523157Y2054137D02*
X1523782Y2054884D01*
X1524157Y2055724D01*
Y2056470D01*
X1523782Y2057217D01*
X1523157Y2057777D01*
X1522282Y2058057D01*
X1521407Y2057870D01*
X1520657Y2057404D01*
X1520157Y2056564D01*
X1519907Y2055444D01*
X1519407Y2054790D01*
X1518532Y2054510D01*
X1517657Y2054697D01*
X1517032Y2055164D01*
X1516657Y2055817D01*
Y2056470D01*
X1516907Y2057124D01*
X1517532Y2057684D01*
G01X1524157Y2061637D02*
X1516657D01*
G01Y2065557D02*
X1524157D01*
G01X1520407D02*
Y2061637D01*
G01X1524157Y2072964D02*
Y2069230D01*
X1516657D01*
Y2072964D01*
G01X1520282Y2071470D02*
Y2069230D01*
G01X1524157Y2076544D02*
X1516657D01*
Y2078410D01*
X1517032Y2079157D01*
X1517532Y2079717D01*
X1518282Y2080184D01*
X1519157Y2080557D01*
X1520407Y2080650D01*
X1521657Y2080557D01*
X1522532Y2080184D01*
X1523282Y2079717D01*
X1523782Y2079157D01*
X1524157Y2078410D01*
Y2076544D01*
G01Y2091730D02*
X1516657D01*
Y2093970D01*
X1517032Y2094717D01*
X1517907Y2095277D01*
X1518907Y2095464D01*
X1519907Y2095277D01*
X1520657Y2094810D01*
X1521032Y2093970D01*
Y2091730D01*
G01X1516657Y2101097D02*
X1524157D01*
G01X1516657Y2098950D02*
Y2103244D01*
G01X1524157Y2106637D02*
X1516657D01*
G01Y2110557D02*
X1524157D01*
G01X1520407D02*
Y2106637D01*
G01X1516657Y2122477D02*
Y2124717D01*
G01Y2123597D02*
X1524157D01*
G01Y2122477D02*
Y2124717D01*
G01X1523157Y2129137D02*
X1523782Y2129884D01*
X1524157Y2130724D01*
Y2131470D01*
X1523782Y2132217D01*
X1523157Y2132777D01*
X1522282Y2133057D01*
X1521407Y2132870D01*
X1520657Y2132404D01*
X1520157Y2131564D01*
X1519907Y2130444D01*
X1519407Y2129790D01*
X1518532Y2129510D01*
X1517657Y2129697D01*
X1517032Y2130164D01*
X1516657Y2130817D01*
Y2131470D01*
X1516907Y2132124D01*
X1517532Y2132684D01*
G01X1516657Y2146097D02*
X1516907Y2145350D01*
X1517532Y2144790D01*
X1518282Y2144417D01*
X1519282Y2144137D01*
X1520407Y2144044D01*
X1521532Y2144137D01*
X1522532Y2144417D01*
X1523282Y2144790D01*
X1523907Y2145350D01*
X1524157Y2146097D01*
X1523907Y2146844D01*
X1523282Y2147404D01*
X1522532Y2147777D01*
X1521532Y2148057D01*
X1520407Y2148150D01*
X1519282Y2148057D01*
X1518282Y2147777D01*
X1517532Y2147404D01*
X1516907Y2146844D01*
X1516657Y2146097D01*
G01X1524407Y2153597D02*
X1524282Y2153410D01*
X1524032D01*
X1523907Y2153597D01*
X1524032Y2153784D01*
X1524282D01*
X1524407Y2153597D01*
G01X1524157Y2162217D02*
X1516657D01*
X1522032Y2158764D01*
Y2163430D01*
G01X1524157Y2166170D02*
X1516657D01*
X1522907Y2168597D01*
X1516657Y2171024D01*
X1524157D01*
G01Y2173670D02*
X1516657D01*
X1522907Y2176097D01*
X1516657Y2178524D01*
X1524157D01*
G01Y2188670D02*
X1516657D01*
X1522907Y2191097D01*
X1516657Y2193524D01*
X1524157D01*
G01Y2200464D02*
Y2196730D01*
X1516657D01*
Y2200464D01*
G01X1520282Y2198970D02*
Y2196730D01*
G01X1516657Y2206097D02*
X1524157D01*
G01X1516657Y2203950D02*
Y2208244D01*
G01X1524157Y2211730D02*
X1516657D01*
Y2214064D01*
X1517032Y2214810D01*
X1517532Y2215277D01*
X1518532Y2215464D01*
X1519532Y2215277D01*
X1520157Y2214717D01*
X1520532Y2214064D01*
Y2211730D01*
G01Y2214064D02*
X1524157Y2215464D01*
G01X1516657Y2219977D02*
Y2222217D01*
G01Y2221097D02*
X1524157D01*
G01Y2219977D02*
Y2222217D01*
G01X1517282Y2230650D02*
X1516907Y2230090D01*
X1516657Y2229437D01*
Y2228690D01*
X1517032Y2227850D01*
X1517657Y2227197D01*
X1518407Y2226730D01*
X1519657Y2226357D01*
X1520782Y2226264D01*
X1521907Y2226450D01*
X1522657Y2226730D01*
X1523407Y2227290D01*
X1523907Y2227944D01*
X1524157Y2228597D01*
Y2229250D01*
X1523907Y2229904D01*
X1523532Y2230464D01*
X1523032Y2230930D01*
G01X1524157Y2241544D02*
X1516657D01*
Y2243410D01*
X1517032Y2244157D01*
X1517532Y2244717D01*
X1518282Y2245184D01*
X1519157Y2245557D01*
X1520407Y2245650D01*
X1521657Y2245557D01*
X1522532Y2245184D01*
X1523282Y2244717D01*
X1523782Y2244157D01*
X1524157Y2243410D01*
Y2241544D01*
G01Y2249230D02*
X1516657D01*
Y2251564D01*
X1517032Y2252310D01*
X1517532Y2252777D01*
X1518532Y2252964D01*
X1519532Y2252777D01*
X1520157Y2252217D01*
X1520532Y2251564D01*
Y2249230D01*
G01Y2251564D02*
X1524157Y2252964D01*
G01X1516657Y2257477D02*
Y2259717D01*
G01Y2258597D02*
X1524157D01*
G01Y2257477D02*
Y2259717D01*
G01X1516657Y2264230D02*
X1524157D01*
Y2267964D01*
G01X1516657Y2271730D02*
X1524157D01*
Y2275464D01*
G01X1526657Y2280630D02*
X1525407Y2279697D01*
X1524157Y2279230D01*
X1519157D01*
X1517907Y2279697D01*
X1516657Y2280630D01*
G01Y2288597D02*
X1516907Y2287850D01*
X1517532Y2287290D01*
X1518282Y2286917D01*
X1519282Y2286637D01*
X1520407Y2286544D01*
X1521532Y2286637D01*
X1522532Y2286917D01*
X1523282Y2287290D01*
X1523907Y2287850D01*
X1524157Y2288597D01*
X1523907Y2289344D01*
X1523282Y2289904D01*
X1522532Y2290277D01*
X1521532Y2290557D01*
X1520407Y2290650D01*
X1519282Y2290557D01*
X1518282Y2290277D01*
X1517532Y2289904D01*
X1516907Y2289344D01*
X1516657Y2288597D01*
G01X1524407Y2296097D02*
X1524282Y2295910D01*
X1524032D01*
X1523907Y2296097D01*
X1524032Y2296284D01*
X1524282D01*
X1524407Y2296097D01*
G01X1516657Y2303597D02*
X1516907Y2302850D01*
X1517532Y2302290D01*
X1518282Y2301917D01*
X1519282Y2301637D01*
X1520407Y2301544D01*
X1521532Y2301637D01*
X1522532Y2301917D01*
X1523282Y2302290D01*
X1523907Y2302850D01*
X1524157Y2303597D01*
X1523907Y2304344D01*
X1523282Y2304904D01*
X1522532Y2305277D01*
X1521532Y2305557D01*
X1520407Y2305650D01*
X1519282Y2305557D01*
X1518282Y2305277D01*
X1517532Y2304904D01*
X1516907Y2304344D01*
X1516657Y2303597D01*
G01X1524157Y2311097D02*
X1516657D01*
X1518157Y2309977D01*
G01X1524157D02*
Y2312217D01*
G01X1523032Y2316544D02*
X1523657Y2317104D01*
X1524032Y2317757D01*
X1524157Y2318597D01*
X1523907Y2319437D01*
X1523407Y2320090D01*
X1522532Y2320557D01*
X1521532Y2320650D01*
X1520532Y2320464D01*
X1519907Y2319997D01*
X1519407Y2319344D01*
X1519282Y2318690D01*
X1519407Y2318037D01*
X1519907Y2317197D01*
X1516657Y2317477D01*
Y2319997D01*
G01X1524157Y2325910D02*
X1522532Y2326097D01*
X1521157Y2326377D01*
X1519907Y2326750D01*
X1518532Y2327217D01*
X1516657Y2327964D01*
Y2324230D01*
G01X1518282Y2332757D02*
X1516657Y2333224D01*
G01Y2334437D02*
X1518282Y2333970D01*
G01X1526657Y2341564D02*
X1525407Y2342497D01*
X1524157Y2342964D01*
X1519157D01*
X1517907Y2342497D01*
X1516657Y2341564D01*
G01X1534514Y1699444D02*
X1527014D01*
X1533264Y1701871D01*
X1527014Y1704298D01*
X1534514D01*
G01Y1707038D02*
X1527014Y1709371D01*
X1534514Y1711704D01*
G01X1531889Y1710864D02*
Y1707878D01*
G01X1534514Y1715004D02*
X1527014D01*
Y1717338D01*
X1527389Y1718084D01*
X1527889Y1718551D01*
X1528889Y1718738D01*
X1529889Y1718551D01*
X1530514Y1717991D01*
X1530889Y1717338D01*
Y1715004D01*
G01Y1717338D02*
X1534514Y1718738D01*
G01Y1722318D02*
X1527014D01*
G01Y1725864D02*
X1531639Y1722318D01*
G01X1534514Y1726424D02*
X1529514Y1723904D01*
G01X1534764Y1731871D02*
X1534639Y1731684D01*
X1534389D01*
X1534264Y1731871D01*
X1534389Y1732058D01*
X1534639D01*
X1534764Y1731871D01*
G01X1531389D02*
X1531264Y1731684D01*
X1531014D01*
X1530889Y1731871D01*
X1531014Y1732058D01*
X1531264D01*
X1531389Y1731871D01*
G01X1534514Y1737504D02*
X1527014D01*
Y1739838D01*
X1527389Y1740584D01*
X1527889Y1741051D01*
X1528889Y1741238D01*
X1529889Y1741051D01*
X1530514Y1740491D01*
X1530889Y1739838D01*
Y1737504D01*
G01Y1739838D02*
X1534514Y1741238D01*
G01Y1748738D02*
Y1745004D01*
X1527014D01*
Y1748738D01*
G01X1530639Y1747244D02*
Y1745004D01*
G01X1527639Y1756424D02*
X1527264Y1755864D01*
X1527014Y1755211D01*
Y1754464D01*
X1527389Y1753624D01*
X1528014Y1752971D01*
X1528764Y1752504D01*
X1530014Y1752131D01*
X1531139Y1752038D01*
X1532264Y1752224D01*
X1533014Y1752504D01*
X1533764Y1753064D01*
X1534264Y1753718D01*
X1534514Y1754371D01*
Y1755024D01*
X1534264Y1755678D01*
X1533889Y1756238D01*
X1533389Y1756704D01*
G01X1534514Y1761871D02*
X1534389Y1761124D01*
X1533889Y1760471D01*
X1533139Y1759911D01*
X1532264Y1759538D01*
X1531264Y1759351D01*
X1530264D01*
X1529264Y1759538D01*
X1528389Y1759911D01*
X1527639Y1760471D01*
X1527139Y1761124D01*
X1527014Y1761871D01*
X1527139Y1762618D01*
X1527639Y1763271D01*
X1528389Y1763831D01*
X1529264Y1764204D01*
X1530264Y1764391D01*
X1531264D01*
X1532264Y1764204D01*
X1533139Y1763831D01*
X1533889Y1763271D01*
X1534389Y1762618D01*
X1534514Y1761871D01*
G01Y1766944D02*
X1527014D01*
X1533264Y1769371D01*
X1527014Y1771798D01*
X1534514D01*
G01Y1774444D02*
X1527014D01*
X1533264Y1776871D01*
X1527014Y1779298D01*
X1534514D01*
G01Y1786238D02*
Y1782504D01*
X1527014D01*
Y1786238D01*
G01X1530639Y1784744D02*
Y1782504D01*
G01X1534514Y1789724D02*
X1527014D01*
X1534514Y1794018D01*
X1527014D01*
G01X1534514Y1797318D02*
X1527014D01*
Y1799184D01*
X1527389Y1799931D01*
X1527889Y1800491D01*
X1528639Y1800958D01*
X1529514Y1801331D01*
X1530764Y1801424D01*
X1532014Y1801331D01*
X1532889Y1800958D01*
X1533639Y1800491D01*
X1534139Y1799931D01*
X1534514Y1799184D01*
Y1797318D01*
G01Y1808738D02*
Y1805004D01*
X1527014D01*
Y1808738D01*
G01X1530639Y1807244D02*
Y1805004D01*
G01X1534514Y1812318D02*
X1527014D01*
Y1814184D01*
X1527389Y1814931D01*
X1527889Y1815491D01*
X1528639Y1815958D01*
X1529514Y1816331D01*
X1530764Y1816424D01*
X1532014Y1816331D01*
X1532889Y1815958D01*
X1533639Y1815491D01*
X1534139Y1814931D01*
X1534514Y1814184D01*
Y1812318D01*
G01Y1827318D02*
X1527014D01*
Y1829184D01*
X1527389Y1829931D01*
X1527889Y1830491D01*
X1528639Y1830958D01*
X1529514Y1831331D01*
X1530764Y1831424D01*
X1532014Y1831331D01*
X1532889Y1830958D01*
X1533639Y1830491D01*
X1534139Y1829931D01*
X1534514Y1829184D01*
Y1827318D01*
G01Y1835004D02*
X1527014D01*
Y1837338D01*
X1527389Y1838084D01*
X1527889Y1838551D01*
X1528889Y1838738D01*
X1529889Y1838551D01*
X1530514Y1837991D01*
X1530889Y1837338D01*
Y1835004D01*
G01Y1837338D02*
X1534514Y1838738D01*
G01X1527014Y1843251D02*
Y1845491D01*
G01Y1844371D02*
X1534514D01*
G01Y1843251D02*
Y1845491D01*
G01X1527014Y1850004D02*
X1534514D01*
Y1853738D01*
G01X1527014Y1857504D02*
X1534514D01*
Y1861238D01*
G01X1533514Y1872411D02*
X1534139Y1873158D01*
X1534514Y1873998D01*
Y1874744D01*
X1534139Y1875491D01*
X1533514Y1876051D01*
X1532639Y1876331D01*
X1531764Y1876144D01*
X1531014Y1875678D01*
X1530514Y1874838D01*
X1530264Y1873718D01*
X1529764Y1873064D01*
X1528889Y1872784D01*
X1528014Y1872971D01*
X1527389Y1873438D01*
X1527014Y1874091D01*
Y1874744D01*
X1527264Y1875398D01*
X1527889Y1875958D01*
G01X1527014Y1880751D02*
Y1882991D01*
G01Y1881871D02*
X1534514D01*
G01Y1880751D02*
Y1882991D01*
G01X1527014Y1887598D02*
Y1891144D01*
X1534514Y1887598D01*
Y1891144D01*
G01Y1898738D02*
Y1895004D01*
X1527014D01*
Y1898738D01*
G01X1530639Y1897244D02*
Y1895004D01*
G01X1534514Y1910098D02*
X1527014D01*
Y1913644D01*
G01X1530639Y1912338D02*
Y1910098D01*
G01X1534514Y1919371D02*
X1534389Y1918624D01*
X1533889Y1917971D01*
X1533139Y1917411D01*
X1532264Y1917038D01*
X1531264Y1916851D01*
X1530264D01*
X1529264Y1917038D01*
X1528389Y1917411D01*
X1527639Y1917971D01*
X1527139Y1918624D01*
X1527014Y1919371D01*
X1527139Y1920118D01*
X1527639Y1920771D01*
X1528389Y1921331D01*
X1529264Y1921704D01*
X1530264Y1921891D01*
X1531264D01*
X1532264Y1921704D01*
X1533139Y1921331D01*
X1533889Y1920771D01*
X1534389Y1920118D01*
X1534514Y1919371D01*
G01Y1925004D02*
X1527014D01*
Y1927338D01*
X1527389Y1928084D01*
X1527889Y1928551D01*
X1528889Y1928738D01*
X1529889Y1928551D01*
X1530514Y1927991D01*
X1530889Y1927338D01*
Y1925004D01*
G01Y1927338D02*
X1534514Y1928738D01*
G01X1527014Y1941871D02*
X1527264Y1941124D01*
X1527889Y1940564D01*
X1528639Y1940191D01*
X1529639Y1939911D01*
X1530764Y1939818D01*
X1531889Y1939911D01*
X1532889Y1940191D01*
X1533639Y1940564D01*
X1534264Y1941124D01*
X1534514Y1941871D01*
X1534264Y1942618D01*
X1533639Y1943178D01*
X1532889Y1943551D01*
X1531889Y1943831D01*
X1530764Y1943924D01*
X1529639Y1943831D01*
X1528639Y1943551D01*
X1527889Y1943178D01*
X1527264Y1942618D01*
X1527014Y1941871D01*
G01X1534764Y1949371D02*
X1534639Y1949184D01*
X1534389D01*
X1534264Y1949371D01*
X1534389Y1949558D01*
X1534639D01*
X1534764Y1949371D01*
G01X1533389Y1954818D02*
X1534014Y1955378D01*
X1534389Y1956031D01*
X1534514Y1956871D01*
X1534264Y1957711D01*
X1533764Y1958364D01*
X1532889Y1958831D01*
X1531889Y1958924D01*
X1530889Y1958738D01*
X1530264Y1958271D01*
X1529764Y1957618D01*
X1529639Y1956964D01*
X1529764Y1956311D01*
X1530264Y1955471D01*
X1527014Y1955751D01*
Y1958271D01*
G01X1534514Y1961944D02*
X1527014D01*
X1533264Y1964371D01*
X1527014Y1966798D01*
X1534514D01*
G01Y1969444D02*
X1527014D01*
X1533264Y1971871D01*
X1527014Y1974298D01*
X1534514D01*
G01Y1985098D02*
X1527014D01*
Y1988644D01*
G01X1530639Y1987338D02*
Y1985098D01*
G01X1527014Y1993251D02*
Y1995491D01*
G01Y1994371D02*
X1534514D01*
G01Y1993251D02*
Y1995491D01*
G01Y1999724D02*
X1527014D01*
X1534514Y2004018D01*
X1527014D01*
G01Y2008251D02*
Y2010491D01*
G01Y2009371D02*
X1534514D01*
G01Y2008251D02*
Y2010491D01*
G01X1533514Y2014911D02*
X1534139Y2015658D01*
X1534514Y2016498D01*
Y2017244D01*
X1534139Y2017991D01*
X1533514Y2018551D01*
X1532639Y2018831D01*
X1531764Y2018644D01*
X1531014Y2018178D01*
X1530514Y2017338D01*
X1530264Y2016218D01*
X1529764Y2015564D01*
X1528889Y2015284D01*
X1528014Y2015471D01*
X1527389Y2015938D01*
X1527014Y2016591D01*
Y2017244D01*
X1527264Y2017898D01*
X1527889Y2018458D01*
G01X1534514Y2022411D02*
X1527014D01*
G01Y2026331D02*
X1534514D01*
G01X1530764D02*
Y2022411D01*
G01X1534514Y2033738D02*
Y2030004D01*
X1527014D01*
Y2033738D01*
G01X1530639Y2032244D02*
Y2030004D01*
G01X1534514Y2037318D02*
X1527014D01*
Y2039184D01*
X1527389Y2039931D01*
X1527889Y2040491D01*
X1528639Y2040958D01*
X1529514Y2041331D01*
X1530764Y2041424D01*
X1532014Y2041331D01*
X1532889Y2040958D01*
X1533639Y2040491D01*
X1534139Y2039931D01*
X1534514Y2039184D01*
Y2037318D01*
G01Y2052504D02*
X1527014D01*
Y2054744D01*
X1527389Y2055491D01*
X1528264Y2056051D01*
X1529264Y2056238D01*
X1530264Y2056051D01*
X1531014Y2055584D01*
X1531389Y2054744D01*
Y2052504D01*
G01X1527014Y2061871D02*
X1534514D01*
G01X1527014Y2059724D02*
Y2064018D01*
G01X1534514Y2067411D02*
X1527014D01*
G01Y2071331D02*
X1534514D01*
G01X1530764D02*
Y2067411D01*
G01X1527014Y2083251D02*
Y2085491D01*
G01Y2084371D02*
X1534514D01*
G01Y2083251D02*
Y2085491D01*
G01X1533514Y2089911D02*
X1534139Y2090658D01*
X1534514Y2091498D01*
Y2092244D01*
X1534139Y2092991D01*
X1533514Y2093551D01*
X1532639Y2093831D01*
X1531764Y2093644D01*
X1531014Y2093178D01*
X1530514Y2092338D01*
X1530264Y2091218D01*
X1529764Y2090564D01*
X1528889Y2090284D01*
X1528014Y2090471D01*
X1527389Y2090938D01*
X1527014Y2091591D01*
Y2092244D01*
X1527264Y2092898D01*
X1527889Y2093458D01*
G01X1527014Y2106871D02*
X1527264Y2106124D01*
X1527889Y2105564D01*
X1528639Y2105191D01*
X1529639Y2104911D01*
X1530764Y2104818D01*
X1531889Y2104911D01*
X1532889Y2105191D01*
X1533639Y2105564D01*
X1534264Y2106124D01*
X1534514Y2106871D01*
X1534264Y2107618D01*
X1533639Y2108178D01*
X1532889Y2108551D01*
X1531889Y2108831D01*
X1530764Y2108924D01*
X1529639Y2108831D01*
X1528639Y2108551D01*
X1527889Y2108178D01*
X1527264Y2107618D01*
X1527014Y2106871D01*
G01X1534764Y2114371D02*
X1534639Y2114184D01*
X1534389D01*
X1534264Y2114371D01*
X1534389Y2114558D01*
X1534639D01*
X1534764Y2114371D01*
G01X1531389Y2120098D02*
X1530514Y2120751D01*
X1530014Y2121311D01*
X1529764Y2122058D01*
X1530014Y2122711D01*
X1530514Y2123178D01*
X1531264Y2123551D01*
X1532139Y2123644D01*
X1532889Y2123551D01*
X1533639Y2123178D01*
X1534264Y2122618D01*
X1534514Y2121964D01*
X1534264Y2121218D01*
X1533514Y2120564D01*
X1532389Y2120191D01*
X1531139Y2120098D01*
X1529514Y2120284D01*
X1528639Y2120564D01*
X1527764Y2121031D01*
X1527139Y2121684D01*
X1527014Y2122338D01*
X1527264Y2122991D01*
X1527889Y2123458D01*
G01X1534514Y2126944D02*
X1527014D01*
X1533264Y2129371D01*
X1527014Y2131798D01*
X1534514D01*
G01Y2134444D02*
X1527014D01*
X1533264Y2136871D01*
X1527014Y2139298D01*
X1534514D01*
G01Y2149444D02*
X1527014D01*
X1533264Y2151871D01*
X1527014Y2154298D01*
X1534514D01*
G01Y2161238D02*
Y2157504D01*
X1527014D01*
Y2161238D01*
G01X1530639Y2159744D02*
Y2157504D01*
G01X1527014Y2166871D02*
X1534514D01*
G01X1527014Y2164724D02*
Y2169018D01*
G01X1534514Y2172504D02*
X1527014D01*
Y2174838D01*
X1527389Y2175584D01*
X1527889Y2176051D01*
X1528889Y2176238D01*
X1529889Y2176051D01*
X1530514Y2175491D01*
X1530889Y2174838D01*
Y2172504D01*
G01Y2174838D02*
X1534514Y2176238D01*
G01X1527014Y2180751D02*
Y2182991D01*
G01Y2181871D02*
X1534514D01*
G01Y2180751D02*
Y2182991D01*
G01X1527639Y2191424D02*
X1527264Y2190864D01*
X1527014Y2190211D01*
Y2189464D01*
X1527389Y2188624D01*
X1528014Y2187971D01*
X1528764Y2187504D01*
X1530014Y2187131D01*
X1531139Y2187038D01*
X1532264Y2187224D01*
X1533014Y2187504D01*
X1533764Y2188064D01*
X1534264Y2188718D01*
X1534514Y2189371D01*
Y2190024D01*
X1534264Y2190678D01*
X1533889Y2191238D01*
X1533389Y2191704D01*
G01X1534514Y2202318D02*
X1527014D01*
Y2204184D01*
X1527389Y2204931D01*
X1527889Y2205491D01*
X1528639Y2205958D01*
X1529514Y2206331D01*
X1530764Y2206424D01*
X1532014Y2206331D01*
X1532889Y2205958D01*
X1533639Y2205491D01*
X1534139Y2204931D01*
X1534514Y2204184D01*
Y2202318D01*
G01Y2210004D02*
X1527014D01*
Y2212338D01*
X1527389Y2213084D01*
X1527889Y2213551D01*
X1528889Y2213738D01*
X1529889Y2213551D01*
X1530514Y2212991D01*
X1530889Y2212338D01*
Y2210004D01*
G01Y2212338D02*
X1534514Y2213738D01*
G01X1527014Y2218251D02*
Y2220491D01*
G01Y2219371D02*
X1534514D01*
G01Y2218251D02*
Y2220491D01*
G01X1527014Y2225004D02*
X1534514D01*
Y2228738D01*
G01X1527014Y2232504D02*
X1534514D01*
Y2236238D01*
G01X1537014Y2241404D02*
X1535764Y2240471D01*
X1534514Y2240004D01*
X1529514D01*
X1528264Y2240471D01*
X1527014Y2241404D01*
G01Y2249371D02*
X1527264Y2248624D01*
X1527889Y2248064D01*
X1528639Y2247691D01*
X1529639Y2247411D01*
X1530764Y2247318D01*
X1531889Y2247411D01*
X1532889Y2247691D01*
X1533639Y2248064D01*
X1534264Y2248624D01*
X1534514Y2249371D01*
X1534264Y2250118D01*
X1533639Y2250678D01*
X1532889Y2251051D01*
X1531889Y2251331D01*
X1530764Y2251424D01*
X1529639Y2251331D01*
X1528639Y2251051D01*
X1527889Y2250678D01*
X1527264Y2250118D01*
X1527014Y2249371D01*
G01X1534764Y2256871D02*
X1534639Y2256684D01*
X1534389D01*
X1534264Y2256871D01*
X1534389Y2257058D01*
X1534639D01*
X1534764Y2256871D01*
G01X1527014Y2264371D02*
X1527264Y2263624D01*
X1527889Y2263064D01*
X1528639Y2262691D01*
X1529639Y2262411D01*
X1530764Y2262318D01*
X1531889Y2262411D01*
X1532889Y2262691D01*
X1533639Y2263064D01*
X1534264Y2263624D01*
X1534514Y2264371D01*
X1534264Y2265118D01*
X1533639Y2265678D01*
X1532889Y2266051D01*
X1531889Y2266331D01*
X1530764Y2266424D01*
X1529639Y2266331D01*
X1528639Y2266051D01*
X1527889Y2265678D01*
X1527264Y2265118D01*
X1527014Y2264371D01*
G01X1528264Y2270098D02*
X1527514Y2270658D01*
X1527139Y2271311D01*
X1527014Y2272058D01*
X1527264Y2272991D01*
X1527889Y2273644D01*
X1528639Y2273831D01*
X1529389Y2273738D01*
X1530014Y2273364D01*
X1531264Y2271498D01*
X1532139Y2270658D01*
X1533389Y2270098D01*
X1534514Y2269911D01*
Y2273831D01*
G01X1533014Y2277318D02*
X1533889Y2277878D01*
X1534389Y2278624D01*
X1534514Y2279464D01*
X1534389Y2280211D01*
X1533764Y2280958D01*
X1533014Y2281424D01*
X1532264Y2281518D01*
X1531389Y2281331D01*
X1530764Y2280678D01*
X1530514Y2280024D01*
Y2279184D01*
G01Y2280024D02*
X1530139Y2280584D01*
X1529514Y2281051D01*
X1528764Y2281238D01*
X1528014Y2281051D01*
X1527389Y2280584D01*
X1527014Y2279744D01*
X1527139Y2278904D01*
X1527639Y2278064D01*
G01X1531389Y2285098D02*
X1530514Y2285751D01*
X1530014Y2286311D01*
X1529764Y2287058D01*
X1530014Y2287711D01*
X1530514Y2288178D01*
X1531264Y2288551D01*
X1532139Y2288644D01*
X1532889Y2288551D01*
X1533639Y2288178D01*
X1534264Y2287618D01*
X1534514Y2286964D01*
X1534264Y2286218D01*
X1533514Y2285564D01*
X1532389Y2285191D01*
X1531139Y2285098D01*
X1529514Y2285284D01*
X1528639Y2285564D01*
X1527764Y2286031D01*
X1527139Y2286684D01*
X1527014Y2287338D01*
X1527264Y2287991D01*
X1527889Y2288458D01*
G01X1528639Y2293531D02*
X1527014Y2293998D01*
G01Y2295211D02*
X1528639Y2294744D01*
G01X1537014Y2302338D02*
X1535764Y2303271D01*
X1534514Y2303738D01*
X1529514D01*
X1528264Y2303271D01*
X1527014Y2302338D01*
G01X1550050Y1453504D02*
G03I-2452J0D01*
G01X1541389Y1457835D02*
G03I-2452J0D01*
G01X1550050Y1468859D02*
G03I-2452J0D01*
G01X1541389Y1473189D02*
G03I-2452J0D01*
G01X1550050Y1484213D02*
G03I-2452J0D01*
G01X1541389Y1488544D02*
G03I-2452J0D01*
G01X1550050Y1514922D02*
G03I-2452J0D01*
G01Y1499567D02*
G03I-2452J0D01*
G01X1541389Y1503898D02*
G03I-2452J0D01*
G01Y1519252D02*
G03I-2452J0D01*
G01X1550050Y1555867D02*
G03I-2452J0D01*
G01X1541389Y1560197D02*
G03I-2452J0D01*
G01X1550050Y1571221D02*
G03I-2452J0D01*
G01X1541389Y1575552D02*
G03I-2452J0D01*
G01X1550050Y1586575D02*
G03I-2452J0D01*
G01X1541389Y1590906D02*
G03I-2452J0D01*
G01X1550050Y1601930D02*
G03I-2452J0D01*
G01X1541389Y1606260D02*
G03I-2452J0D01*
G01X1550050Y1617284D02*
G03I-2452J0D01*
G01X1541389Y1621615D02*
G03I-2452J0D01*
G01X1558712Y1457835D02*
G03I-2452J0D01*
G01Y1473189D02*
G03I-2452J0D01*
G01Y1488544D02*
G03I-2452J0D01*
G01Y1503898D02*
G03I-2452J0D01*
G01Y1519252D02*
G03I-2452J0D01*
G01X1558711Y1560197D02*
G03I-2451J0D01*
G01X1558712Y1575552D02*
G03I-2452J0D01*
G01Y1590906D02*
G03I-2452J0D01*
G01X1558711Y1606260D02*
G03I-2451J0D01*
G01X1558712Y1621615D02*
G03I-2452J0D01*
G01X1662648Y1457835D02*
G03I-2452J0D01*
G01X1653986Y1453504D02*
G03I-2451J0D01*
G01X1662648Y1473189D02*
G03I-2452J0D01*
G01X1653987Y1468859D02*
G03I-2452J0D01*
G01X1653986Y1499567D02*
G03I-2451J0D01*
G01X1662648Y1488544D02*
G03I-2452J0D01*
G01X1653987Y1484213D02*
G03I-2452J0D01*
G01Y1514922D02*
G03I-2452J0D01*
G01X1662648Y1503898D02*
G03I-2452J0D01*
G01Y1519252D02*
G03I-2452J0D01*
G01X1653987Y1555867D02*
G03I-2452J0D01*
G01X1662648Y1560197D02*
G03I-2452J0D01*
G01Y1575552D02*
G03I-2452J0D01*
G01X1653987Y1571221D02*
G03I-2452J0D01*
G01X1662648Y1590906D02*
G03I-2452J0D01*
G01X1653987Y1586575D02*
G03I-2452J0D01*
G01X1662648Y1606260D02*
G03I-2452J0D01*
G01X1653987Y1601930D02*
G03I-2452J0D01*
G01X1662648Y1621615D02*
G03I-2452J0D01*
G01X1653987Y1617284D02*
G03I-2452J0D01*
G01X1679971Y1457835D02*
G03I-2452J0D01*
G01X1671309Y1453504D02*
G03I-2451J0D01*
G01X1679971Y1473189D02*
G03I-2452J0D01*
G01X1671310Y1468859D02*
G03I-2452J0D01*
G01X1671309Y1499567D02*
G03I-2451J0D01*
G01X1679971Y1488544D02*
G03I-2452J0D01*
G01X1671310Y1484213D02*
G03I-2452J0D01*
G01Y1514922D02*
G03I-2452J0D01*
G01X1679971Y1503898D02*
G03I-2452J0D01*
G01Y1519252D02*
G03I-2452J0D01*
G01Y1560197D02*
G03I-2452J0D01*
G01X1671310Y1555867D02*
G03I-2452J0D01*
G01X1679971Y1575552D02*
G03I-2452J0D01*
G01X1671310Y1571221D02*
G03I-2452J0D01*
G01X1679971Y1590906D02*
G03I-2452J0D01*
G01X1671310Y1586575D02*
G03I-2452J0D01*
G01X1679971Y1606260D02*
G03I-2452J0D01*
G01X1671310Y1601930D02*
G03I-2452J0D01*
G01X1679971Y1621615D02*
G03I-2452J0D01*
G01X1671310Y1617284D02*
G03I-2452J0D01*
G01X1697294Y1457835D02*
G03I-2452J0D01*
G01X1688632Y1453504D02*
G03I-2451J0D01*
G01X1697294Y1473189D02*
G03I-2452J0D01*
G01X1688633Y1468859D02*
G03I-2452J0D01*
G01X1688632Y1499567D02*
G03I-2451J0D01*
G01X1697294Y1488544D02*
G03I-2452J0D01*
G01X1688633Y1484213D02*
G03I-2452J0D01*
G01Y1514922D02*
G03I-2452J0D01*
G01X1697294Y1503898D02*
G03I-2452J0D01*
G01Y1519252D02*
G03I-2452J0D01*
G01Y1560197D02*
G03I-2452J0D01*
G01X1688633Y1555867D02*
G03I-2452J0D01*
G01X1697294Y1575552D02*
G03I-2452J0D01*
G01X1688633Y1571221D02*
G03I-2452J0D01*
G01X1697294Y1590906D02*
G03I-2452J0D01*
G01X1688632Y1586575D02*
G03I-2451J0D01*
G01X1697294Y1606260D02*
G03I-2452J0D01*
G01X1688633Y1601930D02*
G03I-2452J0D01*
G01X1697294Y1621615D02*
G03I-2452J0D01*
G01X1688633Y1617284D02*
G03I-2452J0D01*
G01X1697345Y1703752D02*
X1689845D01*
X1697345Y1708046D01*
X1689845D01*
G01X1697345Y1713399D02*
X1697220Y1712652D01*
X1696720Y1711999D01*
X1695970Y1711439D01*
X1695095Y1711066D01*
X1694095Y1710879D01*
X1693095D01*
X1692095Y1711066D01*
X1691220Y1711439D01*
X1690470Y1711999D01*
X1689970Y1712652D01*
X1689845Y1713399D01*
X1689970Y1714146D01*
X1690470Y1714799D01*
X1691220Y1715359D01*
X1692095Y1715732D01*
X1693095Y1715919D01*
X1694095D01*
X1695095Y1715732D01*
X1695970Y1715359D01*
X1696720Y1714799D01*
X1697220Y1714146D01*
X1697345Y1713399D01*
G01Y1718752D02*
X1689845D01*
X1697345Y1723046D01*
X1689845D01*
G01X1694845Y1727186D02*
Y1729612D01*
G01X1697345Y1733472D02*
X1689845D01*
X1696095Y1735899D01*
X1689845Y1738326D01*
X1697345D01*
G01Y1741066D02*
X1689845Y1743399D01*
X1697345Y1745732D01*
G01X1694720Y1744892D02*
Y1741906D01*
G01X1697345Y1749032D02*
X1689845D01*
Y1751366D01*
X1690220Y1752112D01*
X1690720Y1752579D01*
X1691720Y1752766D01*
X1692720Y1752579D01*
X1693345Y1752019D01*
X1693720Y1751366D01*
Y1749032D01*
G01Y1751366D02*
X1697345Y1752766D01*
G01Y1756346D02*
X1689845D01*
G01Y1759892D02*
X1694470Y1756346D01*
G01X1697345Y1760452D02*
X1692345Y1757932D01*
G01X1697595Y1765899D02*
X1697470Y1765712D01*
X1697220D01*
X1697095Y1765899D01*
X1697220Y1766086D01*
X1697470D01*
X1697595Y1765899D01*
G01X1694220D02*
X1694095Y1765712D01*
X1693845D01*
X1693720Y1765899D01*
X1693845Y1766086D01*
X1694095D01*
X1694220Y1765899D01*
G01X1697345Y1771532D02*
X1689845D01*
Y1773866D01*
X1690220Y1774612D01*
X1690720Y1775079D01*
X1691720Y1775266D01*
X1692720Y1775079D01*
X1693345Y1774519D01*
X1693720Y1773866D01*
Y1771532D01*
G01Y1773866D02*
X1697345Y1775266D01*
G01Y1782766D02*
Y1779032D01*
X1689845D01*
Y1782766D01*
G01X1693470Y1781272D02*
Y1779032D01*
G01X1690470Y1790452D02*
X1690095Y1789892D01*
X1689845Y1789239D01*
Y1788492D01*
X1690220Y1787652D01*
X1690845Y1786999D01*
X1691595Y1786532D01*
X1692845Y1786159D01*
X1693970Y1786066D01*
X1695095Y1786252D01*
X1695845Y1786532D01*
X1696595Y1787092D01*
X1697095Y1787746D01*
X1697345Y1788399D01*
Y1789052D01*
X1697095Y1789706D01*
X1696720Y1790266D01*
X1696220Y1790732D01*
G01X1697345Y1795899D02*
X1697220Y1795152D01*
X1696720Y1794499D01*
X1695970Y1793939D01*
X1695095Y1793566D01*
X1694095Y1793379D01*
X1693095D01*
X1692095Y1793566D01*
X1691220Y1793939D01*
X1690470Y1794499D01*
X1689970Y1795152D01*
X1689845Y1795899D01*
X1689970Y1796646D01*
X1690470Y1797299D01*
X1691220Y1797859D01*
X1692095Y1798232D01*
X1693095Y1798419D01*
X1694095D01*
X1695095Y1798232D01*
X1695970Y1797859D01*
X1696720Y1797299D01*
X1697220Y1796646D01*
X1697345Y1795899D01*
G01Y1800972D02*
X1689845D01*
X1696095Y1803399D01*
X1689845Y1805826D01*
X1697345D01*
G01Y1808472D02*
X1689845D01*
X1696095Y1810899D01*
X1689845Y1813326D01*
X1697345D01*
G01Y1820266D02*
Y1816532D01*
X1689845D01*
Y1820266D01*
G01X1693470Y1818772D02*
Y1816532D01*
G01X1697345Y1823752D02*
X1689845D01*
X1697345Y1828046D01*
X1689845D01*
G01X1697345Y1831346D02*
X1689845D01*
Y1833212D01*
X1690220Y1833959D01*
X1690720Y1834519D01*
X1691470Y1834986D01*
X1692345Y1835359D01*
X1693595Y1835452D01*
X1694845Y1835359D01*
X1695720Y1834986D01*
X1696470Y1834519D01*
X1696970Y1833959D01*
X1697345Y1833212D01*
Y1831346D01*
G01Y1842766D02*
Y1839032D01*
X1689845D01*
Y1842766D01*
G01X1693470Y1841272D02*
Y1839032D01*
G01X1697345Y1846346D02*
X1689845D01*
Y1848212D01*
X1690220Y1848959D01*
X1690720Y1849519D01*
X1691470Y1849986D01*
X1692345Y1850359D01*
X1693595Y1850452D01*
X1694845Y1850359D01*
X1695720Y1849986D01*
X1696470Y1849519D01*
X1696970Y1848959D01*
X1697345Y1848212D01*
Y1846346D01*
G01Y1861346D02*
X1689845D01*
Y1863212D01*
X1690220Y1863959D01*
X1690720Y1864519D01*
X1691470Y1864986D01*
X1692345Y1865359D01*
X1693595Y1865452D01*
X1694845Y1865359D01*
X1695720Y1864986D01*
X1696470Y1864519D01*
X1696970Y1863959D01*
X1697345Y1863212D01*
Y1861346D01*
G01Y1869032D02*
X1689845D01*
Y1871366D01*
X1690220Y1872112D01*
X1690720Y1872579D01*
X1691720Y1872766D01*
X1692720Y1872579D01*
X1693345Y1872019D01*
X1693720Y1871366D01*
Y1869032D01*
G01Y1871366D02*
X1697345Y1872766D01*
G01X1689845Y1877279D02*
Y1879519D01*
G01Y1878399D02*
X1697345D01*
G01Y1877279D02*
Y1879519D01*
G01X1689845Y1884032D02*
X1697345D01*
Y1887766D01*
G01X1689845Y1891532D02*
X1697345D01*
Y1895266D01*
G01X1696345Y1906439D02*
X1696970Y1907186D01*
X1697345Y1908026D01*
Y1908772D01*
X1696970Y1909519D01*
X1696345Y1910079D01*
X1695470Y1910359D01*
X1694595Y1910172D01*
X1693845Y1909706D01*
X1693345Y1908866D01*
X1693095Y1907746D01*
X1692595Y1907092D01*
X1691720Y1906812D01*
X1690845Y1906999D01*
X1690220Y1907466D01*
X1689845Y1908119D01*
Y1908772D01*
X1690095Y1909426D01*
X1690720Y1909986D01*
G01X1689845Y1914779D02*
Y1917019D01*
G01Y1915899D02*
X1697345D01*
G01Y1914779D02*
Y1917019D01*
G01X1689845Y1921626D02*
Y1925172D01*
X1697345Y1921626D01*
Y1925172D01*
G01Y1932766D02*
Y1929032D01*
X1689845D01*
Y1932766D01*
G01X1693470Y1931272D02*
Y1929032D01*
G01X1697345Y1944126D02*
X1689845D01*
Y1947672D01*
G01X1693470Y1946366D02*
Y1944126D01*
G01X1697345Y1953399D02*
X1697220Y1952652D01*
X1696720Y1951999D01*
X1695970Y1951439D01*
X1695095Y1951066D01*
X1694095Y1950879D01*
X1693095D01*
X1692095Y1951066D01*
X1691220Y1951439D01*
X1690470Y1951999D01*
X1689970Y1952652D01*
X1689845Y1953399D01*
X1689970Y1954146D01*
X1690470Y1954799D01*
X1691220Y1955359D01*
X1692095Y1955732D01*
X1693095Y1955919D01*
X1694095D01*
X1695095Y1955732D01*
X1695970Y1955359D01*
X1696720Y1954799D01*
X1697220Y1954146D01*
X1697345Y1953399D01*
G01Y1959032D02*
X1689845D01*
Y1961366D01*
X1690220Y1962112D01*
X1690720Y1962579D01*
X1691720Y1962766D01*
X1692720Y1962579D01*
X1693345Y1962019D01*
X1693720Y1961366D01*
Y1959032D01*
G01Y1961366D02*
X1697345Y1962766D01*
G01X1689845Y1975899D02*
X1690095Y1975152D01*
X1690720Y1974592D01*
X1691470Y1974219D01*
X1692470Y1973939D01*
X1693595Y1973846D01*
X1694720Y1973939D01*
X1695720Y1974219D01*
X1696470Y1974592D01*
X1697095Y1975152D01*
X1697345Y1975899D01*
X1697095Y1976646D01*
X1696470Y1977206D01*
X1695720Y1977579D01*
X1694720Y1977859D01*
X1693595Y1977952D01*
X1692470Y1977859D01*
X1691470Y1977579D01*
X1690720Y1977206D01*
X1690095Y1976646D01*
X1689845Y1975899D01*
G01X1697595Y1983399D02*
X1697470Y1983212D01*
X1697220D01*
X1697095Y1983399D01*
X1697220Y1983586D01*
X1697470D01*
X1697595Y1983399D01*
G01X1695845Y1988846D02*
X1696720Y1989406D01*
X1697220Y1990152D01*
X1697345Y1990992D01*
X1697220Y1991739D01*
X1696595Y1992486D01*
X1695845Y1992952D01*
X1695095Y1993046D01*
X1694220Y1992859D01*
X1693595Y1992206D01*
X1693345Y1991552D01*
Y1990712D01*
G01Y1991552D02*
X1692970Y1992112D01*
X1692345Y1992579D01*
X1691595Y1992766D01*
X1690845Y1992579D01*
X1690220Y1992112D01*
X1689845Y1991272D01*
X1689970Y1990432D01*
X1690470Y1989592D01*
G01X1697345Y1998399D02*
X1689845D01*
X1691345Y1997279D01*
G01X1697345D02*
Y1999519D01*
G01Y2003472D02*
X1689845D01*
X1696095Y2005899D01*
X1689845Y2008326D01*
X1697345D01*
G01Y2010972D02*
X1689845D01*
X1696095Y2013399D01*
X1689845Y2015826D01*
X1697345D01*
G01Y2026626D02*
X1689845D01*
Y2030172D01*
G01X1693470Y2028866D02*
Y2026626D01*
G01X1689845Y2034779D02*
Y2037019D01*
G01Y2035899D02*
X1697345D01*
G01Y2034779D02*
Y2037019D01*
G01Y2041252D02*
X1689845D01*
X1697345Y2045546D01*
X1689845D01*
G01Y2049779D02*
Y2052019D01*
G01Y2050899D02*
X1697345D01*
G01Y2049779D02*
Y2052019D01*
G01X1696345Y2056439D02*
X1696970Y2057186D01*
X1697345Y2058026D01*
Y2058772D01*
X1696970Y2059519D01*
X1696345Y2060079D01*
X1695470Y2060359D01*
X1694595Y2060172D01*
X1693845Y2059706D01*
X1693345Y2058866D01*
X1693095Y2057746D01*
X1692595Y2057092D01*
X1691720Y2056812D01*
X1690845Y2056999D01*
X1690220Y2057466D01*
X1689845Y2058119D01*
Y2058772D01*
X1690095Y2059426D01*
X1690720Y2059986D01*
G01X1697345Y2063939D02*
X1689845D01*
G01Y2067859D02*
X1697345D01*
G01X1693595D02*
Y2063939D01*
G01X1697345Y2075266D02*
Y2071532D01*
X1689845D01*
Y2075266D01*
G01X1693470Y2073772D02*
Y2071532D01*
G01X1697345Y2078846D02*
X1689845D01*
Y2080712D01*
X1690220Y2081459D01*
X1690720Y2082019D01*
X1691470Y2082486D01*
X1692345Y2082859D01*
X1693595Y2082952D01*
X1694845Y2082859D01*
X1695720Y2082486D01*
X1696470Y2082019D01*
X1696970Y2081459D01*
X1697345Y2080712D01*
Y2078846D01*
G01Y2094032D02*
X1689845D01*
Y2096272D01*
X1690220Y2097019D01*
X1691095Y2097579D01*
X1692095Y2097766D01*
X1693095Y2097579D01*
X1693845Y2097112D01*
X1694220Y2096272D01*
Y2094032D01*
G01X1689845Y2103399D02*
X1697345D01*
G01X1689845Y2101252D02*
Y2105546D01*
G01X1697345Y2108939D02*
X1689845D01*
G01Y2112859D02*
X1697345D01*
G01X1693595D02*
Y2108939D01*
G01X1689845Y2124779D02*
Y2127019D01*
G01Y2125899D02*
X1697345D01*
G01Y2124779D02*
Y2127019D01*
G01X1696345Y2131439D02*
X1696970Y2132186D01*
X1697345Y2133026D01*
Y2133772D01*
X1696970Y2134519D01*
X1696345Y2135079D01*
X1695470Y2135359D01*
X1694595Y2135172D01*
X1693845Y2134706D01*
X1693345Y2133866D01*
X1693095Y2132746D01*
X1692595Y2132092D01*
X1691720Y2131812D01*
X1690845Y2131999D01*
X1690220Y2132466D01*
X1689845Y2133119D01*
Y2133772D01*
X1690095Y2134426D01*
X1690720Y2134986D01*
G01X1689845Y2148399D02*
X1690095Y2147652D01*
X1690720Y2147092D01*
X1691470Y2146719D01*
X1692470Y2146439D01*
X1693595Y2146346D01*
X1694720Y2146439D01*
X1695720Y2146719D01*
X1696470Y2147092D01*
X1697095Y2147652D01*
X1697345Y2148399D01*
X1697095Y2149146D01*
X1696470Y2149706D01*
X1695720Y2150079D01*
X1694720Y2150359D01*
X1693595Y2150452D01*
X1692470Y2150359D01*
X1691470Y2150079D01*
X1690720Y2149706D01*
X1690095Y2149146D01*
X1689845Y2148399D01*
G01X1697595Y2155899D02*
X1697470Y2155712D01*
X1697220D01*
X1697095Y2155899D01*
X1697220Y2156086D01*
X1697470D01*
X1697595Y2155899D01*
G01X1697345Y2164519D02*
X1689845D01*
X1695220Y2161066D01*
Y2165732D01*
G01X1697345Y2168472D02*
X1689845D01*
X1696095Y2170899D01*
X1689845Y2173326D01*
X1697345D01*
G01Y2175972D02*
X1689845D01*
X1696095Y2178399D01*
X1689845Y2180826D01*
X1697345D01*
G01Y2190972D02*
X1689845D01*
X1696095Y2193399D01*
X1689845Y2195826D01*
X1697345D01*
G01Y2202766D02*
Y2199032D01*
X1689845D01*
Y2202766D01*
G01X1693470Y2201272D02*
Y2199032D01*
G01X1689845Y2208399D02*
X1697345D01*
G01X1689845Y2206252D02*
Y2210546D01*
G01X1697345Y2214032D02*
X1689845D01*
Y2216366D01*
X1690220Y2217112D01*
X1690720Y2217579D01*
X1691720Y2217766D01*
X1692720Y2217579D01*
X1693345Y2217019D01*
X1693720Y2216366D01*
Y2214032D01*
G01Y2216366D02*
X1697345Y2217766D01*
G01X1689845Y2222279D02*
Y2224519D01*
G01Y2223399D02*
X1697345D01*
G01Y2222279D02*
Y2224519D01*
G01X1690470Y2232952D02*
X1690095Y2232392D01*
X1689845Y2231739D01*
Y2230992D01*
X1690220Y2230152D01*
X1690845Y2229499D01*
X1691595Y2229032D01*
X1692845Y2228659D01*
X1693970Y2228566D01*
X1695095Y2228752D01*
X1695845Y2229032D01*
X1696595Y2229592D01*
X1697095Y2230246D01*
X1697345Y2230899D01*
Y2231552D01*
X1697095Y2232206D01*
X1696720Y2232766D01*
X1696220Y2233232D01*
G01X1697345Y2243846D02*
X1689845D01*
Y2245712D01*
X1690220Y2246459D01*
X1690720Y2247019D01*
X1691470Y2247486D01*
X1692345Y2247859D01*
X1693595Y2247952D01*
X1694845Y2247859D01*
X1695720Y2247486D01*
X1696470Y2247019D01*
X1696970Y2246459D01*
X1697345Y2245712D01*
Y2243846D01*
G01Y2251532D02*
X1689845D01*
Y2253866D01*
X1690220Y2254612D01*
X1690720Y2255079D01*
X1691720Y2255266D01*
X1692720Y2255079D01*
X1693345Y2254519D01*
X1693720Y2253866D01*
Y2251532D01*
G01Y2253866D02*
X1697345Y2255266D01*
G01X1689845Y2259779D02*
Y2262019D01*
G01Y2260899D02*
X1697345D01*
G01Y2259779D02*
Y2262019D01*
G01X1689845Y2266532D02*
X1697345D01*
Y2270266D01*
G01X1689845Y2274032D02*
X1697345D01*
Y2277766D01*
G01X1699845Y2282932D02*
X1698595Y2281999D01*
X1697345Y2281532D01*
X1692345D01*
X1691095Y2281999D01*
X1689845Y2282932D01*
G01Y2290899D02*
X1690095Y2290152D01*
X1690720Y2289592D01*
X1691470Y2289219D01*
X1692470Y2288939D01*
X1693595Y2288846D01*
X1694720Y2288939D01*
X1695720Y2289219D01*
X1696470Y2289592D01*
X1697095Y2290152D01*
X1697345Y2290899D01*
X1697095Y2291646D01*
X1696470Y2292206D01*
X1695720Y2292579D01*
X1694720Y2292859D01*
X1693595Y2292952D01*
X1692470Y2292859D01*
X1691470Y2292579D01*
X1690720Y2292206D01*
X1690095Y2291646D01*
X1689845Y2290899D01*
G01X1697595Y2298399D02*
X1697470Y2298212D01*
X1697220D01*
X1697095Y2298399D01*
X1697220Y2298586D01*
X1697470D01*
X1697595Y2298399D01*
G01X1689845Y2305899D02*
X1690095Y2305152D01*
X1690720Y2304592D01*
X1691470Y2304219D01*
X1692470Y2303939D01*
X1693595Y2303846D01*
X1694720Y2303939D01*
X1695720Y2304219D01*
X1696470Y2304592D01*
X1697095Y2305152D01*
X1697345Y2305899D01*
X1697095Y2306646D01*
X1696470Y2307206D01*
X1695720Y2307579D01*
X1694720Y2307859D01*
X1693595Y2307952D01*
X1692470Y2307859D01*
X1691470Y2307579D01*
X1690720Y2307206D01*
X1690095Y2306646D01*
X1689845Y2305899D01*
G01X1697345Y2313399D02*
X1689845D01*
X1691345Y2312279D01*
G01X1697345D02*
Y2314519D01*
G01X1696220Y2318846D02*
X1696845Y2319406D01*
X1697220Y2320059D01*
X1697345Y2320899D01*
X1697095Y2321739D01*
X1696595Y2322392D01*
X1695720Y2322859D01*
X1694720Y2322952D01*
X1693720Y2322766D01*
X1693095Y2322299D01*
X1692595Y2321646D01*
X1692470Y2320992D01*
X1692595Y2320339D01*
X1693095Y2319499D01*
X1689845Y2319779D01*
Y2322299D01*
G01X1697345Y2328212D02*
X1695720Y2328399D01*
X1694345Y2328679D01*
X1693095Y2329052D01*
X1691720Y2329519D01*
X1689845Y2330266D01*
Y2326532D01*
G01X1691470Y2335059D02*
X1689845Y2335526D01*
G01Y2336739D02*
X1691470Y2336272D01*
G01X1699845Y2343866D02*
X1698595Y2344799D01*
X1697345Y2345266D01*
X1692345D01*
X1691095Y2344799D01*
X1689845Y2343866D01*
G01X1705955Y1453504D02*
G03I-2451J0D01*
G01Y1468859D02*
G03I-2451J0D01*
G01Y1499567D02*
G03I-2451J0D01*
G01Y1484213D02*
G03I-2451J0D01*
G01Y1514922D02*
G03I-2451J0D01*
G01Y1555867D02*
G03I-2451J0D01*
G01Y1571221D02*
G03I-2451J0D01*
G01Y1586575D02*
G03I-2451J0D01*
G01Y1601930D02*
G03I-2451J0D01*
G01Y1617284D02*
G03I-2451J0D01*
G01X1709329Y1706669D02*
X1701829D01*
X1708079Y1709096D01*
X1701829Y1711523D01*
X1709329D01*
G01Y1714263D02*
X1701829Y1716596D01*
X1709329Y1718929D01*
G01X1706704Y1718089D02*
Y1715103D01*
G01X1709329Y1722229D02*
X1701829D01*
Y1724563D01*
X1702204Y1725309D01*
X1702704Y1725776D01*
X1703704Y1725963D01*
X1704704Y1725776D01*
X1705329Y1725216D01*
X1705704Y1724563D01*
Y1722229D01*
G01Y1724563D02*
X1709329Y1725963D01*
G01Y1729543D02*
X1701829D01*
G01Y1733089D02*
X1706454Y1729543D01*
G01X1709329Y1733649D02*
X1704329Y1731129D01*
G01X1709579Y1739096D02*
X1709454Y1738909D01*
X1709204D01*
X1709079Y1739096D01*
X1709204Y1739283D01*
X1709454D01*
X1709579Y1739096D01*
G01X1706204D02*
X1706079Y1738909D01*
X1705829D01*
X1705704Y1739096D01*
X1705829Y1739283D01*
X1706079D01*
X1706204Y1739096D01*
G01X1709329Y1744729D02*
X1701829D01*
Y1747063D01*
X1702204Y1747809D01*
X1702704Y1748276D01*
X1703704Y1748463D01*
X1704704Y1748276D01*
X1705329Y1747716D01*
X1705704Y1747063D01*
Y1744729D01*
G01Y1747063D02*
X1709329Y1748463D01*
G01Y1755963D02*
Y1752229D01*
X1701829D01*
Y1755963D01*
G01X1705454Y1754469D02*
Y1752229D01*
G01X1702454Y1763649D02*
X1702079Y1763089D01*
X1701829Y1762436D01*
Y1761689D01*
X1702204Y1760849D01*
X1702829Y1760196D01*
X1703579Y1759729D01*
X1704829Y1759356D01*
X1705954Y1759263D01*
X1707079Y1759449D01*
X1707829Y1759729D01*
X1708579Y1760289D01*
X1709079Y1760943D01*
X1709329Y1761596D01*
Y1762249D01*
X1709079Y1762903D01*
X1708704Y1763463D01*
X1708204Y1763929D01*
G01X1709329Y1769096D02*
X1709204Y1768349D01*
X1708704Y1767696D01*
X1707954Y1767136D01*
X1707079Y1766763D01*
X1706079Y1766576D01*
X1705079D01*
X1704079Y1766763D01*
X1703204Y1767136D01*
X1702454Y1767696D01*
X1701954Y1768349D01*
X1701829Y1769096D01*
X1701954Y1769843D01*
X1702454Y1770496D01*
X1703204Y1771056D01*
X1704079Y1771429D01*
X1705079Y1771616D01*
X1706079D01*
X1707079Y1771429D01*
X1707954Y1771056D01*
X1708704Y1770496D01*
X1709204Y1769843D01*
X1709329Y1769096D01*
G01Y1774169D02*
X1701829D01*
X1708079Y1776596D01*
X1701829Y1779023D01*
X1709329D01*
G01Y1781669D02*
X1701829D01*
X1708079Y1784096D01*
X1701829Y1786523D01*
X1709329D01*
G01Y1793463D02*
Y1789729D01*
X1701829D01*
Y1793463D01*
G01X1705454Y1791969D02*
Y1789729D01*
G01X1709329Y1796949D02*
X1701829D01*
X1709329Y1801243D01*
X1701829D01*
G01X1709329Y1804543D02*
X1701829D01*
Y1806409D01*
X1702204Y1807156D01*
X1702704Y1807716D01*
X1703454Y1808183D01*
X1704329Y1808556D01*
X1705579Y1808649D01*
X1706829Y1808556D01*
X1707704Y1808183D01*
X1708454Y1807716D01*
X1708954Y1807156D01*
X1709329Y1806409D01*
Y1804543D01*
G01Y1815963D02*
Y1812229D01*
X1701829D01*
Y1815963D01*
G01X1705454Y1814469D02*
Y1812229D01*
G01X1709329Y1819543D02*
X1701829D01*
Y1821409D01*
X1702204Y1822156D01*
X1702704Y1822716D01*
X1703454Y1823183D01*
X1704329Y1823556D01*
X1705579Y1823649D01*
X1706829Y1823556D01*
X1707704Y1823183D01*
X1708454Y1822716D01*
X1708954Y1822156D01*
X1709329Y1821409D01*
Y1819543D01*
G01Y1834543D02*
X1701829D01*
Y1836409D01*
X1702204Y1837156D01*
X1702704Y1837716D01*
X1703454Y1838183D01*
X1704329Y1838556D01*
X1705579Y1838649D01*
X1706829Y1838556D01*
X1707704Y1838183D01*
X1708454Y1837716D01*
X1708954Y1837156D01*
X1709329Y1836409D01*
Y1834543D01*
G01Y1842229D02*
X1701829D01*
Y1844563D01*
X1702204Y1845309D01*
X1702704Y1845776D01*
X1703704Y1845963D01*
X1704704Y1845776D01*
X1705329Y1845216D01*
X1705704Y1844563D01*
Y1842229D01*
G01Y1844563D02*
X1709329Y1845963D01*
G01X1701829Y1850476D02*
Y1852716D01*
G01Y1851596D02*
X1709329D01*
G01Y1850476D02*
Y1852716D01*
G01X1701829Y1857229D02*
X1709329D01*
Y1860963D01*
G01X1701829Y1864729D02*
X1709329D01*
Y1868463D01*
G01X1708329Y1879636D02*
X1708954Y1880383D01*
X1709329Y1881223D01*
Y1881969D01*
X1708954Y1882716D01*
X1708329Y1883276D01*
X1707454Y1883556D01*
X1706579Y1883369D01*
X1705829Y1882903D01*
X1705329Y1882063D01*
X1705079Y1880943D01*
X1704579Y1880289D01*
X1703704Y1880009D01*
X1702829Y1880196D01*
X1702204Y1880663D01*
X1701829Y1881316D01*
Y1881969D01*
X1702079Y1882623D01*
X1702704Y1883183D01*
G01X1701829Y1887976D02*
Y1890216D01*
G01Y1889096D02*
X1709329D01*
G01Y1887976D02*
Y1890216D01*
G01X1701829Y1894823D02*
Y1898369D01*
X1709329Y1894823D01*
Y1898369D01*
G01Y1905963D02*
Y1902229D01*
X1701829D01*
Y1905963D01*
G01X1705454Y1904469D02*
Y1902229D01*
G01X1709329Y1917323D02*
X1701829D01*
Y1920869D01*
G01X1705454Y1919563D02*
Y1917323D01*
G01X1709329Y1926596D02*
X1709204Y1925849D01*
X1708704Y1925196D01*
X1707954Y1924636D01*
X1707079Y1924263D01*
X1706079Y1924076D01*
X1705079D01*
X1704079Y1924263D01*
X1703204Y1924636D01*
X1702454Y1925196D01*
X1701954Y1925849D01*
X1701829Y1926596D01*
X1701954Y1927343D01*
X1702454Y1927996D01*
X1703204Y1928556D01*
X1704079Y1928929D01*
X1705079Y1929116D01*
X1706079D01*
X1707079Y1928929D01*
X1707954Y1928556D01*
X1708704Y1927996D01*
X1709204Y1927343D01*
X1709329Y1926596D01*
G01Y1932229D02*
X1701829D01*
Y1934563D01*
X1702204Y1935309D01*
X1702704Y1935776D01*
X1703704Y1935963D01*
X1704704Y1935776D01*
X1705329Y1935216D01*
X1705704Y1934563D01*
Y1932229D01*
G01Y1934563D02*
X1709329Y1935963D01*
G01X1701829Y1949096D02*
X1702079Y1948349D01*
X1702704Y1947789D01*
X1703454Y1947416D01*
X1704454Y1947136D01*
X1705579Y1947043D01*
X1706704Y1947136D01*
X1707704Y1947416D01*
X1708454Y1947789D01*
X1709079Y1948349D01*
X1709329Y1949096D01*
X1709079Y1949843D01*
X1708454Y1950403D01*
X1707704Y1950776D01*
X1706704Y1951056D01*
X1705579Y1951149D01*
X1704454Y1951056D01*
X1703454Y1950776D01*
X1702704Y1950403D01*
X1702079Y1949843D01*
X1701829Y1949096D01*
G01X1709579Y1956596D02*
X1709454Y1956409D01*
X1709204D01*
X1709079Y1956596D01*
X1709204Y1956783D01*
X1709454D01*
X1709579Y1956596D01*
G01X1708204Y1962043D02*
X1708829Y1962603D01*
X1709204Y1963256D01*
X1709329Y1964096D01*
X1709079Y1964936D01*
X1708579Y1965589D01*
X1707704Y1966056D01*
X1706704Y1966149D01*
X1705704Y1965963D01*
X1705079Y1965496D01*
X1704579Y1964843D01*
X1704454Y1964189D01*
X1704579Y1963536D01*
X1705079Y1962696D01*
X1701829Y1962976D01*
Y1965496D01*
G01X1709329Y1969169D02*
X1701829D01*
X1708079Y1971596D01*
X1701829Y1974023D01*
X1709329D01*
G01Y1976669D02*
X1701829D01*
X1708079Y1979096D01*
X1701829Y1981523D01*
X1709329D01*
G01Y1992323D02*
X1701829D01*
Y1995869D01*
G01X1705454Y1994563D02*
Y1992323D01*
G01X1701829Y2000476D02*
Y2002716D01*
G01Y2001596D02*
X1709329D01*
G01Y2000476D02*
Y2002716D01*
G01Y2006949D02*
X1701829D01*
X1709329Y2011243D01*
X1701829D01*
G01Y2015476D02*
Y2017716D01*
G01Y2016596D02*
X1709329D01*
G01Y2015476D02*
Y2017716D01*
G01X1708329Y2022136D02*
X1708954Y2022883D01*
X1709329Y2023723D01*
Y2024469D01*
X1708954Y2025216D01*
X1708329Y2025776D01*
X1707454Y2026056D01*
X1706579Y2025869D01*
X1705829Y2025403D01*
X1705329Y2024563D01*
X1705079Y2023443D01*
X1704579Y2022789D01*
X1703704Y2022509D01*
X1702829Y2022696D01*
X1702204Y2023163D01*
X1701829Y2023816D01*
Y2024469D01*
X1702079Y2025123D01*
X1702704Y2025683D01*
G01X1709329Y2029636D02*
X1701829D01*
G01Y2033556D02*
X1709329D01*
G01X1705579D02*
Y2029636D01*
G01X1709329Y2040963D02*
Y2037229D01*
X1701829D01*
Y2040963D01*
G01X1705454Y2039469D02*
Y2037229D01*
G01X1709329Y2044543D02*
X1701829D01*
Y2046409D01*
X1702204Y2047156D01*
X1702704Y2047716D01*
X1703454Y2048183D01*
X1704329Y2048556D01*
X1705579Y2048649D01*
X1706829Y2048556D01*
X1707704Y2048183D01*
X1708454Y2047716D01*
X1708954Y2047156D01*
X1709329Y2046409D01*
Y2044543D01*
G01Y2059729D02*
X1701829D01*
Y2061969D01*
X1702204Y2062716D01*
X1703079Y2063276D01*
X1704079Y2063463D01*
X1705079Y2063276D01*
X1705829Y2062809D01*
X1706204Y2061969D01*
Y2059729D01*
G01X1701829Y2069096D02*
X1709329D01*
G01X1701829Y2066949D02*
Y2071243D01*
G01X1709329Y2074636D02*
X1701829D01*
G01Y2078556D02*
X1709329D01*
G01X1705579D02*
Y2074636D01*
G01X1701829Y2090476D02*
Y2092716D01*
G01Y2091596D02*
X1709329D01*
G01Y2090476D02*
Y2092716D01*
G01X1708329Y2097136D02*
X1708954Y2097883D01*
X1709329Y2098723D01*
Y2099469D01*
X1708954Y2100216D01*
X1708329Y2100776D01*
X1707454Y2101056D01*
X1706579Y2100869D01*
X1705829Y2100403D01*
X1705329Y2099563D01*
X1705079Y2098443D01*
X1704579Y2097789D01*
X1703704Y2097509D01*
X1702829Y2097696D01*
X1702204Y2098163D01*
X1701829Y2098816D01*
Y2099469D01*
X1702079Y2100123D01*
X1702704Y2100683D01*
G01X1701829Y2114096D02*
X1702079Y2113349D01*
X1702704Y2112789D01*
X1703454Y2112416D01*
X1704454Y2112136D01*
X1705579Y2112043D01*
X1706704Y2112136D01*
X1707704Y2112416D01*
X1708454Y2112789D01*
X1709079Y2113349D01*
X1709329Y2114096D01*
X1709079Y2114843D01*
X1708454Y2115403D01*
X1707704Y2115776D01*
X1706704Y2116056D01*
X1705579Y2116149D01*
X1704454Y2116056D01*
X1703454Y2115776D01*
X1702704Y2115403D01*
X1702079Y2114843D01*
X1701829Y2114096D01*
G01X1709579Y2121596D02*
X1709454Y2121409D01*
X1709204D01*
X1709079Y2121596D01*
X1709204Y2121783D01*
X1709454D01*
X1709579Y2121596D01*
G01X1706204Y2127323D02*
X1705329Y2127976D01*
X1704829Y2128536D01*
X1704579Y2129283D01*
X1704829Y2129936D01*
X1705329Y2130403D01*
X1706079Y2130776D01*
X1706954Y2130869D01*
X1707704Y2130776D01*
X1708454Y2130403D01*
X1709079Y2129843D01*
X1709329Y2129189D01*
X1709079Y2128443D01*
X1708329Y2127789D01*
X1707204Y2127416D01*
X1705954Y2127323D01*
X1704329Y2127509D01*
X1703454Y2127789D01*
X1702579Y2128256D01*
X1701954Y2128909D01*
X1701829Y2129563D01*
X1702079Y2130216D01*
X1702704Y2130683D01*
G01X1709329Y2134169D02*
X1701829D01*
X1708079Y2136596D01*
X1701829Y2139023D01*
X1709329D01*
G01Y2141669D02*
X1701829D01*
X1708079Y2144096D01*
X1701829Y2146523D01*
X1709329D01*
G01Y2156669D02*
X1701829D01*
X1708079Y2159096D01*
X1701829Y2161523D01*
X1709329D01*
G01Y2168463D02*
Y2164729D01*
X1701829D01*
Y2168463D01*
G01X1705454Y2166969D02*
Y2164729D01*
G01X1701829Y2174096D02*
X1709329D01*
G01X1701829Y2171949D02*
Y2176243D01*
G01X1709329Y2179729D02*
X1701829D01*
Y2182063D01*
X1702204Y2182809D01*
X1702704Y2183276D01*
X1703704Y2183463D01*
X1704704Y2183276D01*
X1705329Y2182716D01*
X1705704Y2182063D01*
Y2179729D01*
G01Y2182063D02*
X1709329Y2183463D01*
G01X1701829Y2187976D02*
Y2190216D01*
G01Y2189096D02*
X1709329D01*
G01Y2187976D02*
Y2190216D01*
G01X1702454Y2198649D02*
X1702079Y2198089D01*
X1701829Y2197436D01*
Y2196689D01*
X1702204Y2195849D01*
X1702829Y2195196D01*
X1703579Y2194729D01*
X1704829Y2194356D01*
X1705954Y2194263D01*
X1707079Y2194449D01*
X1707829Y2194729D01*
X1708579Y2195289D01*
X1709079Y2195943D01*
X1709329Y2196596D01*
Y2197249D01*
X1709079Y2197903D01*
X1708704Y2198463D01*
X1708204Y2198929D01*
G01X1709329Y2209543D02*
X1701829D01*
Y2211409D01*
X1702204Y2212156D01*
X1702704Y2212716D01*
X1703454Y2213183D01*
X1704329Y2213556D01*
X1705579Y2213649D01*
X1706829Y2213556D01*
X1707704Y2213183D01*
X1708454Y2212716D01*
X1708954Y2212156D01*
X1709329Y2211409D01*
Y2209543D01*
G01Y2217229D02*
X1701829D01*
Y2219563D01*
X1702204Y2220309D01*
X1702704Y2220776D01*
X1703704Y2220963D01*
X1704704Y2220776D01*
X1705329Y2220216D01*
X1705704Y2219563D01*
Y2217229D01*
G01Y2219563D02*
X1709329Y2220963D01*
G01X1701829Y2225476D02*
Y2227716D01*
G01Y2226596D02*
X1709329D01*
G01Y2225476D02*
Y2227716D01*
G01X1701829Y2232229D02*
X1709329D01*
Y2235963D01*
G01X1701829Y2239729D02*
X1709329D01*
Y2243463D01*
G01X1711829Y2248629D02*
X1710579Y2247696D01*
X1709329Y2247229D01*
X1704329D01*
X1703079Y2247696D01*
X1701829Y2248629D01*
G01Y2256596D02*
X1702079Y2255849D01*
X1702704Y2255289D01*
X1703454Y2254916D01*
X1704454Y2254636D01*
X1705579Y2254543D01*
X1706704Y2254636D01*
X1707704Y2254916D01*
X1708454Y2255289D01*
X1709079Y2255849D01*
X1709329Y2256596D01*
X1709079Y2257343D01*
X1708454Y2257903D01*
X1707704Y2258276D01*
X1706704Y2258556D01*
X1705579Y2258649D01*
X1704454Y2258556D01*
X1703454Y2258276D01*
X1702704Y2257903D01*
X1702079Y2257343D01*
X1701829Y2256596D01*
G01X1709579Y2264096D02*
X1709454Y2263909D01*
X1709204D01*
X1709079Y2264096D01*
X1709204Y2264283D01*
X1709454D01*
X1709579Y2264096D01*
G01X1701829Y2271596D02*
X1702079Y2270849D01*
X1702704Y2270289D01*
X1703454Y2269916D01*
X1704454Y2269636D01*
X1705579Y2269543D01*
X1706704Y2269636D01*
X1707704Y2269916D01*
X1708454Y2270289D01*
X1709079Y2270849D01*
X1709329Y2271596D01*
X1709079Y2272343D01*
X1708454Y2272903D01*
X1707704Y2273276D01*
X1706704Y2273556D01*
X1705579Y2273649D01*
X1704454Y2273556D01*
X1703454Y2273276D01*
X1702704Y2272903D01*
X1702079Y2272343D01*
X1701829Y2271596D01*
G01X1703079Y2277323D02*
X1702329Y2277883D01*
X1701954Y2278536D01*
X1701829Y2279283D01*
X1702079Y2280216D01*
X1702704Y2280869D01*
X1703454Y2281056D01*
X1704204Y2280963D01*
X1704829Y2280589D01*
X1706079Y2278723D01*
X1706954Y2277883D01*
X1708204Y2277323D01*
X1709329Y2277136D01*
Y2281056D01*
G01X1707829Y2284543D02*
X1708704Y2285103D01*
X1709204Y2285849D01*
X1709329Y2286689D01*
X1709204Y2287436D01*
X1708579Y2288183D01*
X1707829Y2288649D01*
X1707079Y2288743D01*
X1706204Y2288556D01*
X1705579Y2287903D01*
X1705329Y2287249D01*
Y2286409D01*
G01Y2287249D02*
X1704954Y2287809D01*
X1704329Y2288276D01*
X1703579Y2288463D01*
X1702829Y2288276D01*
X1702204Y2287809D01*
X1701829Y2286969D01*
X1701954Y2286129D01*
X1702454Y2285289D01*
G01X1706204Y2292323D02*
X1705329Y2292976D01*
X1704829Y2293536D01*
X1704579Y2294283D01*
X1704829Y2294936D01*
X1705329Y2295403D01*
X1706079Y2295776D01*
X1706954Y2295869D01*
X1707704Y2295776D01*
X1708454Y2295403D01*
X1709079Y2294843D01*
X1709329Y2294189D01*
X1709079Y2293443D01*
X1708329Y2292789D01*
X1707204Y2292416D01*
X1705954Y2292323D01*
X1704329Y2292509D01*
X1703454Y2292789D01*
X1702579Y2293256D01*
X1701954Y2293909D01*
X1701829Y2294563D01*
X1702079Y2295216D01*
X1702704Y2295683D01*
G01X1703454Y2300756D02*
X1701829Y2301223D01*
G01Y2302436D02*
X1703454Y2301969D01*
G01X1711829Y2309563D02*
X1710579Y2310496D01*
X1709329Y2310963D01*
X1704329D01*
X1703079Y2310496D01*
X1701829Y2309563D01*
G01X1730462Y-444645D02*
X1717962D01*
X1720462Y-446505D01*
G01X1730462D02*
Y-442785D01*
G01Y-432555D02*
X1727754Y-432245D01*
X1725462Y-431780D01*
X1723379Y-431160D01*
X1721087Y-430385D01*
X1717962Y-429145D01*
Y-435345D01*
G01X1720045Y-422790D02*
X1718796Y-421860D01*
X1718170Y-420775D01*
X1717962Y-419535D01*
X1718379Y-417985D01*
X1719420Y-416900D01*
X1720670Y-416590D01*
X1721921Y-416745D01*
X1722962Y-417365D01*
X1725045Y-420465D01*
X1726504Y-421860D01*
X1728587Y-422790D01*
X1730462Y-423100D01*
Y-416590D01*
G01Y-405585D02*
X1717962D01*
X1726920Y-411320D01*
Y-403570D01*
G01X1720045Y-397990D02*
X1718796Y-397060D01*
X1718170Y-395975D01*
X1717962Y-394735D01*
X1718379Y-393185D01*
X1719420Y-392100D01*
X1720670Y-391790D01*
X1721921Y-391945D01*
X1722962Y-392565D01*
X1725045Y-395665D01*
X1726504Y-397060D01*
X1728587Y-397990D01*
X1730462Y-398300D01*
Y-391790D01*
G01X1730879Y-382645D02*
X1730670Y-382955D01*
X1730254D01*
X1730045Y-382645D01*
X1730254Y-382335D01*
X1730670D01*
X1730879Y-382645D01*
G01X1730462Y-370245D02*
X1717962D01*
X1720462Y-372105D01*
G01X1730462D02*
Y-368385D01*
G01X1720045Y-360790D02*
X1718796Y-359860D01*
X1718170Y-358775D01*
X1717962Y-357535D01*
X1718379Y-355985D01*
X1719420Y-354900D01*
X1720670Y-354590D01*
X1721921Y-354745D01*
X1722962Y-355365D01*
X1725045Y-358465D01*
X1726504Y-359860D01*
X1728587Y-360790D01*
X1730462Y-361100D01*
Y-354590D01*
G01Y-321385D02*
X1717962D01*
X1726920Y-327120D01*
Y-319370D01*
G01X1727962Y-314255D02*
X1729421Y-313325D01*
X1730254Y-312085D01*
X1730462Y-310690D01*
X1730254Y-309450D01*
X1729212Y-308210D01*
X1727962Y-307435D01*
X1726712Y-307280D01*
X1725254Y-307590D01*
X1724212Y-308675D01*
X1723795Y-309760D01*
Y-311155D01*
G01Y-309760D02*
X1723170Y-308830D01*
X1722129Y-308055D01*
X1720879Y-307745D01*
X1719629Y-308055D01*
X1718587Y-308830D01*
X1717962Y-310225D01*
X1718170Y-311620D01*
X1719004Y-313015D01*
G01X1730462Y-298755D02*
X1727754Y-298445D01*
X1725462Y-297980D01*
X1723379Y-297360D01*
X1721087Y-296585D01*
X1717962Y-295345D01*
Y-301545D01*
G01X1730879Y-286045D02*
X1730670Y-286355D01*
X1730254D01*
X1730045Y-286045D01*
X1730254Y-285735D01*
X1730670D01*
X1730879Y-286045D01*
G01X1729004Y-276280D02*
X1730045Y-275195D01*
X1730462Y-273955D01*
X1730045Y-272715D01*
X1728796Y-271630D01*
X1726920Y-270855D01*
X1725045Y-270545D01*
X1722754D01*
X1720879Y-270855D01*
X1719212Y-271630D01*
X1718379Y-272560D01*
X1717962Y-273645D01*
X1718379Y-274885D01*
X1719212Y-275815D01*
X1720462Y-276435D01*
X1722129Y-276745D01*
X1723587Y-276435D01*
X1725045Y-275660D01*
X1725879Y-274730D01*
X1726087Y-273645D01*
X1725671Y-272405D01*
X1724629Y-271475D01*
X1722754Y-270545D01*
G01X1728587Y-264655D02*
X1729629Y-263725D01*
X1730254Y-262640D01*
X1730462Y-261245D01*
X1730045Y-259850D01*
X1729212Y-258765D01*
X1727754Y-257990D01*
X1726087Y-257835D01*
X1724420Y-258145D01*
X1723379Y-258920D01*
X1722545Y-260005D01*
X1722337Y-261090D01*
X1722545Y-262175D01*
X1723379Y-263570D01*
X1717962Y-263105D01*
Y-258920D01*
G01X1723278Y1453504D02*
G03I-2452J0D01*
G01X1714617Y1457835D02*
G03I-2452J0D01*
G01X1723278Y1468859D02*
G03I-2452J0D01*
G01X1714617Y1473189D02*
G03I-2452J0D01*
G01X1723278Y1499567D02*
G03I-2452J0D01*
G01Y1484213D02*
G03I-2452J0D01*
G01X1714617Y1488544D02*
G03I-2452J0D01*
G01X1723278Y1514922D02*
G03I-2452J0D01*
G01X1714617Y1503898D02*
G03I-2452J0D01*
G01Y1519252D02*
G03I-2452J0D01*
G01X1723278Y1555867D02*
G03I-2452J0D01*
G01X1714617Y1560197D02*
G03I-2452J0D01*
G01X1723278Y1571221D02*
G03I-2452J0D01*
G01X1714617Y1575552D02*
G03I-2452J0D01*
G01X1723278Y1586575D02*
G03I-2452J0D01*
G01X1714617Y1590906D02*
G03I-2452J0D01*
G01X1723278Y1601930D02*
G03I-2452J0D01*
G01X1714617Y1606260D02*
G03I-2452J0D01*
G01X1723278Y1617284D02*
G03I-2452J0D01*
G01X1714617Y1621615D02*
G03I-2452J0D01*
G01X1731940Y1457835D02*
G03I-2452J0D01*
G01Y1473189D02*
G03I-2452J0D01*
G01Y1488544D02*
G03I-2452J0D01*
G01Y1503898D02*
G03I-2452J0D01*
G01Y1519252D02*
G03I-2452J0D01*
G01X1731939Y1560197D02*
G03I-2451J0D01*
G01X1731940Y1575552D02*
G03I-2452J0D01*
G01Y1590906D02*
G03I-2452J0D01*
G01X1731939Y1606260D02*
G03I-2451J0D01*
G01X1731940Y1621615D02*
G03I-2452J0D01*
G01X1850202Y49483D02*
Y57483D01*
X1854802Y49483D01*
Y57483D01*
G01X1858502Y49483D02*
Y57483D01*
X1860902D01*
X1861702Y57083D01*
X1862302Y56150D01*
X1862502Y55083D01*
X1862302Y54016D01*
X1861802Y53216D01*
X1860902Y52816D01*
X1858502D01*
G01X1868502Y57483D02*
Y49483D01*
G01X1866202Y57483D02*
X1870802D01*
G01X1874402Y49483D02*
Y57483D01*
G01X1878602D02*
Y49483D01*
G01Y53483D02*
X1874402D01*
G01X1900502Y57483D02*
Y49483D01*
G01X1898202Y57483D02*
X1902802D01*
G01X1908502Y49483D02*
X1907702Y49616D01*
X1907002Y50150D01*
X1906402Y50950D01*
X1906002Y51883D01*
X1905802Y52950D01*
Y54016D01*
X1906002Y55083D01*
X1906402Y56016D01*
X1907002Y56816D01*
X1907702Y57350D01*
X1908502Y57483D01*
X1909302Y57350D01*
X1910002Y56816D01*
X1910602Y56016D01*
X1911002Y55083D01*
X1911202Y54016D01*
Y52950D01*
X1911002Y51883D01*
X1910602Y50950D01*
X1910002Y50150D01*
X1909302Y49616D01*
X1908502Y49483D01*
G01X1914502Y57483D02*
Y49483D01*
X1918502D01*
G01X1926502D02*
X1922502D01*
Y57483D01*
X1926502D01*
G01X1924902Y53616D02*
X1922502D01*
G01X1930202Y49483D02*
Y57483D01*
X1934802Y49483D01*
Y57483D01*
G01X1938002Y49483D02*
X1940502Y57483D01*
X1943002Y49483D01*
G01X1942102Y52283D02*
X1938902D01*
G01X1946202Y49483D02*
Y57483D01*
X1950802Y49483D01*
Y57483D01*
G01X1958702Y56816D02*
X1958102Y57216D01*
X1957402Y57483D01*
X1956602D01*
X1955702Y57083D01*
X1955002Y56416D01*
X1954502Y55616D01*
X1954102Y54283D01*
X1954002Y53083D01*
X1954202Y51883D01*
X1954502Y51083D01*
X1955102Y50283D01*
X1955802Y49750D01*
X1956502Y49483D01*
X1957202D01*
X1957902Y49750D01*
X1958502Y50150D01*
X1959002Y50683D01*
G01X1966502Y49483D02*
X1962502D01*
Y57483D01*
X1966502D01*
G01X1964902Y53616D02*
X1962502D01*
G01X1972502Y49216D02*
X1972302Y49350D01*
Y49616D01*
X1972502Y49750D01*
X1972702Y49616D01*
Y49350D01*
X1972502Y49216D01*
G01Y52816D02*
X1972302Y52950D01*
Y53216D01*
X1972502Y53350D01*
X1972702Y53216D01*
Y52950D01*
X1972502Y52816D01*
G01X1979402Y52150D02*
X1981802D01*
G01X1980502Y53883D02*
Y50416D01*
G01X1986602Y56150D02*
X1987202Y56950D01*
X1987902Y57350D01*
X1988702Y57483D01*
X1989702Y57216D01*
X1990402Y56550D01*
X1990602Y55750D01*
X1990502Y54949D01*
X1990102Y54283D01*
X1988102Y52950D01*
X1987202Y52016D01*
X1986602Y50683D01*
X1986402Y49483D01*
X1990602D01*
G01X1994702Y49216D02*
X1998302Y57483D01*
G01X2003202Y52150D02*
X2005802D01*
G01X2010602Y56150D02*
X2011202Y56950D01*
X2011902Y57350D01*
X2012702Y57483D01*
X2013702Y57216D01*
X2014402Y56550D01*
X2014602Y55750D01*
X2014502Y54949D01*
X2014102Y54283D01*
X2012102Y52950D01*
X2011202Y52016D01*
X2010602Y50683D01*
X2010402Y49483D01*
X2014602D01*
G01X2025502D02*
Y54816D01*
G01Y53350D02*
X2025802Y54016D01*
X2026302Y54550D01*
X2027002Y54816D01*
X2027702Y54550D01*
X2028202Y54016D01*
X2028502Y53350D01*
Y49483D01*
G01Y53350D02*
X2028802Y54016D01*
X2029302Y54550D01*
X2030002Y54816D01*
X2030702Y54550D01*
X2031202Y54016D01*
X2031502Y53216D01*
Y49483D01*
G01X2036502Y54816D02*
Y49483D01*
G01Y56950D02*
X2036302Y57083D01*
Y57350D01*
X2036502Y57483D01*
X2036702Y57350D01*
Y57083D01*
X2036502Y56950D01*
G01X2044502Y49483D02*
Y57483D01*
G01X1874695Y720596D02*
X1862195D01*
X1864695Y718736D01*
G01X1874695D02*
Y722456D01*
G01X1869487Y730051D02*
X1868028Y731136D01*
X1867195Y732066D01*
X1866778Y733306D01*
X1867195Y734391D01*
X1868028Y735166D01*
X1869278Y735786D01*
X1870737Y735941D01*
X1871987Y735786D01*
X1873237Y735166D01*
X1874278Y734236D01*
X1874695Y733151D01*
X1874278Y731911D01*
X1873029Y730826D01*
X1871153Y730206D01*
X1869070Y730051D01*
X1866362Y730361D01*
X1864903Y730826D01*
X1863445Y731601D01*
X1862403Y732686D01*
X1862195Y733771D01*
X1862612Y734856D01*
X1863653Y735631D01*
G01X1874695Y747256D02*
X1862195D01*
X1871153Y741521D01*
Y749271D01*
G01X1874695Y757486D02*
X1871987Y757796D01*
X1869695Y758261D01*
X1867612Y758881D01*
X1865320Y759656D01*
X1862195Y760896D01*
Y754696D01*
G01X1873237Y767561D02*
X1874278Y768646D01*
X1874695Y769886D01*
X1874278Y771126D01*
X1873029Y772211D01*
X1871153Y772986D01*
X1869278Y773296D01*
X1866987D01*
X1865112Y772986D01*
X1863445Y772211D01*
X1862612Y771281D01*
X1862195Y770196D01*
X1862612Y768956D01*
X1863445Y768026D01*
X1864695Y767406D01*
X1866362Y767096D01*
X1867820Y767406D01*
X1869278Y768181D01*
X1870112Y769111D01*
X1870320Y770196D01*
X1869904Y771436D01*
X1868862Y772366D01*
X1866987Y773296D01*
G01X1875112Y782596D02*
X1874903Y782286D01*
X1874487D01*
X1874278Y782596D01*
X1874487Y782906D01*
X1874903D01*
X1875112Y782596D01*
G01X1873237Y792361D02*
X1874278Y793446D01*
X1874695Y794686D01*
X1874278Y795926D01*
X1873029Y797011D01*
X1871153Y797786D01*
X1869278Y798096D01*
X1866987D01*
X1865112Y797786D01*
X1863445Y797011D01*
X1862612Y796081D01*
X1862195Y794996D01*
X1862612Y793756D01*
X1863445Y792826D01*
X1864695Y792206D01*
X1866362Y791896D01*
X1867820Y792206D01*
X1869278Y792981D01*
X1870112Y793911D01*
X1870320Y794996D01*
X1869904Y796236D01*
X1868862Y797166D01*
X1866987Y798096D01*
G01X1864278Y804451D02*
X1863029Y805381D01*
X1862403Y806466D01*
X1862195Y807706D01*
X1862612Y809256D01*
X1863653Y810341D01*
X1864903Y810651D01*
X1866154Y810496D01*
X1867195Y809876D01*
X1869278Y806776D01*
X1870737Y805381D01*
X1872820Y804451D01*
X1874695Y804141D01*
Y810651D01*
G01X1899695Y735006D02*
X1887195D01*
X1896153Y729271D01*
Y737021D01*
G01X1899695Y745546D02*
X1887195D01*
X1889695Y743686D01*
G01X1899695D02*
Y747406D01*
G01Y757946D02*
X1899487Y759031D01*
X1898862Y760271D01*
X1897820Y761046D01*
X1896362Y761356D01*
X1894904Y761046D01*
X1893653Y760116D01*
X1893028Y758721D01*
Y757171D01*
X1892612Y756241D01*
X1891570Y755466D01*
X1890112Y755156D01*
X1888653Y755621D01*
X1887612Y756706D01*
X1887195Y757946D01*
X1887612Y759186D01*
X1888653Y760271D01*
X1890112Y760736D01*
X1891570Y760426D01*
X1892612Y759651D01*
X1893028Y758721D01*
Y757171D01*
X1893653Y755776D01*
X1894904Y754846D01*
X1896362Y754536D01*
X1897820Y754846D01*
X1898862Y755621D01*
X1899487Y756861D01*
X1899695Y757946D01*
G01X1900112Y770346D02*
X1899903Y770036D01*
X1899487D01*
X1899278Y770346D01*
X1899487Y770656D01*
X1899903D01*
X1900112Y770346D01*
G01X1897820Y779336D02*
X1898862Y780266D01*
X1899487Y781351D01*
X1899695Y782746D01*
X1899278Y784141D01*
X1898445Y785226D01*
X1896987Y786001D01*
X1895320Y786156D01*
X1893653Y785846D01*
X1892612Y785071D01*
X1891778Y783986D01*
X1891570Y782901D01*
X1891778Y781816D01*
X1892612Y780421D01*
X1887195Y780886D01*
Y785071D01*
G01X1898237Y792511D02*
X1899278Y793596D01*
X1899695Y794836D01*
X1899278Y796076D01*
X1898029Y797161D01*
X1896153Y797936D01*
X1894278Y798246D01*
X1891987D01*
X1890112Y797936D01*
X1888445Y797161D01*
X1887612Y796231D01*
X1887195Y795146D01*
X1887612Y793906D01*
X1888445Y792976D01*
X1889695Y792356D01*
X1891362Y792046D01*
X1892820Y792356D01*
X1894278Y793131D01*
X1895112Y794061D01*
X1895320Y795146D01*
X1894904Y796386D01*
X1893862Y797316D01*
X1891987Y798246D01*
G01X2097718Y1060285D02*
Y1072785D01*
X2095858Y1070285D01*
G01Y1060285D02*
X2099578D01*
G01X2110118Y1072785D02*
X2108878Y1072368D01*
X2107948Y1071327D01*
X2107328Y1070077D01*
X2106863Y1068410D01*
X2106708Y1066535D01*
X2106863Y1064660D01*
X2107328Y1062993D01*
X2107948Y1061743D01*
X2108878Y1060702D01*
X2110118Y1060285D01*
X2111358Y1060702D01*
X2112288Y1061743D01*
X2112908Y1062993D01*
X2113373Y1064660D01*
X2113528Y1066535D01*
X2113373Y1068410D01*
X2112908Y1070077D01*
X2112288Y1071327D01*
X2111358Y1072368D01*
X2110118Y1072785D01*
G01X2119573Y1065493D02*
X2120658Y1066952D01*
X2121588Y1067785D01*
X2122828Y1068202D01*
X2123913Y1067785D01*
X2124688Y1066952D01*
X2125308Y1065702D01*
X2125463Y1064243D01*
X2125308Y1062993D01*
X2124688Y1061743D01*
X2123758Y1060702D01*
X2122673Y1060285D01*
X2121433Y1060702D01*
X2120348Y1061951D01*
X2119728Y1063827D01*
X2119573Y1065910D01*
X2119883Y1068618D01*
X2120348Y1070077D01*
X2121123Y1071535D01*
X2122208Y1072577D01*
X2123293Y1072785D01*
X2124378Y1072368D01*
X2125153Y1071327D01*
G01X2131973Y1065493D02*
X2133058Y1066952D01*
X2133988Y1067785D01*
X2135228Y1068202D01*
X2136313Y1067785D01*
X2137088Y1066952D01*
X2137708Y1065702D01*
X2137863Y1064243D01*
X2137708Y1062993D01*
X2137088Y1061743D01*
X2136158Y1060702D01*
X2135073Y1060285D01*
X2133833Y1060702D01*
X2132748Y1061951D01*
X2132128Y1063827D01*
X2131973Y1065910D01*
X2132283Y1068618D01*
X2132748Y1070077D01*
X2133523Y1071535D01*
X2134608Y1072577D01*
X2135693Y1072785D01*
X2136778Y1072368D01*
X2137553Y1071327D01*
G01X2143908Y1062160D02*
X2144838Y1061118D01*
X2145923Y1060493D01*
X2147318Y1060285D01*
X2148713Y1060702D01*
X2149798Y1061535D01*
X2150573Y1062993D01*
X2150728Y1064660D01*
X2150418Y1066327D01*
X2149643Y1067368D01*
X2148558Y1068202D01*
X2147473Y1068410D01*
X2146388Y1068202D01*
X2144993Y1067368D01*
X2145458Y1072785D01*
X2149643D01*
G01X2159718Y1059868D02*
X2159408Y1060077D01*
Y1060493D01*
X2159718Y1060702D01*
X2160028Y1060493D01*
Y1060077D01*
X2159718Y1059868D01*
G01X2168708Y1062785D02*
X2169638Y1061326D01*
X2170878Y1060493D01*
X2172273Y1060285D01*
X2173513Y1060493D01*
X2174753Y1061535D01*
X2175528Y1062785D01*
X2175683Y1064035D01*
X2175373Y1065493D01*
X2174288Y1066535D01*
X2173203Y1066952D01*
X2171808D01*
G01X2173203D02*
X2174133Y1067577D01*
X2174908Y1068618D01*
X2175218Y1069868D01*
X2174908Y1071118D01*
X2174133Y1072160D01*
X2172738Y1072785D01*
X2171343Y1072577D01*
X2169948Y1071743D01*
G01X2181108Y1062160D02*
X2182038Y1061118D01*
X2183123Y1060493D01*
X2184518Y1060285D01*
X2185913Y1060702D01*
X2186998Y1061535D01*
X2187773Y1062993D01*
X2187928Y1064660D01*
X2187618Y1066327D01*
X2186843Y1067368D01*
X2185758Y1068202D01*
X2184673Y1068410D01*
X2183588Y1068202D01*
X2182193Y1067368D01*
X2182658Y1072785D01*
X2186843D01*
G01X2107325Y1257136D02*
Y1269636D01*
X2105465Y1267136D01*
G01Y1257136D02*
X2109185D01*
G01X2116780Y1267553D02*
X2117710Y1268802D01*
X2118795Y1269428D01*
X2120035Y1269636D01*
X2121585Y1269219D01*
X2122670Y1268178D01*
X2122980Y1266928D01*
X2122825Y1265677D01*
X2122205Y1264636D01*
X2119105Y1262553D01*
X2117710Y1261094D01*
X2116780Y1259011D01*
X2116470Y1257136D01*
X2122980D01*
G01X2129180Y1262344D02*
X2130265Y1263803D01*
X2131195Y1264636D01*
X2132435Y1265053D01*
X2133520Y1264636D01*
X2134295Y1263803D01*
X2134915Y1262553D01*
X2135070Y1261094D01*
X2134915Y1259844D01*
X2134295Y1258594D01*
X2133365Y1257553D01*
X2132280Y1257136D01*
X2131040Y1257553D01*
X2129955Y1258802D01*
X2129335Y1260678D01*
X2129180Y1262761D01*
X2129490Y1265469D01*
X2129955Y1266928D01*
X2130730Y1268386D01*
X2131815Y1269428D01*
X2132900Y1269636D01*
X2133985Y1269219D01*
X2134760Y1268178D01*
G01X2141115Y1259636D02*
X2142045Y1258177D01*
X2143285Y1257344D01*
X2144680Y1257136D01*
X2145920Y1257344D01*
X2147160Y1258386D01*
X2147935Y1259636D01*
X2148090Y1260886D01*
X2147780Y1262344D01*
X2146695Y1263386D01*
X2145610Y1263803D01*
X2144215D01*
G01X2145610D02*
X2146540Y1264428D01*
X2147315Y1265469D01*
X2147625Y1266719D01*
X2147315Y1267969D01*
X2146540Y1269011D01*
X2145145Y1269636D01*
X2143750Y1269428D01*
X2142355Y1268594D01*
G01X2153515Y1259636D02*
X2154445Y1258177D01*
X2155685Y1257344D01*
X2157080Y1257136D01*
X2158320Y1257344D01*
X2159560Y1258386D01*
X2160335Y1259636D01*
X2160490Y1260886D01*
X2160180Y1262344D01*
X2159095Y1263386D01*
X2158010Y1263803D01*
X2156615D01*
G01X2158010D02*
X2158940Y1264428D01*
X2159715Y1265469D01*
X2160025Y1266719D01*
X2159715Y1267969D01*
X2158940Y1269011D01*
X2157545Y1269636D01*
X2156150Y1269428D01*
X2154755Y1268594D01*
G01X2169325Y1256719D02*
X2169015Y1256928D01*
Y1257344D01*
X2169325Y1257553D01*
X2169635Y1257344D01*
Y1256928D01*
X2169325Y1256719D01*
G01X2181725Y1257136D02*
X2182810Y1257344D01*
X2184050Y1257969D01*
X2184825Y1259011D01*
X2185135Y1260469D01*
X2184825Y1261927D01*
X2183895Y1263178D01*
X2182500Y1263803D01*
X2180950D01*
X2180020Y1264219D01*
X2179245Y1265261D01*
X2178935Y1266719D01*
X2179400Y1268178D01*
X2180485Y1269219D01*
X2181725Y1269636D01*
X2182965Y1269219D01*
X2184050Y1268178D01*
X2184515Y1266719D01*
X2184205Y1265261D01*
X2183430Y1264219D01*
X2182500Y1263803D01*
X2180950D01*
X2179555Y1263178D01*
X2178625Y1261927D01*
X2178315Y1260469D01*
X2178625Y1259011D01*
X2179400Y1257969D01*
X2180640Y1257344D01*
X2181725Y1257136D01*
G01X2191180Y1262344D02*
X2192265Y1263803D01*
X2193195Y1264636D01*
X2194435Y1265053D01*
X2195520Y1264636D01*
X2196295Y1263803D01*
X2196915Y1262553D01*
X2197070Y1261094D01*
X2196915Y1259844D01*
X2196295Y1258594D01*
X2195365Y1257553D01*
X2194280Y1257136D01*
X2193040Y1257553D01*
X2191955Y1258802D01*
X2191335Y1260678D01*
X2191180Y1262761D01*
X2191490Y1265469D01*
X2191955Y1266928D01*
X2192730Y1268386D01*
X2193815Y1269428D01*
X2194900Y1269636D01*
X2195985Y1269219D01*
X2196760Y1268178D01*
G01X2167864Y384833D02*
X2168794Y383374D01*
X2170034Y382541D01*
X2171429Y382333D01*
X2172669Y382541D01*
X2173909Y383583D01*
X2174684Y384833D01*
X2174839Y386083D01*
X2174529Y387541D01*
X2173444Y388583D01*
X2172359Y389000D01*
X2170964D01*
G01X2172359D02*
X2173289Y389625D01*
X2174064Y390666D01*
X2174374Y391916D01*
X2174064Y393166D01*
X2173289Y394208D01*
X2171894Y394833D01*
X2170499Y394625D01*
X2169104Y393791D01*
G01X2183674Y382333D02*
X2184759Y382541D01*
X2185999Y383166D01*
X2186774Y384208D01*
X2187084Y385666D01*
X2186774Y387124D01*
X2185844Y388375D01*
X2184449Y389000D01*
X2182899D01*
X2181969Y389416D01*
X2181194Y390458D01*
X2180884Y391916D01*
X2181349Y393375D01*
X2182434Y394416D01*
X2183674Y394833D01*
X2184914Y394416D01*
X2185999Y393375D01*
X2186464Y391916D01*
X2186154Y390458D01*
X2185379Y389416D01*
X2184449Y389000D01*
X2182899D01*
X2181504Y388375D01*
X2180574Y387124D01*
X2180264Y385666D01*
X2180574Y384208D01*
X2181349Y383166D01*
X2182589Y382541D01*
X2183674Y382333D01*
G01X2196074D02*
X2197159Y382541D01*
X2198399Y383166D01*
X2199174Y384208D01*
X2199484Y385666D01*
X2199174Y387124D01*
X2198244Y388375D01*
X2196849Y389000D01*
X2195299D01*
X2194369Y389416D01*
X2193594Y390458D01*
X2193284Y391916D01*
X2193749Y393375D01*
X2194834Y394416D01*
X2196074Y394833D01*
X2197314Y394416D01*
X2198399Y393375D01*
X2198864Y391916D01*
X2198554Y390458D01*
X2197779Y389416D01*
X2196849Y389000D01*
X2195299D01*
X2193904Y388375D01*
X2192974Y387124D01*
X2192664Y385666D01*
X2192974Y384208D01*
X2193749Y383166D01*
X2194989Y382541D01*
X2196074Y382333D01*
G01X2205064Y384208D02*
X2205994Y383166D01*
X2207079Y382541D01*
X2208474Y382333D01*
X2209869Y382750D01*
X2210954Y383583D01*
X2211729Y385041D01*
X2211884Y386708D01*
X2211574Y388375D01*
X2210799Y389416D01*
X2209714Y390250D01*
X2208629Y390458D01*
X2207544Y390250D01*
X2206149Y389416D01*
X2206614Y394833D01*
X2210799D01*
G01X2220874Y381916D02*
X2220564Y382125D01*
Y382541D01*
X2220874Y382750D01*
X2221184Y382541D01*
Y382125D01*
X2220874Y381916D01*
G01X2233274Y382333D02*
X2234359Y382541D01*
X2235599Y383166D01*
X2236374Y384208D01*
X2236684Y385666D01*
X2236374Y387124D01*
X2235444Y388375D01*
X2234049Y389000D01*
X2232499D01*
X2231569Y389416D01*
X2230794Y390458D01*
X2230484Y391916D01*
X2230949Y393375D01*
X2232034Y394416D01*
X2233274Y394833D01*
X2234514Y394416D01*
X2235599Y393375D01*
X2236064Y391916D01*
X2235754Y390458D01*
X2234979Y389416D01*
X2234049Y389000D01*
X2232499D01*
X2231104Y388375D01*
X2230174Y387124D01*
X2229864Y385666D01*
X2230174Y384208D01*
X2230949Y383166D01*
X2232189Y382541D01*
X2233274Y382333D01*
G01X2242264Y384833D02*
X2243194Y383374D01*
X2244434Y382541D01*
X2245829Y382333D01*
X2247069Y382541D01*
X2248309Y383583D01*
X2249084Y384833D01*
X2249239Y386083D01*
X2248929Y387541D01*
X2247844Y388583D01*
X2246759Y389000D01*
X2245364D01*
G01X2246759D02*
X2247689Y389625D01*
X2248464Y390666D01*
X2248774Y391916D01*
X2248464Y393166D01*
X2247689Y394208D01*
X2246294Y394833D01*
X2244899Y394625D01*
X2243504Y393791D01*
G01X2216173Y1070702D02*
X2217103Y1071951D01*
X2218188Y1072577D01*
X2219428Y1072785D01*
X2220978Y1072368D01*
X2222063Y1071327D01*
X2222373Y1070077D01*
X2222218Y1068826D01*
X2221598Y1067785D01*
X2218498Y1065702D01*
X2217103Y1064243D01*
X2216173Y1062160D01*
X2215863Y1060285D01*
X2222373D01*
G01X2231208D02*
X2231518Y1062993D01*
X2231983Y1065285D01*
X2232603Y1067368D01*
X2233378Y1069660D01*
X2234618Y1072785D01*
X2228418D01*
G01X2243918D02*
X2242678Y1072368D01*
X2241748Y1071327D01*
X2241128Y1070077D01*
X2240663Y1068410D01*
X2240508Y1066535D01*
X2240663Y1064660D01*
X2241128Y1062993D01*
X2241748Y1061743D01*
X2242678Y1060702D01*
X2243918Y1060285D01*
X2245158Y1060702D01*
X2246088Y1061743D01*
X2246708Y1062993D01*
X2247173Y1064660D01*
X2247328Y1066535D01*
X2247173Y1068410D01*
X2246708Y1070077D01*
X2246088Y1071327D01*
X2245158Y1072368D01*
X2243918Y1072785D01*
G01X2256318Y1059868D02*
X2256008Y1060077D01*
Y1060493D01*
X2256318Y1060702D01*
X2256628Y1060493D01*
Y1060077D01*
X2256318Y1059868D01*
G01X2266083Y1061743D02*
X2267168Y1060702D01*
X2268408Y1060285D01*
X2269648Y1060702D01*
X2270733Y1061951D01*
X2271508Y1063827D01*
X2271818Y1065702D01*
Y1067993D01*
X2271508Y1069868D01*
X2270733Y1071535D01*
X2269803Y1072368D01*
X2268718Y1072785D01*
X2267478Y1072368D01*
X2266548Y1071535D01*
X2265928Y1070285D01*
X2265618Y1068618D01*
X2265928Y1067160D01*
X2266703Y1065702D01*
X2267633Y1064868D01*
X2268718Y1064660D01*
X2269958Y1065076D01*
X2270888Y1066118D01*
X2271818Y1067993D01*
G01X2225315Y1259636D02*
X2226245Y1258177D01*
X2227485Y1257344D01*
X2228880Y1257136D01*
X2230120Y1257344D01*
X2231360Y1258386D01*
X2232135Y1259636D01*
X2232290Y1260886D01*
X2231980Y1262344D01*
X2230895Y1263386D01*
X2229810Y1263803D01*
X2228415D01*
G01X2229810D02*
X2230740Y1264428D01*
X2231515Y1265469D01*
X2231825Y1266719D01*
X2231515Y1267969D01*
X2230740Y1269011D01*
X2229345Y1269636D01*
X2227950Y1269428D01*
X2226555Y1268594D01*
G01X2238180Y1267553D02*
X2239110Y1268802D01*
X2240195Y1269428D01*
X2241435Y1269636D01*
X2242985Y1269219D01*
X2244070Y1268178D01*
X2244380Y1266928D01*
X2244225Y1265677D01*
X2243605Y1264636D01*
X2240505Y1262553D01*
X2239110Y1261094D01*
X2238180Y1259011D01*
X2237870Y1257136D01*
X2244380D01*
G01X2253525Y1269636D02*
X2252285Y1269219D01*
X2251355Y1268178D01*
X2250735Y1266928D01*
X2250270Y1265261D01*
X2250115Y1263386D01*
X2250270Y1261511D01*
X2250735Y1259844D01*
X2251355Y1258594D01*
X2252285Y1257553D01*
X2253525Y1257136D01*
X2254765Y1257553D01*
X2255695Y1258594D01*
X2256315Y1259844D01*
X2256780Y1261511D01*
X2256935Y1263386D01*
X2256780Y1265261D01*
X2256315Y1266928D01*
X2255695Y1268178D01*
X2254765Y1269219D01*
X2253525Y1269636D01*
G01X2265925Y1256719D02*
X2265615Y1256928D01*
Y1257344D01*
X2265925Y1257553D01*
X2266235Y1257344D01*
Y1256928D01*
X2265925Y1256719D01*
G01X2275690Y1258594D02*
X2276775Y1257553D01*
X2278015Y1257136D01*
X2279255Y1257553D01*
X2280340Y1258802D01*
X2281115Y1260678D01*
X2281425Y1262553D01*
Y1264844D01*
X2281115Y1266719D01*
X2280340Y1268386D01*
X2279410Y1269219D01*
X2278325Y1269636D01*
X2277085Y1269219D01*
X2276155Y1268386D01*
X2275535Y1267136D01*
X2275225Y1265469D01*
X2275535Y1264011D01*
X2276310Y1262553D01*
X2277240Y1261719D01*
X2278325Y1261511D01*
X2279565Y1261927D01*
X2280495Y1262969D01*
X2281425Y1264844D01*
G01X2277639Y383791D02*
X2278724Y382750D01*
X2279964Y382333D01*
X2281204Y382750D01*
X2282289Y383999D01*
X2283064Y385875D01*
X2283374Y387750D01*
Y390041D01*
X2283064Y391916D01*
X2282289Y393583D01*
X2281359Y394416D01*
X2280274Y394833D01*
X2279034Y394416D01*
X2278104Y393583D01*
X2277484Y392333D01*
X2277174Y390666D01*
X2277484Y389208D01*
X2278259Y387750D01*
X2279189Y386916D01*
X2280274Y386708D01*
X2281514Y387124D01*
X2282444Y388166D01*
X2283374Y390041D01*
G01X2292674Y382333D02*
X2293759Y382541D01*
X2294999Y383166D01*
X2295774Y384208D01*
X2296084Y385666D01*
X2295774Y387124D01*
X2294844Y388375D01*
X2293449Y389000D01*
X2291899D01*
X2290969Y389416D01*
X2290194Y390458D01*
X2289884Y391916D01*
X2290349Y393375D01*
X2291434Y394416D01*
X2292674Y394833D01*
X2293914Y394416D01*
X2294999Y393375D01*
X2295464Y391916D01*
X2295154Y390458D01*
X2294379Y389416D01*
X2293449Y389000D01*
X2291899D01*
X2290504Y388375D01*
X2289574Y387124D01*
X2289264Y385666D01*
X2289574Y384208D01*
X2290349Y383166D01*
X2291589Y382541D01*
X2292674Y382333D01*
G01X2305074Y381916D02*
X2304764Y382125D01*
Y382541D01*
X2305074Y382750D01*
X2305384Y382541D01*
Y382125D01*
X2305074Y381916D01*
G01X2317164Y382333D02*
X2317474Y385041D01*
X2317939Y387333D01*
X2318559Y389416D01*
X2319334Y391708D01*
X2320574Y394833D01*
X2314374D01*
G01X2697704Y2240068D02*
X2698324Y2240693D01*
X2698789Y2241734D01*
X2699099Y2243193D01*
X2698789Y2244443D01*
X2698169Y2245276D01*
X2697084Y2245901D01*
X2692899D01*
Y2233401D01*
X2698014D01*
X2699099Y2234234D01*
X2699719Y2235484D01*
X2700029Y2236943D01*
X2699719Y2238401D01*
X2698789Y2239651D01*
X2697704Y2240068D01*
X2692899D01*
G01X2704989Y2233401D02*
X2708864Y2245901D01*
X2712739Y2233401D01*
G01X2711344Y2237776D02*
X2706384D01*
G01X2724674Y2244859D02*
X2723744Y2245484D01*
X2722659Y2245901D01*
X2721419D01*
X2720024Y2245276D01*
X2718939Y2244234D01*
X2718164Y2242984D01*
X2717544Y2240901D01*
X2717389Y2239026D01*
X2717699Y2237151D01*
X2718164Y2235901D01*
X2719094Y2234651D01*
X2720179Y2233818D01*
X2721264Y2233401D01*
X2722349D01*
X2723434Y2233818D01*
X2724364Y2234442D01*
X2725139Y2235276D01*
G01X2730254Y2233401D02*
Y2245901D01*
G01X2736144D02*
X2730254Y2238192D01*
G01X2737074Y2233401D02*
X2732889Y2241734D01*
G01X2742654Y2233401D02*
Y2245901D01*
X2745754D01*
X2746994Y2245276D01*
X2747924Y2244443D01*
X2748699Y2243193D01*
X2749319Y2241734D01*
X2749474Y2239651D01*
X2749319Y2237568D01*
X2748699Y2236109D01*
X2747924Y2234859D01*
X2746994Y2234026D01*
X2745754Y2233401D01*
X2742654D01*
G01X2755364D02*
Y2245901D01*
X2759239D01*
X2760479Y2245276D01*
X2761254Y2244443D01*
X2761564Y2242776D01*
X2761254Y2241109D01*
X2760324Y2240068D01*
X2759239Y2239443D01*
X2755364D01*
G01X2759239D02*
X2761564Y2233401D01*
G01X2769004Y2245901D02*
X2772724D01*
G01X2770864D02*
Y2233401D01*
G01X2769004D02*
X2772724D01*
G01X2780164Y2245901D02*
Y2233401D01*
X2786364D01*
G01X2792564Y2245901D02*
Y2233401D01*
X2798764D01*
G01X2817209Y2235067D02*
X2818449Y2234026D01*
X2819844Y2233401D01*
X2821084D01*
X2822324Y2234026D01*
X2823254Y2235067D01*
X2823719Y2236526D01*
X2823409Y2237984D01*
X2822634Y2239234D01*
X2821239Y2240068D01*
X2819379Y2240484D01*
X2818294Y2241318D01*
X2817829Y2242776D01*
X2818139Y2244234D01*
X2818914Y2245276D01*
X2819999Y2245901D01*
X2821084D01*
X2822169Y2245484D01*
X2823099Y2244443D01*
G01X2832864Y2245901D02*
Y2233401D01*
G01X2829299Y2245901D02*
X2836429D01*
G01X2841854D02*
Y2236943D01*
X2842474Y2235067D01*
X2843714Y2233818D01*
X2845264Y2233401D01*
X2846814Y2233818D01*
X2848054Y2235067D01*
X2848674Y2236943D01*
Y2245901D01*
G01X2858904Y2240068D02*
X2859524Y2240693D01*
X2859989Y2241734D01*
X2860299Y2243193D01*
X2859989Y2244443D01*
X2859369Y2245276D01*
X2858284Y2245901D01*
X2854099D01*
Y2233401D01*
X2859214D01*
X2860299Y2234234D01*
X2860919Y2235484D01*
X2861229Y2236943D01*
X2860919Y2238401D01*
X2859989Y2239651D01*
X2858904Y2240068D01*
X2854099D01*
G01X2879364Y2245901D02*
Y2233401D01*
X2885564D01*
G01X2897964D02*
X2891764D01*
Y2245901D01*
X2897964D01*
G01X2895484Y2239859D02*
X2891764D01*
G01X2903699Y2233401D02*
Y2245901D01*
X2910829Y2233401D01*
Y2245901D01*
G01X2920594Y2239651D02*
X2923694D01*
Y2235901D01*
X2922764Y2234651D01*
X2921679Y2233818D01*
X2920129Y2233401D01*
X2918579Y2233818D01*
X2917494Y2234651D01*
X2916564Y2235901D01*
X2915944Y2237359D01*
X2915634Y2239026D01*
Y2240484D01*
X2915944Y2241734D01*
X2916564Y2243193D01*
X2917494Y2244443D01*
X2918424Y2245276D01*
X2919664Y2245901D01*
X2920749D01*
X2921989Y2245484D01*
X2922919Y2244651D01*
G01X2932064Y2245901D02*
Y2233401D01*
G01X2928499Y2245901D02*
X2935629D01*
G01X2941209Y2233401D02*
Y2245901D01*
G01X2947719D02*
Y2233401D01*
G01Y2239651D02*
X2941209D01*
G01X2969264Y2245901D02*
Y2233401D01*
G01X2965699Y2245901D02*
X2972829D01*
G01X2981664Y2233401D02*
X2980424Y2233609D01*
X2979339Y2234442D01*
X2978409Y2235693D01*
X2977789Y2237151D01*
X2977479Y2238818D01*
Y2240484D01*
X2977789Y2242151D01*
X2978409Y2243609D01*
X2979339Y2244859D01*
X2980424Y2245693D01*
X2981664Y2245901D01*
X2982904Y2245693D01*
X2983989Y2244859D01*
X2984919Y2243609D01*
X2985539Y2242151D01*
X2985849Y2240484D01*
Y2238818D01*
X2985539Y2237151D01*
X2984919Y2235693D01*
X2983989Y2234442D01*
X2982904Y2233609D01*
X2981664Y2233401D01*
G01X2990964Y2245901D02*
Y2233401D01*
X2997164D01*
G01X3009564D02*
X3003364D01*
Y2245901D01*
X3009564D01*
G01X3007084Y2239859D02*
X3003364D01*
G01X3015764Y2233401D02*
Y2245901D01*
X3019639D01*
X3020879Y2245276D01*
X3021654Y2244443D01*
X3021964Y2242776D01*
X3021654Y2241109D01*
X3020724Y2240068D01*
X3019639Y2239443D01*
X3015764D01*
G01X3019639D02*
X3021964Y2233401D01*
G01X3027389D02*
X3031264Y2245901D01*
X3035139Y2233401D01*
G01X3033744Y2237776D02*
X3028784D01*
G01X3040099Y2233401D02*
Y2245901D01*
X3047229Y2233401D01*
Y2245901D01*
G01X3059474Y2244859D02*
X3058544Y2245484D01*
X3057459Y2245901D01*
X3056219D01*
X3054824Y2245276D01*
X3053739Y2244234D01*
X3052964Y2242984D01*
X3052344Y2240901D01*
X3052189Y2239026D01*
X3052499Y2237151D01*
X3052964Y2235901D01*
X3053894Y2234651D01*
X3054979Y2233818D01*
X3056064Y2233401D01*
X3057149D01*
X3058234Y2233818D01*
X3059164Y2234442D01*
X3059939Y2235276D01*
G01X3071564Y2233401D02*
X3065364D01*
Y2245901D01*
X3071564D01*
G01X3069084Y2239859D02*
X3065364D01*
G01X3093264Y2245901D02*
Y2233401D01*
G01X3089699Y2245901D02*
X3096829D01*
G01X3105664Y2233401D02*
X3104424Y2233609D01*
X3103339Y2234442D01*
X3102409Y2235693D01*
X3101789Y2237151D01*
X3101479Y2238818D01*
Y2240484D01*
X3101789Y2242151D01*
X3102409Y2243609D01*
X3103339Y2244859D01*
X3104424Y2245693D01*
X3105664Y2245901D01*
X3106904Y2245693D01*
X3107989Y2244859D01*
X3108919Y2243609D01*
X3109539Y2242151D01*
X3109849Y2240484D01*
Y2238818D01*
X3109539Y2237151D01*
X3108919Y2235693D01*
X3107989Y2234442D01*
X3106904Y2233609D01*
X3105664Y2233401D01*
G01X3131704Y2240068D02*
X3132324Y2240693D01*
X3132789Y2241734D01*
X3133099Y2243193D01*
X3132789Y2244443D01*
X3132169Y2245276D01*
X3131084Y2245901D01*
X3126899D01*
Y2233401D01*
X3132014D01*
X3133099Y2234234D01*
X3133719Y2235484D01*
X3134029Y2236943D01*
X3133719Y2238401D01*
X3132789Y2239651D01*
X3131704Y2240068D01*
X3126899D01*
G01X3145964Y2233401D02*
X3139764D01*
Y2245901D01*
X3145964D01*
G01X3143484Y2239859D02*
X3139764D01*
G01X3167354Y2233401D02*
X3167664Y2236109D01*
X3168129Y2238401D01*
X3168749Y2240484D01*
X3169524Y2242776D01*
X3170764Y2245901D01*
X3164564D01*
G01X3190759Y2237568D02*
X3194479D01*
G01X3192464Y2240276D02*
Y2234859D01*
G01X3202074Y2232984D02*
X3207654Y2245901D01*
G01X3215249Y2237568D02*
X3219279D01*
G01X3226254Y2235276D02*
X3227184Y2234234D01*
X3228269Y2233609D01*
X3229664Y2233401D01*
X3231059Y2233818D01*
X3232144Y2234651D01*
X3232919Y2236109D01*
X3233074Y2237776D01*
X3232764Y2239443D01*
X3231989Y2240484D01*
X3230904Y2241318D01*
X3229819Y2241526D01*
X3228734Y2241318D01*
X3227339Y2240484D01*
X3227804Y2245901D01*
X3231989D01*
G01X3250434Y2233401D02*
Y2245901D01*
X3254464Y2235484D01*
X3258494Y2245901D01*
Y2233401D01*
G01X3265004Y2245901D02*
X3268724D01*
G01X3266864D02*
Y2233401D01*
G01X3265004D02*
X3268724D01*
G01X3276164Y2245901D02*
Y2233401D01*
X3282364D01*
G01X3288409Y2235067D02*
X3289649Y2234026D01*
X3291044Y2233401D01*
X3292284D01*
X3293524Y2234026D01*
X3294454Y2235067D01*
X3294919Y2236526D01*
X3294609Y2237984D01*
X3293834Y2239234D01*
X3292439Y2240068D01*
X3290579Y2240484D01*
X3289494Y2241318D01*
X3289029Y2242776D01*
X3289339Y2244234D01*
X3290114Y2245276D01*
X3291199Y2245901D01*
X3292284D01*
X3293369Y2245484D01*
X3294299Y2244443D01*
G01X2533249Y2256318D02*
X2537279D01*
G01X2556034Y2252151D02*
Y2264651D01*
X2560064Y2254234D01*
X2564094Y2264651D01*
Y2252151D01*
G01X2569519D02*
Y2264651D01*
X2575409D01*
G01X2573239Y2258609D02*
X2569519D01*
G01X2585794Y2258401D02*
X2588894D01*
Y2254651D01*
X2587964Y2253401D01*
X2586879Y2252568D01*
X2585329Y2252151D01*
X2583779Y2252568D01*
X2582694Y2253401D01*
X2581764Y2254651D01*
X2581144Y2256109D01*
X2580834Y2257776D01*
Y2259234D01*
X2581144Y2260484D01*
X2581764Y2261943D01*
X2582694Y2263193D01*
X2583624Y2264026D01*
X2584864Y2264651D01*
X2585949D01*
X2587189Y2264234D01*
X2588119Y2263401D01*
G01X2592614Y2247984D02*
X2601914D01*
G01X2606409Y2253817D02*
X2607649Y2252776D01*
X2609044Y2252151D01*
X2610284D01*
X2611524Y2252776D01*
X2612454Y2253817D01*
X2612919Y2255276D01*
X2612609Y2256734D01*
X2611834Y2257984D01*
X2610439Y2258818D01*
X2608579Y2259234D01*
X2607494Y2260068D01*
X2607029Y2261526D01*
X2607339Y2262984D01*
X2608114Y2264026D01*
X2609199Y2264651D01*
X2610284D01*
X2611369Y2264234D01*
X2612299Y2263193D01*
G01X2622064Y2264651D02*
Y2252151D01*
G01X2618499Y2264651D02*
X2625629D01*
G01X2631054D02*
Y2255693D01*
X2631674Y2253817D01*
X2632914Y2252568D01*
X2634464Y2252151D01*
X2636014Y2252568D01*
X2637254Y2253817D01*
X2637874Y2255693D01*
Y2264651D01*
G01X2648104Y2258818D02*
X2648724Y2259443D01*
X2649189Y2260484D01*
X2649499Y2261943D01*
X2649189Y2263193D01*
X2648569Y2264026D01*
X2647484Y2264651D01*
X2643299D01*
Y2252151D01*
X2648414D01*
X2649499Y2252984D01*
X2650119Y2254234D01*
X2650429Y2255693D01*
X2650119Y2257151D01*
X2649189Y2258401D01*
X2648104Y2258818D01*
X2643299D01*
G01X2671664Y2251734D02*
X2671354Y2251943D01*
Y2252359D01*
X2671664Y2252568D01*
X2671974Y2252359D01*
Y2251943D01*
X2671664Y2251734D01*
G01Y2257359D02*
X2671354Y2257568D01*
Y2257984D01*
X2671664Y2258193D01*
X2671974Y2257984D01*
Y2257568D01*
X2671664Y2257359D01*
G01X2692434Y2252151D02*
Y2264651D01*
X2696464Y2254234D01*
X2700494Y2264651D01*
Y2252151D01*
G01X2704989D02*
X2708864Y2264651D01*
X2712739Y2252151D01*
G01X2711344Y2256526D02*
X2706384D01*
G01X2717699Y2252151D02*
Y2264651D01*
X2724829Y2252151D01*
Y2264651D01*
G01X2730254D02*
Y2255693D01*
X2730874Y2253817D01*
X2732114Y2252568D01*
X2733664Y2252151D01*
X2735214Y2252568D01*
X2736454Y2253817D01*
X2737074Y2255693D01*
Y2264651D01*
G01X2743119Y2252151D02*
Y2264651D01*
X2749009D01*
G01X2746839Y2258609D02*
X2743119D01*
G01X2754589Y2252151D02*
X2758464Y2264651D01*
X2762339Y2252151D01*
G01X2760944Y2256526D02*
X2755984D01*
G01X2774274Y2263609D02*
X2773344Y2264234D01*
X2772259Y2264651D01*
X2771019D01*
X2769624Y2264026D01*
X2768539Y2262984D01*
X2767764Y2261734D01*
X2767144Y2259651D01*
X2766989Y2257776D01*
X2767299Y2255901D01*
X2767764Y2254651D01*
X2768694Y2253401D01*
X2769779Y2252568D01*
X2770864Y2252151D01*
X2771949D01*
X2773034Y2252568D01*
X2773964Y2253192D01*
X2774739Y2254026D01*
G01X2783264Y2264651D02*
Y2252151D01*
G01X2779699Y2264651D02*
X2786829D01*
G01X2792254D02*
Y2255693D01*
X2792874Y2253817D01*
X2794114Y2252568D01*
X2795664Y2252151D01*
X2797214Y2252568D01*
X2798454Y2253817D01*
X2799074Y2255693D01*
Y2264651D01*
G01X2804964Y2252151D02*
Y2264651D01*
X2808839D01*
X2810079Y2264026D01*
X2810854Y2263193D01*
X2811164Y2261526D01*
X2810854Y2259859D01*
X2809924Y2258818D01*
X2808839Y2258193D01*
X2804964D01*
G01X2808839D02*
X2811164Y2252151D01*
G01X2818604Y2264651D02*
X2822324D01*
G01X2820464D02*
Y2252151D01*
G01X2818604D02*
X2822324D01*
G01X2829299D02*
Y2264651D01*
X2836429Y2252151D01*
Y2264651D01*
G01X2846194Y2258401D02*
X2849294D01*
Y2254651D01*
X2848364Y2253401D01*
X2847279Y2252568D01*
X2845729Y2252151D01*
X2844179Y2252568D01*
X2843094Y2253401D01*
X2842164Y2254651D01*
X2841544Y2256109D01*
X2841234Y2257776D01*
Y2259234D01*
X2841544Y2260484D01*
X2842164Y2261943D01*
X2843094Y2263193D01*
X2844024Y2264026D01*
X2845264Y2264651D01*
X2846349D01*
X2847589Y2264234D01*
X2848519Y2263401D01*
G01X2866809Y2253817D02*
X2868049Y2252776D01*
X2869444Y2252151D01*
X2870684D01*
X2871924Y2252776D01*
X2872854Y2253817D01*
X2873319Y2255276D01*
X2873009Y2256734D01*
X2872234Y2257984D01*
X2870839Y2258818D01*
X2868979Y2259234D01*
X2867894Y2260068D01*
X2867429Y2261526D01*
X2867739Y2262984D01*
X2868514Y2264026D01*
X2869599Y2264651D01*
X2870684D01*
X2871769Y2264234D01*
X2872699Y2263193D01*
G01X2882464Y2264651D02*
Y2252151D01*
G01X2878899Y2264651D02*
X2886029D01*
G01X2891454D02*
Y2255693D01*
X2892074Y2253817D01*
X2893314Y2252568D01*
X2894864Y2252151D01*
X2896414Y2252568D01*
X2897654Y2253817D01*
X2898274Y2255693D01*
Y2264651D01*
G01X2908504Y2258818D02*
X2909124Y2259443D01*
X2909589Y2260484D01*
X2909899Y2261943D01*
X2909589Y2263193D01*
X2908969Y2264026D01*
X2907884Y2264651D01*
X2903699D01*
Y2252151D01*
X2908814D01*
X2909899Y2252984D01*
X2910519Y2254234D01*
X2910829Y2255693D01*
X2910519Y2257151D01*
X2909589Y2258401D01*
X2908504Y2258818D01*
X2903699D01*
G01X2928964Y2264651D02*
Y2252151D01*
X2935164D01*
G01X2947564D02*
X2941364D01*
Y2264651D01*
X2947564D01*
G01X2945084Y2258609D02*
X2941364D01*
G01X2953299Y2252151D02*
Y2264651D01*
X2960429Y2252151D01*
Y2264651D01*
G01X2970194Y2258401D02*
X2973294D01*
Y2254651D01*
X2972364Y2253401D01*
X2971279Y2252568D01*
X2969729Y2252151D01*
X2968179Y2252568D01*
X2967094Y2253401D01*
X2966164Y2254651D01*
X2965544Y2256109D01*
X2965234Y2257776D01*
Y2259234D01*
X2965544Y2260484D01*
X2966164Y2261943D01*
X2967094Y2263193D01*
X2968024Y2264026D01*
X2969264Y2264651D01*
X2970349D01*
X2971589Y2264234D01*
X2972519Y2263401D01*
G01X2981664Y2264651D02*
Y2252151D01*
G01X2978099Y2264651D02*
X2985229D01*
G01X2990809Y2252151D02*
Y2264651D01*
G01X2997319D02*
Y2252151D01*
G01Y2258401D02*
X2990809D01*
G01X2693209Y2272567D02*
X2694449Y2271526D01*
X2695844Y2270901D01*
X2697084D01*
X2698324Y2271526D01*
X2699254Y2272567D01*
X2699719Y2274026D01*
X2699409Y2275484D01*
X2698634Y2276734D01*
X2697239Y2277568D01*
X2695379Y2277984D01*
X2694294Y2278818D01*
X2693829Y2280276D01*
X2694139Y2281734D01*
X2694914Y2282776D01*
X2695999Y2283401D01*
X2697084D01*
X2698169Y2282984D01*
X2699099Y2281943D01*
G01X2705454Y2283401D02*
Y2274443D01*
X2706074Y2272567D01*
X2707314Y2271318D01*
X2708864Y2270901D01*
X2710414Y2271318D01*
X2711654Y2272567D01*
X2712274Y2274443D01*
Y2283401D01*
G01X2718164Y2270901D02*
Y2283401D01*
X2722039D01*
X2723279Y2282776D01*
X2724054Y2281943D01*
X2724364Y2280276D01*
X2724054Y2278609D01*
X2723124Y2277568D01*
X2722039Y2276943D01*
X2718164D01*
G01X2722039D02*
X2724364Y2270901D01*
G01X2730719D02*
Y2283401D01*
X2736609D01*
G01X2734439Y2277359D02*
X2730719D01*
G01X2742189Y2270901D02*
X2746064Y2283401D01*
X2749939Y2270901D01*
G01X2748544Y2275276D02*
X2743584D01*
G01X2761874Y2282359D02*
X2760944Y2282984D01*
X2759859Y2283401D01*
X2758619D01*
X2757224Y2282776D01*
X2756139Y2281734D01*
X2755364Y2280484D01*
X2754744Y2278401D01*
X2754589Y2276526D01*
X2754899Y2274651D01*
X2755364Y2273401D01*
X2756294Y2272151D01*
X2757379Y2271318D01*
X2758464Y2270901D01*
X2759549D01*
X2760634Y2271318D01*
X2761564Y2271942D01*
X2762339Y2272776D01*
G01X2773964Y2270901D02*
X2767764D01*
Y2283401D01*
X2773964D01*
G01X2771484Y2277359D02*
X2767764D01*
G01X2795664Y2270901D02*
X2794424Y2271109D01*
X2793339Y2271942D01*
X2792409Y2273193D01*
X2791789Y2274651D01*
X2791479Y2276318D01*
Y2277984D01*
X2791789Y2279651D01*
X2792409Y2281109D01*
X2793339Y2282359D01*
X2794424Y2283193D01*
X2795664Y2283401D01*
X2796904Y2283193D01*
X2797989Y2282359D01*
X2798919Y2281109D01*
X2799539Y2279651D01*
X2799849Y2277984D01*
Y2276318D01*
X2799539Y2274651D01*
X2798919Y2273193D01*
X2797989Y2271942D01*
X2796904Y2271109D01*
X2795664Y2270901D01*
G01X2805119D02*
Y2283401D01*
X2811009D01*
G01X2808839Y2277359D02*
X2805119D01*
G01X2828834Y2270901D02*
Y2283401D01*
X2832864Y2272984D01*
X2836894Y2283401D01*
Y2270901D01*
G01X2841854Y2283401D02*
Y2274443D01*
X2842474Y2272567D01*
X2843714Y2271318D01*
X2845264Y2270901D01*
X2846814Y2271318D01*
X2848054Y2272567D01*
X2848674Y2274443D01*
Y2283401D01*
G01X2854409Y2272567D02*
X2855649Y2271526D01*
X2857044Y2270901D01*
X2858284D01*
X2859524Y2271526D01*
X2860454Y2272567D01*
X2860919Y2274026D01*
X2860609Y2275484D01*
X2859834Y2276734D01*
X2858439Y2277568D01*
X2856579Y2277984D01*
X2855494Y2278818D01*
X2855029Y2280276D01*
X2855339Y2281734D01*
X2856114Y2282776D01*
X2857199Y2283401D01*
X2858284D01*
X2859369Y2282984D01*
X2860299Y2281943D01*
G01X2870064Y2283401D02*
Y2270901D01*
G01X2866499Y2283401D02*
X2873629D01*
G01X2880449Y2275068D02*
X2884479D01*
G01X2891299Y2270901D02*
Y2283401D01*
X2898429Y2270901D01*
Y2283401D01*
G01X2907264Y2270901D02*
X2906024Y2271109D01*
X2904939Y2271942D01*
X2904009Y2273193D01*
X2903389Y2274651D01*
X2903079Y2276318D01*
Y2277984D01*
X2903389Y2279651D01*
X2904009Y2281109D01*
X2904939Y2282359D01*
X2906024Y2283193D01*
X2907264Y2283401D01*
X2908504Y2283193D01*
X2909589Y2282359D01*
X2910519Y2281109D01*
X2911139Y2279651D01*
X2911449Y2277984D01*
Y2276318D01*
X2911139Y2274651D01*
X2910519Y2273193D01*
X2909589Y2271942D01*
X2908504Y2271109D01*
X2907264Y2270901D01*
G01X2919664Y2283401D02*
Y2270901D01*
G01X2916099Y2283401D02*
X2923229D01*
G01X2930049Y2275068D02*
X2934079D01*
G01X2947874Y2282359D02*
X2946944Y2282984D01*
X2945859Y2283401D01*
X2944619D01*
X2943224Y2282776D01*
X2942139Y2281734D01*
X2941364Y2280484D01*
X2940744Y2278401D01*
X2940589Y2276526D01*
X2940899Y2274651D01*
X2941364Y2273401D01*
X2942294Y2272151D01*
X2943379Y2271318D01*
X2944464Y2270901D01*
X2945549D01*
X2946634Y2271318D01*
X2947564Y2271942D01*
X2948339Y2272776D01*
G01X2953454Y2283401D02*
Y2274443D01*
X2954074Y2272567D01*
X2955314Y2271318D01*
X2956864Y2270901D01*
X2958414Y2271318D01*
X2959654Y2272567D01*
X2960274Y2274443D01*
Y2283401D01*
G01X2969264D02*
Y2270901D01*
G01X2965699Y2283401D02*
X2972829D01*
G01X2979649Y2275068D02*
X2983679D01*
G01X2990964Y2283401D02*
Y2270901D01*
X2997164D01*
G01X3002589D02*
X3006464Y2283401D01*
X3010339Y2270901D01*
G01X3008944Y2275276D02*
X3003984D01*
G01X3018864Y2270901D02*
Y2276526D01*
X3015764Y2283401D01*
G01X3021964D02*
X3018864Y2276526D01*
G01X3034364Y2270901D02*
X3028164D01*
Y2283401D01*
X3034364D01*
G01X3031884Y2277359D02*
X3028164D01*
G01X3040564Y2270901D02*
Y2283401D01*
X3044439D01*
X3045679Y2282776D01*
X3046454Y2281943D01*
X3046764Y2280276D01*
X3046454Y2278609D01*
X3045524Y2277568D01*
X3044439Y2276943D01*
X3040564D01*
G01X3044439D02*
X3046764Y2270901D01*
G01X2533249Y2293818D02*
X2537279D01*
G01X2556034Y2289651D02*
Y2302151D01*
X2560064Y2291734D01*
X2564094Y2302151D01*
Y2289651D01*
G01X2568589D02*
X2572464Y2302151D01*
X2576339Y2289651D01*
G01X2574944Y2294026D02*
X2569984D01*
G01X2581609Y2289651D02*
X2588119Y2302151D01*
G01X2581609D02*
X2588119Y2289651D01*
G01X2592614Y2285484D02*
X2601914D01*
G01X2606254Y2289651D02*
Y2302151D01*
X2609354D01*
X2610594Y2301526D01*
X2611524Y2300693D01*
X2612299Y2299443D01*
X2612919Y2297984D01*
X2613074Y2295901D01*
X2612919Y2293818D01*
X2612299Y2292359D01*
X2611524Y2291109D01*
X2610594Y2290276D01*
X2609354Y2289651D01*
X2606254D01*
G01X2625164D02*
X2618964D01*
Y2302151D01*
X2625164D01*
G01X2622684Y2296109D02*
X2618964D01*
G01X2631364Y2289651D02*
Y2302151D01*
X2635084D01*
X2636324Y2301526D01*
X2637254Y2300068D01*
X2637564Y2298401D01*
X2637254Y2296734D01*
X2636479Y2295484D01*
X2635084Y2294859D01*
X2631364D01*
G01X2646864Y2302151D02*
Y2289651D01*
G01X2643299Y2302151D02*
X2650429D01*
G01X2656009Y2289651D02*
Y2302151D01*
G01X2662519D02*
Y2289651D01*
G01Y2295901D02*
X2656009D01*
G01X2671664Y2289234D02*
X2671354Y2289443D01*
Y2289859D01*
X2671664Y2290068D01*
X2671974Y2289859D01*
Y2289443D01*
X2671664Y2289234D01*
G01Y2294859D02*
X2671354Y2295068D01*
Y2295484D01*
X2671664Y2295693D01*
X2671974Y2295484D01*
Y2295068D01*
X2671664Y2294859D01*
G01X2693054Y2289651D02*
Y2302151D01*
X2696154D01*
X2697394Y2301526D01*
X2698324Y2300693D01*
X2699099Y2299443D01*
X2699719Y2297984D01*
X2699874Y2295901D01*
X2699719Y2293818D01*
X2699099Y2292359D01*
X2698324Y2291109D01*
X2697394Y2290276D01*
X2696154Y2289651D01*
X2693054D01*
G01X2711964D02*
X2705764D01*
Y2302151D01*
X2711964D01*
G01X2709484Y2296109D02*
X2705764D01*
G01X2718164Y2289651D02*
Y2302151D01*
X2721884D01*
X2723124Y2301526D01*
X2724054Y2300068D01*
X2724364Y2298401D01*
X2724054Y2296734D01*
X2723279Y2295484D01*
X2721884Y2294859D01*
X2718164D01*
G01X2733664Y2302151D02*
Y2289651D01*
G01X2730099Y2302151D02*
X2737229D01*
G01X2742809Y2289651D02*
Y2302151D01*
G01X2749319D02*
Y2289651D01*
G01Y2295901D02*
X2742809D01*
G01X2767919Y2289651D02*
Y2302151D01*
X2773809D01*
G01X2771639Y2296109D02*
X2767919D01*
G01X2780164Y2289651D02*
Y2302151D01*
X2784039D01*
X2785279Y2301526D01*
X2786054Y2300693D01*
X2786364Y2299026D01*
X2786054Y2297359D01*
X2785124Y2296318D01*
X2784039Y2295693D01*
X2780164D01*
G01X2784039D02*
X2786364Y2289651D01*
G01X2795664D02*
X2794424Y2289859D01*
X2793339Y2290692D01*
X2792409Y2291943D01*
X2791789Y2293401D01*
X2791479Y2295068D01*
Y2296734D01*
X2791789Y2298401D01*
X2792409Y2299859D01*
X2793339Y2301109D01*
X2794424Y2301943D01*
X2795664Y2302151D01*
X2796904Y2301943D01*
X2797989Y2301109D01*
X2798919Y2299859D01*
X2799539Y2298401D01*
X2799849Y2296734D01*
Y2295068D01*
X2799539Y2293401D01*
X2798919Y2291943D01*
X2797989Y2290692D01*
X2796904Y2289859D01*
X2795664Y2289651D01*
G01X2804034D02*
Y2302151D01*
X2808064Y2291734D01*
X2812094Y2302151D01*
Y2289651D01*
G01X2829609Y2291317D02*
X2830849Y2290276D01*
X2832244Y2289651D01*
X2833484D01*
X2834724Y2290276D01*
X2835654Y2291317D01*
X2836119Y2292776D01*
X2835809Y2294234D01*
X2835034Y2295484D01*
X2833639Y2296318D01*
X2831779Y2296734D01*
X2830694Y2297568D01*
X2830229Y2299026D01*
X2830539Y2300484D01*
X2831314Y2301526D01*
X2832399Y2302151D01*
X2833484D01*
X2834569Y2301734D01*
X2835499Y2300693D01*
G01X2845264Y2302151D02*
Y2289651D01*
G01X2841699Y2302151D02*
X2848829D01*
G01X2853789Y2289651D02*
X2857664Y2302151D01*
X2861539Y2289651D01*
G01X2860144Y2294026D02*
X2855184D01*
G01X2866964Y2289651D02*
Y2302151D01*
X2870839D01*
X2872079Y2301526D01*
X2872854Y2300693D01*
X2873164Y2299026D01*
X2872854Y2297359D01*
X2871924Y2296318D01*
X2870839Y2295693D01*
X2866964D01*
G01X2870839D02*
X2873164Y2289651D01*
G01X2882464Y2302151D02*
Y2289651D01*
G01X2878899Y2302151D02*
X2886029D01*
G01X2904164D02*
Y2289651D01*
X2910364D01*
G01X2915789D02*
X2919664Y2302151D01*
X2923539Y2289651D01*
G01X2922144Y2294026D02*
X2917184D01*
G01X2932064Y2289651D02*
Y2295276D01*
X2928964Y2302151D01*
G01X2935164D02*
X2932064Y2295276D01*
G01X2947564Y2289651D02*
X2941364D01*
Y2302151D01*
X2947564D01*
G01X2945084Y2296109D02*
X2941364D01*
G01X2953764Y2289651D02*
Y2302151D01*
X2957639D01*
X2958879Y2301526D01*
X2959654Y2300693D01*
X2959964Y2299026D01*
X2959654Y2297359D01*
X2958724Y2296318D01*
X2957639Y2295693D01*
X2953764D01*
G01X2957639D02*
X2959964Y2289651D01*
G01X2981664Y2302151D02*
Y2289651D01*
G01X2978099Y2302151D02*
X2985229D01*
G01X2994064Y2289651D02*
X2992824Y2289859D01*
X2991739Y2290692D01*
X2990809Y2291943D01*
X2990189Y2293401D01*
X2989879Y2295068D01*
Y2296734D01*
X2990189Y2298401D01*
X2990809Y2299859D01*
X2991739Y2301109D01*
X2992824Y2301943D01*
X2994064Y2302151D01*
X2995304Y2301943D01*
X2996389Y2301109D01*
X2997319Y2299859D01*
X2997939Y2298401D01*
X2998249Y2296734D01*
Y2295068D01*
X2997939Y2293401D01*
X2997319Y2291943D01*
X2996389Y2290692D01*
X2995304Y2289859D01*
X2994064Y2289651D01*
G01X3018864Y2302151D02*
Y2289651D01*
G01X3015299Y2302151D02*
X3022429D01*
G01X3028009Y2289651D02*
Y2302151D01*
G01X3034519D02*
Y2289651D01*
G01Y2295901D02*
X3028009D01*
G01X3046764Y2289651D02*
X3040564D01*
Y2302151D01*
X3046764D01*
G01X3044284Y2296109D02*
X3040564D01*
G01X2533249Y2312568D02*
X2537279D01*
G01X2556034Y2308401D02*
Y2320901D01*
X2560064Y2310484D01*
X2564094Y2320901D01*
Y2308401D01*
G01X2568899D02*
Y2320901D01*
X2576029Y2308401D01*
Y2320901D01*
G01X2588274Y2319859D02*
X2587344Y2320484D01*
X2586259Y2320901D01*
X2585019D01*
X2583624Y2320276D01*
X2582539Y2319234D01*
X2581764Y2317984D01*
X2581144Y2315901D01*
X2580989Y2314026D01*
X2581299Y2312151D01*
X2581764Y2310901D01*
X2582694Y2309651D01*
X2583779Y2308818D01*
X2584864Y2308401D01*
X2585949D01*
X2587034Y2308818D01*
X2587964Y2309442D01*
X2588739Y2310276D01*
G01X2592614Y2304234D02*
X2601914D01*
G01X2606564Y2320901D02*
Y2308401D01*
X2612764D01*
G01X2618189D02*
X2622064Y2320901D01*
X2625939Y2308401D01*
G01X2624544Y2312776D02*
X2619584D01*
G01X2634464Y2308401D02*
Y2314026D01*
X2631364Y2320901D01*
G01X2637564D02*
X2634464Y2314026D01*
G01X2649964Y2308401D02*
X2643764D01*
Y2320901D01*
X2649964D01*
G01X2647484Y2314859D02*
X2643764D01*
G01X2656164Y2308401D02*
Y2320901D01*
X2660039D01*
X2661279Y2320276D01*
X2662054Y2319443D01*
X2662364Y2317776D01*
X2662054Y2316109D01*
X2661124Y2315068D01*
X2660039Y2314443D01*
X2656164D01*
G01X2660039D02*
X2662364Y2308401D01*
G01X2671664Y2307984D02*
X2671354Y2308193D01*
Y2308609D01*
X2671664Y2308818D01*
X2671974Y2308609D01*
Y2308193D01*
X2671664Y2307984D01*
G01Y2313609D02*
X2671354Y2313818D01*
Y2314234D01*
X2671664Y2314443D01*
X2671974Y2314234D01*
Y2313818D01*
X2671664Y2313609D01*
G01X2692434Y2308401D02*
Y2320901D01*
X2696464Y2310484D01*
X2700494Y2320901D01*
Y2308401D01*
G01X2705454Y2320901D02*
Y2311943D01*
X2706074Y2310067D01*
X2707314Y2308818D01*
X2708864Y2308401D01*
X2710414Y2308818D01*
X2711654Y2310067D01*
X2712274Y2311943D01*
Y2320901D01*
G01X2718009Y2310067D02*
X2719249Y2309026D01*
X2720644Y2308401D01*
X2721884D01*
X2723124Y2309026D01*
X2724054Y2310067D01*
X2724519Y2311526D01*
X2724209Y2312984D01*
X2723434Y2314234D01*
X2722039Y2315068D01*
X2720179Y2315484D01*
X2719094Y2316318D01*
X2718629Y2317776D01*
X2718939Y2319234D01*
X2719714Y2320276D01*
X2720799Y2320901D01*
X2721884D01*
X2722969Y2320484D01*
X2723899Y2319443D01*
G01X2733664Y2320901D02*
Y2308401D01*
G01X2730099Y2320901D02*
X2737229D01*
G01X2744049Y2312568D02*
X2748079D01*
G01X2754899Y2308401D02*
Y2320901D01*
X2762029Y2308401D01*
Y2320901D01*
G01X2770864Y2308401D02*
X2769624Y2308609D01*
X2768539Y2309442D01*
X2767609Y2310693D01*
X2766989Y2312151D01*
X2766679Y2313818D01*
Y2315484D01*
X2766989Y2317151D01*
X2767609Y2318609D01*
X2768539Y2319859D01*
X2769624Y2320693D01*
X2770864Y2320901D01*
X2772104Y2320693D01*
X2773189Y2319859D01*
X2774119Y2318609D01*
X2774739Y2317151D01*
X2775049Y2315484D01*
Y2313818D01*
X2774739Y2312151D01*
X2774119Y2310693D01*
X2773189Y2309442D01*
X2772104Y2308609D01*
X2770864Y2308401D01*
G01X2783264Y2320901D02*
Y2308401D01*
G01X2779699Y2320901D02*
X2786829D01*
G01X2793649Y2312568D02*
X2797679D01*
G01X2811474Y2319859D02*
X2810544Y2320484D01*
X2809459Y2320901D01*
X2808219D01*
X2806824Y2320276D01*
X2805739Y2319234D01*
X2804964Y2317984D01*
X2804344Y2315901D01*
X2804189Y2314026D01*
X2804499Y2312151D01*
X2804964Y2310901D01*
X2805894Y2309651D01*
X2806979Y2308818D01*
X2808064Y2308401D01*
X2809149D01*
X2810234Y2308818D01*
X2811164Y2309442D01*
X2811939Y2310276D01*
G01X2817054Y2320901D02*
Y2311943D01*
X2817674Y2310067D01*
X2818914Y2308818D01*
X2820464Y2308401D01*
X2822014Y2308818D01*
X2823254Y2310067D01*
X2823874Y2311943D01*
Y2320901D01*
G01X2832864D02*
Y2308401D01*
G01X2829299Y2320901D02*
X2836429D01*
G01X2843249Y2312568D02*
X2847279D01*
G01X2854564Y2320901D02*
Y2308401D01*
X2860764D01*
G01X2866189D02*
X2870064Y2320901D01*
X2873939Y2308401D01*
G01X2872544Y2312776D02*
X2867584D01*
G01X2882464Y2308401D02*
Y2314026D01*
X2879364Y2320901D01*
G01X2885564D02*
X2882464Y2314026D01*
G01X2897964Y2308401D02*
X2891764D01*
Y2320901D01*
X2897964D01*
G01X2895484Y2314859D02*
X2891764D01*
G01X2904164Y2308401D02*
Y2320901D01*
X2908039D01*
X2909279Y2320276D01*
X2910054Y2319443D01*
X2910364Y2317776D01*
X2910054Y2316109D01*
X2909124Y2315068D01*
X2908039Y2314443D01*
X2904164D01*
G01X2908039D02*
X2910364Y2308401D01*
G01X2531699Y2327151D02*
Y2339651D01*
X2538829Y2327151D01*
Y2339651D01*
G01X2547664Y2327151D02*
X2546424Y2327359D01*
X2545339Y2328192D01*
X2544409Y2329443D01*
X2543789Y2330901D01*
X2543479Y2332568D01*
Y2334234D01*
X2543789Y2335901D01*
X2544409Y2337359D01*
X2545339Y2338609D01*
X2546424Y2339443D01*
X2547664Y2339651D01*
X2548904Y2339443D01*
X2549989Y2338609D01*
X2550919Y2337359D01*
X2551539Y2335901D01*
X2551849Y2334234D01*
Y2332568D01*
X2551539Y2330901D01*
X2550919Y2329443D01*
X2549989Y2328192D01*
X2548904Y2327359D01*
X2547664Y2327151D01*
G01X2560064Y2339651D02*
Y2327151D01*
G01X2556499Y2339651D02*
X2563629D01*
G01X2575564Y2327151D02*
X2569364D01*
Y2339651D01*
X2575564D01*
G01X2573084Y2333609D02*
X2569364D01*
G01X2581609Y2328817D02*
X2582849Y2327776D01*
X2584244Y2327151D01*
X2585484D01*
X2586724Y2327776D01*
X2587654Y2328817D01*
X2588119Y2330276D01*
X2587809Y2331734D01*
X2587034Y2332984D01*
X2585639Y2333818D01*
X2583779Y2334234D01*
X2582694Y2335068D01*
X2582229Y2336526D01*
X2582539Y2337984D01*
X2583314Y2339026D01*
X2584399Y2339651D01*
X2585484D01*
X2586569Y2339234D01*
X2587499Y2338193D01*
G01X2597264Y2326734D02*
X2596954Y2326943D01*
Y2327359D01*
X2597264Y2327568D01*
X2597574Y2327359D01*
Y2326943D01*
X2597264Y2326734D01*
G01Y2332359D02*
X2596954Y2332568D01*
Y2332984D01*
X2597264Y2333193D01*
X2597574Y2332984D01*
Y2332568D01*
X2597264Y2332359D01*
G01X2541619Y2427151D02*
Y2439651D01*
X2547509D01*
G01X2545339Y2433609D02*
X2541619D01*
G01X2555104Y2439651D02*
X2558824D01*
G01X2556964D02*
Y2427151D01*
G01X2555104D02*
X2558824D01*
G01X2570294Y2433401D02*
X2573394D01*
Y2429651D01*
X2572464Y2428401D01*
X2571379Y2427568D01*
X2569829Y2427151D01*
X2568279Y2427568D01*
X2567194Y2428401D01*
X2566264Y2429651D01*
X2565644Y2431109D01*
X2565334Y2432776D01*
Y2434234D01*
X2565644Y2435484D01*
X2566264Y2436943D01*
X2567194Y2438193D01*
X2568124Y2439026D01*
X2569364Y2439651D01*
X2570449D01*
X2571689Y2439234D01*
X2572619Y2438401D01*
G01X2578354Y2439651D02*
Y2430693D01*
X2578974Y2428817D01*
X2580214Y2427568D01*
X2581764Y2427151D01*
X2583314Y2427568D01*
X2584554Y2428817D01*
X2585174Y2430693D01*
Y2439651D01*
G01X2591064Y2427151D02*
Y2439651D01*
X2594939D01*
X2596179Y2439026D01*
X2596954Y2438193D01*
X2597264Y2436526D01*
X2596954Y2434859D01*
X2596024Y2433818D01*
X2594939Y2433193D01*
X2591064D01*
G01X2594939D02*
X2597264Y2427151D01*
G01X2609664D02*
X2603464D01*
Y2439651D01*
X2609664D01*
G01X2607184Y2433609D02*
X2603464D01*
G01X2711431Y2600380D02*
X2712051Y2601005D01*
X2712516Y2602046D01*
X2712826Y2603505D01*
X2712516Y2604755D01*
X2711896Y2605588D01*
X2710811Y2606213D01*
X2706626D01*
Y2593713D01*
X2711741D01*
X2712826Y2594546D01*
X2713446Y2595796D01*
X2713756Y2597255D01*
X2713446Y2598713D01*
X2712516Y2599963D01*
X2711431Y2600380D01*
X2706626D01*
G01X2718716Y2593713D02*
X2722591Y2606213D01*
X2726466Y2593713D01*
G01X2725071Y2598088D02*
X2720111D01*
G01X2738401Y2605171D02*
X2737471Y2605796D01*
X2736386Y2606213D01*
X2735146D01*
X2733751Y2605588D01*
X2732666Y2604546D01*
X2731891Y2603296D01*
X2731271Y2601213D01*
X2731116Y2599338D01*
X2731426Y2597463D01*
X2731891Y2596213D01*
X2732821Y2594963D01*
X2733906Y2594130D01*
X2734991Y2593713D01*
X2736076D01*
X2737161Y2594130D01*
X2738091Y2594754D01*
X2738866Y2595588D01*
G01X2743981Y2593713D02*
Y2606213D01*
G01X2749871D02*
X2743981Y2598504D01*
G01X2750801Y2593713D02*
X2746616Y2602046D01*
G01X2756381Y2593713D02*
Y2606213D01*
X2759481D01*
X2760721Y2605588D01*
X2761651Y2604755D01*
X2762426Y2603505D01*
X2763046Y2602046D01*
X2763201Y2599963D01*
X2763046Y2597880D01*
X2762426Y2596421D01*
X2761651Y2595171D01*
X2760721Y2594338D01*
X2759481Y2593713D01*
X2756381D01*
G01X2769091D02*
Y2606213D01*
X2772966D01*
X2774206Y2605588D01*
X2774981Y2604755D01*
X2775291Y2603088D01*
X2774981Y2601421D01*
X2774051Y2600380D01*
X2772966Y2599755D01*
X2769091D01*
G01X2772966D02*
X2775291Y2593713D01*
G01X2782731Y2606213D02*
X2786451D01*
G01X2784591D02*
Y2593713D01*
G01X2782731D02*
X2786451D01*
G01X2793891Y2606213D02*
Y2593713D01*
X2800091D01*
G01X2806291Y2606213D02*
Y2593713D01*
X2812491D01*
G01X2830936Y2595379D02*
X2832176Y2594338D01*
X2833571Y2593713D01*
X2834811D01*
X2836051Y2594338D01*
X2836981Y2595379D01*
X2837446Y2596838D01*
X2837136Y2598296D01*
X2836361Y2599546D01*
X2834966Y2600380D01*
X2833106Y2600796D01*
X2832021Y2601630D01*
X2831556Y2603088D01*
X2831866Y2604546D01*
X2832641Y2605588D01*
X2833726Y2606213D01*
X2834811D01*
X2835896Y2605796D01*
X2836826Y2604755D01*
G01X2846591Y2606213D02*
Y2593713D01*
G01X2843026Y2606213D02*
X2850156D01*
G01X2855581D02*
Y2597255D01*
X2856201Y2595379D01*
X2857441Y2594130D01*
X2858991Y2593713D01*
X2860541Y2594130D01*
X2861781Y2595379D01*
X2862401Y2597255D01*
Y2606213D01*
G01X2872631Y2600380D02*
X2873251Y2601005D01*
X2873716Y2602046D01*
X2874026Y2603505D01*
X2873716Y2604755D01*
X2873096Y2605588D01*
X2872011Y2606213D01*
X2867826D01*
Y2593713D01*
X2872941D01*
X2874026Y2594546D01*
X2874646Y2595796D01*
X2874956Y2597255D01*
X2874646Y2598713D01*
X2873716Y2599963D01*
X2872631Y2600380D01*
X2867826D01*
G01X2893091Y2606213D02*
Y2593713D01*
X2899291D01*
G01X2911691D02*
X2905491D01*
Y2606213D01*
X2911691D01*
G01X2909211Y2600171D02*
X2905491D01*
G01X2917426Y2593713D02*
Y2606213D01*
X2924556Y2593713D01*
Y2606213D01*
G01X2934321Y2599963D02*
X2937421D01*
Y2596213D01*
X2936491Y2594963D01*
X2935406Y2594130D01*
X2933856Y2593713D01*
X2932306Y2594130D01*
X2931221Y2594963D01*
X2930291Y2596213D01*
X2929671Y2597671D01*
X2929361Y2599338D01*
Y2600796D01*
X2929671Y2602046D01*
X2930291Y2603505D01*
X2931221Y2604755D01*
X2932151Y2605588D01*
X2933391Y2606213D01*
X2934476D01*
X2935716Y2605796D01*
X2936646Y2604963D01*
G01X2945791Y2606213D02*
Y2593713D01*
G01X2942226Y2606213D02*
X2949356D01*
G01X2954936Y2593713D02*
Y2606213D01*
G01X2961446D02*
Y2593713D01*
G01Y2599963D02*
X2954936D01*
G01X2982991Y2606213D02*
Y2593713D01*
G01X2979426Y2606213D02*
X2986556D01*
G01X2995391Y2593713D02*
X2994151Y2593921D01*
X2993066Y2594754D01*
X2992136Y2596005D01*
X2991516Y2597463D01*
X2991206Y2599130D01*
Y2600796D01*
X2991516Y2602463D01*
X2992136Y2603921D01*
X2993066Y2605171D01*
X2994151Y2606005D01*
X2995391Y2606213D01*
X2996631Y2606005D01*
X2997716Y2605171D01*
X2998646Y2603921D01*
X2999266Y2602463D01*
X2999576Y2600796D01*
Y2599130D01*
X2999266Y2597463D01*
X2998646Y2596005D01*
X2997716Y2594754D01*
X2996631Y2593921D01*
X2995391Y2593713D01*
G01X3004691Y2606213D02*
Y2593713D01*
X3010891D01*
G01X3023291D02*
X3017091D01*
Y2606213D01*
X3023291D01*
G01X3020811Y2600171D02*
X3017091D01*
G01X3029491Y2593713D02*
Y2606213D01*
X3033366D01*
X3034606Y2605588D01*
X3035381Y2604755D01*
X3035691Y2603088D01*
X3035381Y2601421D01*
X3034451Y2600380D01*
X3033366Y2599755D01*
X3029491D01*
G01X3033366D02*
X3035691Y2593713D01*
G01X3041116D02*
X3044991Y2606213D01*
X3048866Y2593713D01*
G01X3047471Y2598088D02*
X3042511D01*
G01X3053826Y2593713D02*
Y2606213D01*
X3060956Y2593713D01*
Y2606213D01*
G01X3073201Y2605171D02*
X3072271Y2605796D01*
X3071186Y2606213D01*
X3069946D01*
X3068551Y2605588D01*
X3067466Y2604546D01*
X3066691Y2603296D01*
X3066071Y2601213D01*
X3065916Y2599338D01*
X3066226Y2597463D01*
X3066691Y2596213D01*
X3067621Y2594963D01*
X3068706Y2594130D01*
X3069791Y2593713D01*
X3070876D01*
X3071961Y2594130D01*
X3072891Y2594754D01*
X3073666Y2595588D01*
G01X3085291Y2593713D02*
X3079091D01*
Y2606213D01*
X3085291D01*
G01X3082811Y2600171D02*
X3079091D01*
G01X3106991Y2606213D02*
Y2593713D01*
G01X3103426Y2606213D02*
X3110556D01*
G01X3119391Y2593713D02*
X3118151Y2593921D01*
X3117066Y2594754D01*
X3116136Y2596005D01*
X3115516Y2597463D01*
X3115206Y2599130D01*
Y2600796D01*
X3115516Y2602463D01*
X3116136Y2603921D01*
X3117066Y2605171D01*
X3118151Y2606005D01*
X3119391Y2606213D01*
X3120631Y2606005D01*
X3121716Y2605171D01*
X3122646Y2603921D01*
X3123266Y2602463D01*
X3123576Y2600796D01*
Y2599130D01*
X3123266Y2597463D01*
X3122646Y2596005D01*
X3121716Y2594754D01*
X3120631Y2593921D01*
X3119391Y2593713D01*
G01X3145431Y2600380D02*
X3146051Y2601005D01*
X3146516Y2602046D01*
X3146826Y2603505D01*
X3146516Y2604755D01*
X3145896Y2605588D01*
X3144811Y2606213D01*
X3140626D01*
Y2593713D01*
X3145741D01*
X3146826Y2594546D01*
X3147446Y2595796D01*
X3147756Y2597255D01*
X3147446Y2598713D01*
X3146516Y2599963D01*
X3145431Y2600380D01*
X3140626D01*
G01X3159691Y2593713D02*
X3153491D01*
Y2606213D01*
X3159691D01*
G01X3157211Y2600171D02*
X3153491D01*
G01X3181081Y2593713D02*
X3181391Y2596421D01*
X3181856Y2598713D01*
X3182476Y2600796D01*
X3183251Y2603088D01*
X3184491Y2606213D01*
X3178291D01*
G01X3204486Y2597880D02*
X3208206D01*
G01X3206191Y2600588D02*
Y2595171D01*
G01X3215801Y2593296D02*
X3221381Y2606213D01*
G01X3228976Y2597880D02*
X3233006D01*
G01X3239981Y2595588D02*
X3240911Y2594546D01*
X3241996Y2593921D01*
X3243391Y2593713D01*
X3244786Y2594130D01*
X3245871Y2594963D01*
X3246646Y2596421D01*
X3246801Y2598088D01*
X3246491Y2599755D01*
X3245716Y2600796D01*
X3244631Y2601630D01*
X3243546Y2601838D01*
X3242461Y2601630D01*
X3241066Y2600796D01*
X3241531Y2606213D01*
X3245716D01*
G01X3264161Y2593713D02*
Y2606213D01*
X3268191Y2595796D01*
X3272221Y2606213D01*
Y2593713D01*
G01X3278731Y2606213D02*
X3282451D01*
G01X3280591D02*
Y2593713D01*
G01X3278731D02*
X3282451D01*
G01X3289891Y2606213D02*
Y2593713D01*
X3296091D01*
G01X3302136Y2595379D02*
X3303376Y2594338D01*
X3304771Y2593713D01*
X3306011D01*
X3307251Y2594338D01*
X3308181Y2595379D01*
X3308646Y2596838D01*
X3308336Y2598296D01*
X3307561Y2599546D01*
X3306166Y2600380D01*
X3304306Y2600796D01*
X3303221Y2601630D01*
X3302756Y2603088D01*
X3303066Y2604546D01*
X3303841Y2605588D01*
X3304926Y2606213D01*
X3306011D01*
X3307096Y2605796D01*
X3308026Y2604755D01*
G01X2546976Y2616630D02*
X2551006D01*
G01X2569761Y2612463D02*
Y2624963D01*
X2573791Y2614546D01*
X2577821Y2624963D01*
Y2612463D01*
G01X2583246D02*
Y2624963D01*
X2589136D01*
G01X2586966Y2618921D02*
X2583246D01*
G01X2599521Y2618713D02*
X2602621D01*
Y2614963D01*
X2601691Y2613713D01*
X2600606Y2612880D01*
X2599056Y2612463D01*
X2597506Y2612880D01*
X2596421Y2613713D01*
X2595491Y2614963D01*
X2594871Y2616421D01*
X2594561Y2618088D01*
Y2619546D01*
X2594871Y2620796D01*
X2595491Y2622255D01*
X2596421Y2623505D01*
X2597351Y2624338D01*
X2598591Y2624963D01*
X2599676D01*
X2600916Y2624546D01*
X2601846Y2623713D01*
G01X2606341Y2608296D02*
X2615641D01*
G01X2620136Y2614129D02*
X2621376Y2613088D01*
X2622771Y2612463D01*
X2624011D01*
X2625251Y2613088D01*
X2626181Y2614129D01*
X2626646Y2615588D01*
X2626336Y2617046D01*
X2625561Y2618296D01*
X2624166Y2619130D01*
X2622306Y2619546D01*
X2621221Y2620380D01*
X2620756Y2621838D01*
X2621066Y2623296D01*
X2621841Y2624338D01*
X2622926Y2624963D01*
X2624011D01*
X2625096Y2624546D01*
X2626026Y2623505D01*
G01X2635791Y2624963D02*
Y2612463D01*
G01X2632226Y2624963D02*
X2639356D01*
G01X2644781D02*
Y2616005D01*
X2645401Y2614129D01*
X2646641Y2612880D01*
X2648191Y2612463D01*
X2649741Y2612880D01*
X2650981Y2614129D01*
X2651601Y2616005D01*
Y2624963D01*
G01X2661831Y2619130D02*
X2662451Y2619755D01*
X2662916Y2620796D01*
X2663226Y2622255D01*
X2662916Y2623505D01*
X2662296Y2624338D01*
X2661211Y2624963D01*
X2657026D01*
Y2612463D01*
X2662141D01*
X2663226Y2613296D01*
X2663846Y2614546D01*
X2664156Y2616005D01*
X2663846Y2617463D01*
X2662916Y2618713D01*
X2661831Y2619130D01*
X2657026D01*
G01X2685391Y2612046D02*
X2685081Y2612255D01*
Y2612671D01*
X2685391Y2612880D01*
X2685701Y2612671D01*
Y2612255D01*
X2685391Y2612046D01*
G01Y2617671D02*
X2685081Y2617880D01*
Y2618296D01*
X2685391Y2618505D01*
X2685701Y2618296D01*
Y2617880D01*
X2685391Y2617671D01*
G01X2706161Y2612463D02*
Y2624963D01*
X2710191Y2614546D01*
X2714221Y2624963D01*
Y2612463D01*
G01X2718716D02*
X2722591Y2624963D01*
X2726466Y2612463D01*
G01X2725071Y2616838D02*
X2720111D01*
G01X2731426Y2612463D02*
Y2624963D01*
X2738556Y2612463D01*
Y2624963D01*
G01X2743981D02*
Y2616005D01*
X2744601Y2614129D01*
X2745841Y2612880D01*
X2747391Y2612463D01*
X2748941Y2612880D01*
X2750181Y2614129D01*
X2750801Y2616005D01*
Y2624963D01*
G01X2756846Y2612463D02*
Y2624963D01*
X2762736D01*
G01X2760566Y2618921D02*
X2756846D01*
G01X2768316Y2612463D02*
X2772191Y2624963D01*
X2776066Y2612463D01*
G01X2774671Y2616838D02*
X2769711D01*
G01X2788001Y2623921D02*
X2787071Y2624546D01*
X2785986Y2624963D01*
X2784746D01*
X2783351Y2624338D01*
X2782266Y2623296D01*
X2781491Y2622046D01*
X2780871Y2619963D01*
X2780716Y2618088D01*
X2781026Y2616213D01*
X2781491Y2614963D01*
X2782421Y2613713D01*
X2783506Y2612880D01*
X2784591Y2612463D01*
X2785676D01*
X2786761Y2612880D01*
X2787691Y2613504D01*
X2788466Y2614338D01*
G01X2796991Y2624963D02*
Y2612463D01*
G01X2793426Y2624963D02*
X2800556D01*
G01X2805981D02*
Y2616005D01*
X2806601Y2614129D01*
X2807841Y2612880D01*
X2809391Y2612463D01*
X2810941Y2612880D01*
X2812181Y2614129D01*
X2812801Y2616005D01*
Y2624963D01*
G01X2818691Y2612463D02*
Y2624963D01*
X2822566D01*
X2823806Y2624338D01*
X2824581Y2623505D01*
X2824891Y2621838D01*
X2824581Y2620171D01*
X2823651Y2619130D01*
X2822566Y2618505D01*
X2818691D01*
G01X2822566D02*
X2824891Y2612463D01*
G01X2832331Y2624963D02*
X2836051D01*
G01X2834191D02*
Y2612463D01*
G01X2832331D02*
X2836051D01*
G01X2843026D02*
Y2624963D01*
X2850156Y2612463D01*
Y2624963D01*
G01X2859921Y2618713D02*
X2863021D01*
Y2614963D01*
X2862091Y2613713D01*
X2861006Y2612880D01*
X2859456Y2612463D01*
X2857906Y2612880D01*
X2856821Y2613713D01*
X2855891Y2614963D01*
X2855271Y2616421D01*
X2854961Y2618088D01*
Y2619546D01*
X2855271Y2620796D01*
X2855891Y2622255D01*
X2856821Y2623505D01*
X2857751Y2624338D01*
X2858991Y2624963D01*
X2860076D01*
X2861316Y2624546D01*
X2862246Y2623713D01*
G01X2880536Y2614129D02*
X2881776Y2613088D01*
X2883171Y2612463D01*
X2884411D01*
X2885651Y2613088D01*
X2886581Y2614129D01*
X2887046Y2615588D01*
X2886736Y2617046D01*
X2885961Y2618296D01*
X2884566Y2619130D01*
X2882706Y2619546D01*
X2881621Y2620380D01*
X2881156Y2621838D01*
X2881466Y2623296D01*
X2882241Y2624338D01*
X2883326Y2624963D01*
X2884411D01*
X2885496Y2624546D01*
X2886426Y2623505D01*
G01X2896191Y2624963D02*
Y2612463D01*
G01X2892626Y2624963D02*
X2899756D01*
G01X2905181D02*
Y2616005D01*
X2905801Y2614129D01*
X2907041Y2612880D01*
X2908591Y2612463D01*
X2910141Y2612880D01*
X2911381Y2614129D01*
X2912001Y2616005D01*
Y2624963D01*
G01X2922231Y2619130D02*
X2922851Y2619755D01*
X2923316Y2620796D01*
X2923626Y2622255D01*
X2923316Y2623505D01*
X2922696Y2624338D01*
X2921611Y2624963D01*
X2917426D01*
Y2612463D01*
X2922541D01*
X2923626Y2613296D01*
X2924246Y2614546D01*
X2924556Y2616005D01*
X2924246Y2617463D01*
X2923316Y2618713D01*
X2922231Y2619130D01*
X2917426D01*
G01X2942691Y2624963D02*
Y2612463D01*
X2948891D01*
G01X2961291D02*
X2955091D01*
Y2624963D01*
X2961291D01*
G01X2958811Y2618921D02*
X2955091D01*
G01X2967026Y2612463D02*
Y2624963D01*
X2974156Y2612463D01*
Y2624963D01*
G01X2983921Y2618713D02*
X2987021D01*
Y2614963D01*
X2986091Y2613713D01*
X2985006Y2612880D01*
X2983456Y2612463D01*
X2981906Y2612880D01*
X2980821Y2613713D01*
X2979891Y2614963D01*
X2979271Y2616421D01*
X2978961Y2618088D01*
Y2619546D01*
X2979271Y2620796D01*
X2979891Y2622255D01*
X2980821Y2623505D01*
X2981751Y2624338D01*
X2982991Y2624963D01*
X2984076D01*
X2985316Y2624546D01*
X2986246Y2623713D01*
G01X2995391Y2624963D02*
Y2612463D01*
G01X2991826Y2624963D02*
X2998956D01*
G01X3004536Y2612463D02*
Y2624963D01*
G01X3011046D02*
Y2612463D01*
G01Y2618713D02*
X3004536D01*
G01X2706936Y2632879D02*
X2708176Y2631838D01*
X2709571Y2631213D01*
X2710811D01*
X2712051Y2631838D01*
X2712981Y2632879D01*
X2713446Y2634338D01*
X2713136Y2635796D01*
X2712361Y2637046D01*
X2710966Y2637880D01*
X2709106Y2638296D01*
X2708021Y2639130D01*
X2707556Y2640588D01*
X2707866Y2642046D01*
X2708641Y2643088D01*
X2709726Y2643713D01*
X2710811D01*
X2711896Y2643296D01*
X2712826Y2642255D01*
G01X2719181Y2643713D02*
Y2634755D01*
X2719801Y2632879D01*
X2721041Y2631630D01*
X2722591Y2631213D01*
X2724141Y2631630D01*
X2725381Y2632879D01*
X2726001Y2634755D01*
Y2643713D01*
G01X2731891Y2631213D02*
Y2643713D01*
X2735766D01*
X2737006Y2643088D01*
X2737781Y2642255D01*
X2738091Y2640588D01*
X2737781Y2638921D01*
X2736851Y2637880D01*
X2735766Y2637255D01*
X2731891D01*
G01X2735766D02*
X2738091Y2631213D01*
G01X2744446D02*
Y2643713D01*
X2750336D01*
G01X2748166Y2637671D02*
X2744446D01*
G01X2755916Y2631213D02*
X2759791Y2643713D01*
X2763666Y2631213D01*
G01X2762271Y2635588D02*
X2757311D01*
G01X2775601Y2642671D02*
X2774671Y2643296D01*
X2773586Y2643713D01*
X2772346D01*
X2770951Y2643088D01*
X2769866Y2642046D01*
X2769091Y2640796D01*
X2768471Y2638713D01*
X2768316Y2636838D01*
X2768626Y2634963D01*
X2769091Y2633713D01*
X2770021Y2632463D01*
X2771106Y2631630D01*
X2772191Y2631213D01*
X2773276D01*
X2774361Y2631630D01*
X2775291Y2632254D01*
X2776066Y2633088D01*
G01X2787691Y2631213D02*
X2781491D01*
Y2643713D01*
X2787691D01*
G01X2785211Y2637671D02*
X2781491D01*
G01X2809391Y2631213D02*
X2808151Y2631421D01*
X2807066Y2632254D01*
X2806136Y2633505D01*
X2805516Y2634963D01*
X2805206Y2636630D01*
Y2638296D01*
X2805516Y2639963D01*
X2806136Y2641421D01*
X2807066Y2642671D01*
X2808151Y2643505D01*
X2809391Y2643713D01*
X2810631Y2643505D01*
X2811716Y2642671D01*
X2812646Y2641421D01*
X2813266Y2639963D01*
X2813576Y2638296D01*
Y2636630D01*
X2813266Y2634963D01*
X2812646Y2633505D01*
X2811716Y2632254D01*
X2810631Y2631421D01*
X2809391Y2631213D01*
G01X2818846D02*
Y2643713D01*
X2824736D01*
G01X2822566Y2637671D02*
X2818846D01*
G01X2842561Y2631213D02*
Y2643713D01*
X2846591Y2633296D01*
X2850621Y2643713D01*
Y2631213D01*
G01X2855581Y2643713D02*
Y2634755D01*
X2856201Y2632879D01*
X2857441Y2631630D01*
X2858991Y2631213D01*
X2860541Y2631630D01*
X2861781Y2632879D01*
X2862401Y2634755D01*
Y2643713D01*
G01X2868136Y2632879D02*
X2869376Y2631838D01*
X2870771Y2631213D01*
X2872011D01*
X2873251Y2631838D01*
X2874181Y2632879D01*
X2874646Y2634338D01*
X2874336Y2635796D01*
X2873561Y2637046D01*
X2872166Y2637880D01*
X2870306Y2638296D01*
X2869221Y2639130D01*
X2868756Y2640588D01*
X2869066Y2642046D01*
X2869841Y2643088D01*
X2870926Y2643713D01*
X2872011D01*
X2873096Y2643296D01*
X2874026Y2642255D01*
G01X2883791Y2643713D02*
Y2631213D01*
G01X2880226Y2643713D02*
X2887356D01*
G01X2894176Y2635380D02*
X2898206D01*
G01X2905026Y2631213D02*
Y2643713D01*
X2912156Y2631213D01*
Y2643713D01*
G01X2920991Y2631213D02*
X2919751Y2631421D01*
X2918666Y2632254D01*
X2917736Y2633505D01*
X2917116Y2634963D01*
X2916806Y2636630D01*
Y2638296D01*
X2917116Y2639963D01*
X2917736Y2641421D01*
X2918666Y2642671D01*
X2919751Y2643505D01*
X2920991Y2643713D01*
X2922231Y2643505D01*
X2923316Y2642671D01*
X2924246Y2641421D01*
X2924866Y2639963D01*
X2925176Y2638296D01*
Y2636630D01*
X2924866Y2634963D01*
X2924246Y2633505D01*
X2923316Y2632254D01*
X2922231Y2631421D01*
X2920991Y2631213D01*
G01X2933391Y2643713D02*
Y2631213D01*
G01X2929826Y2643713D02*
X2936956D01*
G01X2943776Y2635380D02*
X2947806D01*
G01X2961601Y2642671D02*
X2960671Y2643296D01*
X2959586Y2643713D01*
X2958346D01*
X2956951Y2643088D01*
X2955866Y2642046D01*
X2955091Y2640796D01*
X2954471Y2638713D01*
X2954316Y2636838D01*
X2954626Y2634963D01*
X2955091Y2633713D01*
X2956021Y2632463D01*
X2957106Y2631630D01*
X2958191Y2631213D01*
X2959276D01*
X2960361Y2631630D01*
X2961291Y2632254D01*
X2962066Y2633088D01*
G01X2967181Y2643713D02*
Y2634755D01*
X2967801Y2632879D01*
X2969041Y2631630D01*
X2970591Y2631213D01*
X2972141Y2631630D01*
X2973381Y2632879D01*
X2974001Y2634755D01*
Y2643713D01*
G01X2982991D02*
Y2631213D01*
G01X2979426Y2643713D02*
X2986556D01*
G01X2993376Y2635380D02*
X2997406D01*
G01X3004691Y2643713D02*
Y2631213D01*
X3010891D01*
G01X3016316D02*
X3020191Y2643713D01*
X3024066Y2631213D01*
G01X3022671Y2635588D02*
X3017711D01*
G01X3032591Y2631213D02*
Y2636838D01*
X3029491Y2643713D01*
G01X3035691D02*
X3032591Y2636838D01*
G01X3048091Y2631213D02*
X3041891D01*
Y2643713D01*
X3048091D01*
G01X3045611Y2637671D02*
X3041891D01*
G01X3054291Y2631213D02*
Y2643713D01*
X3058166D01*
X3059406Y2643088D01*
X3060181Y2642255D01*
X3060491Y2640588D01*
X3060181Y2638921D01*
X3059251Y2637880D01*
X3058166Y2637255D01*
X3054291D01*
G01X3058166D02*
X3060491Y2631213D01*
G01X2546976Y2654130D02*
X2551006D01*
G01X2569761Y2649963D02*
Y2662463D01*
X2573791Y2652046D01*
X2577821Y2662463D01*
Y2649963D01*
G01X2582316D02*
X2586191Y2662463D01*
X2590066Y2649963D01*
G01X2588671Y2654338D02*
X2583711D01*
G01X2595336Y2649963D02*
X2601846Y2662463D01*
G01X2595336D02*
X2601846Y2649963D01*
G01X2606341Y2645796D02*
X2615641D01*
G01X2619981Y2649963D02*
Y2662463D01*
X2623081D01*
X2624321Y2661838D01*
X2625251Y2661005D01*
X2626026Y2659755D01*
X2626646Y2658296D01*
X2626801Y2656213D01*
X2626646Y2654130D01*
X2626026Y2652671D01*
X2625251Y2651421D01*
X2624321Y2650588D01*
X2623081Y2649963D01*
X2619981D01*
G01X2638891D02*
X2632691D01*
Y2662463D01*
X2638891D01*
G01X2636411Y2656421D02*
X2632691D01*
G01X2645091Y2649963D02*
Y2662463D01*
X2648811D01*
X2650051Y2661838D01*
X2650981Y2660380D01*
X2651291Y2658713D01*
X2650981Y2657046D01*
X2650206Y2655796D01*
X2648811Y2655171D01*
X2645091D01*
G01X2660591Y2662463D02*
Y2649963D01*
G01X2657026Y2662463D02*
X2664156D01*
G01X2669736Y2649963D02*
Y2662463D01*
G01X2676246D02*
Y2649963D01*
G01Y2656213D02*
X2669736D01*
G01X2685391Y2649546D02*
X2685081Y2649755D01*
Y2650171D01*
X2685391Y2650380D01*
X2685701Y2650171D01*
Y2649755D01*
X2685391Y2649546D01*
G01Y2655171D02*
X2685081Y2655380D01*
Y2655796D01*
X2685391Y2656005D01*
X2685701Y2655796D01*
Y2655380D01*
X2685391Y2655171D01*
G01X2706781Y2649963D02*
Y2662463D01*
X2709881D01*
X2711121Y2661838D01*
X2712051Y2661005D01*
X2712826Y2659755D01*
X2713446Y2658296D01*
X2713601Y2656213D01*
X2713446Y2654130D01*
X2712826Y2652671D01*
X2712051Y2651421D01*
X2711121Y2650588D01*
X2709881Y2649963D01*
X2706781D01*
G01X2725691D02*
X2719491D01*
Y2662463D01*
X2725691D01*
G01X2723211Y2656421D02*
X2719491D01*
G01X2731891Y2649963D02*
Y2662463D01*
X2735611D01*
X2736851Y2661838D01*
X2737781Y2660380D01*
X2738091Y2658713D01*
X2737781Y2657046D01*
X2737006Y2655796D01*
X2735611Y2655171D01*
X2731891D01*
G01X2747391Y2662463D02*
Y2649963D01*
G01X2743826Y2662463D02*
X2750956D01*
G01X2756536Y2649963D02*
Y2662463D01*
G01X2763046D02*
Y2649963D01*
G01Y2656213D02*
X2756536D01*
G01X2781646Y2649963D02*
Y2662463D01*
X2787536D01*
G01X2785366Y2656421D02*
X2781646D01*
G01X2793891Y2649963D02*
Y2662463D01*
X2797766D01*
X2799006Y2661838D01*
X2799781Y2661005D01*
X2800091Y2659338D01*
X2799781Y2657671D01*
X2798851Y2656630D01*
X2797766Y2656005D01*
X2793891D01*
G01X2797766D02*
X2800091Y2649963D01*
G01X2809391D02*
X2808151Y2650171D01*
X2807066Y2651004D01*
X2806136Y2652255D01*
X2805516Y2653713D01*
X2805206Y2655380D01*
Y2657046D01*
X2805516Y2658713D01*
X2806136Y2660171D01*
X2807066Y2661421D01*
X2808151Y2662255D01*
X2809391Y2662463D01*
X2810631Y2662255D01*
X2811716Y2661421D01*
X2812646Y2660171D01*
X2813266Y2658713D01*
X2813576Y2657046D01*
Y2655380D01*
X2813266Y2653713D01*
X2812646Y2652255D01*
X2811716Y2651004D01*
X2810631Y2650171D01*
X2809391Y2649963D01*
G01X2817761D02*
Y2662463D01*
X2821791Y2652046D01*
X2825821Y2662463D01*
Y2649963D01*
G01X2843336Y2651629D02*
X2844576Y2650588D01*
X2845971Y2649963D01*
X2847211D01*
X2848451Y2650588D01*
X2849381Y2651629D01*
X2849846Y2653088D01*
X2849536Y2654546D01*
X2848761Y2655796D01*
X2847366Y2656630D01*
X2845506Y2657046D01*
X2844421Y2657880D01*
X2843956Y2659338D01*
X2844266Y2660796D01*
X2845041Y2661838D01*
X2846126Y2662463D01*
X2847211D01*
X2848296Y2662046D01*
X2849226Y2661005D01*
G01X2858991Y2662463D02*
Y2649963D01*
G01X2855426Y2662463D02*
X2862556D01*
G01X2867516Y2649963D02*
X2871391Y2662463D01*
X2875266Y2649963D01*
G01X2873871Y2654338D02*
X2868911D01*
G01X2880691Y2649963D02*
Y2662463D01*
X2884566D01*
X2885806Y2661838D01*
X2886581Y2661005D01*
X2886891Y2659338D01*
X2886581Y2657671D01*
X2885651Y2656630D01*
X2884566Y2656005D01*
X2880691D01*
G01X2884566D02*
X2886891Y2649963D01*
G01X2896191Y2662463D02*
Y2649963D01*
G01X2892626Y2662463D02*
X2899756D01*
G01X2917891D02*
Y2649963D01*
X2924091D01*
G01X2929516D02*
X2933391Y2662463D01*
X2937266Y2649963D01*
G01X2935871Y2654338D02*
X2930911D01*
G01X2945791Y2649963D02*
Y2655588D01*
X2942691Y2662463D01*
G01X2948891D02*
X2945791Y2655588D01*
G01X2961291Y2649963D02*
X2955091D01*
Y2662463D01*
X2961291D01*
G01X2958811Y2656421D02*
X2955091D01*
G01X2967491Y2649963D02*
Y2662463D01*
X2971366D01*
X2972606Y2661838D01*
X2973381Y2661005D01*
X2973691Y2659338D01*
X2973381Y2657671D01*
X2972451Y2656630D01*
X2971366Y2656005D01*
X2967491D01*
G01X2971366D02*
X2973691Y2649963D01*
G01X2995391Y2662463D02*
Y2649963D01*
G01X2991826Y2662463D02*
X2998956D01*
G01X3007791Y2649963D02*
X3006551Y2650171D01*
X3005466Y2651004D01*
X3004536Y2652255D01*
X3003916Y2653713D01*
X3003606Y2655380D01*
Y2657046D01*
X3003916Y2658713D01*
X3004536Y2660171D01*
X3005466Y2661421D01*
X3006551Y2662255D01*
X3007791Y2662463D01*
X3009031Y2662255D01*
X3010116Y2661421D01*
X3011046Y2660171D01*
X3011666Y2658713D01*
X3011976Y2657046D01*
Y2655380D01*
X3011666Y2653713D01*
X3011046Y2652255D01*
X3010116Y2651004D01*
X3009031Y2650171D01*
X3007791Y2649963D01*
G01X3032591Y2662463D02*
Y2649963D01*
G01X3029026Y2662463D02*
X3036156D01*
G01X3041736Y2649963D02*
Y2662463D01*
G01X3048246D02*
Y2649963D01*
G01Y2656213D02*
X3041736D01*
G01X3060491Y2649963D02*
X3054291D01*
Y2662463D01*
X3060491D01*
G01X3058011Y2656421D02*
X3054291D01*
G01X2546976Y2672880D02*
X2551006D01*
G01X2569761Y2668713D02*
Y2681213D01*
X2573791Y2670796D01*
X2577821Y2681213D01*
Y2668713D01*
G01X2582626D02*
Y2681213D01*
X2589756Y2668713D01*
Y2681213D01*
G01X2602001Y2680171D02*
X2601071Y2680796D01*
X2599986Y2681213D01*
X2598746D01*
X2597351Y2680588D01*
X2596266Y2679546D01*
X2595491Y2678296D01*
X2594871Y2676213D01*
X2594716Y2674338D01*
X2595026Y2672463D01*
X2595491Y2671213D01*
X2596421Y2669963D01*
X2597506Y2669130D01*
X2598591Y2668713D01*
X2599676D01*
X2600761Y2669130D01*
X2601691Y2669754D01*
X2602466Y2670588D01*
G01X2606341Y2664546D02*
X2615641D01*
G01X2620291Y2681213D02*
Y2668713D01*
X2626491D01*
G01X2631916D02*
X2635791Y2681213D01*
X2639666Y2668713D01*
G01X2638271Y2673088D02*
X2633311D01*
G01X2648191Y2668713D02*
Y2674338D01*
X2645091Y2681213D01*
G01X2651291D02*
X2648191Y2674338D01*
G01X2663691Y2668713D02*
X2657491D01*
Y2681213D01*
X2663691D01*
G01X2661211Y2675171D02*
X2657491D01*
G01X2669891Y2668713D02*
Y2681213D01*
X2673766D01*
X2675006Y2680588D01*
X2675781Y2679755D01*
X2676091Y2678088D01*
X2675781Y2676421D01*
X2674851Y2675380D01*
X2673766Y2674755D01*
X2669891D01*
G01X2673766D02*
X2676091Y2668713D01*
G01X2685391Y2668296D02*
X2685081Y2668505D01*
Y2668921D01*
X2685391Y2669130D01*
X2685701Y2668921D01*
Y2668505D01*
X2685391Y2668296D01*
G01Y2673921D02*
X2685081Y2674130D01*
Y2674546D01*
X2685391Y2674755D01*
X2685701Y2674546D01*
Y2674130D01*
X2685391Y2673921D01*
G01X2706161Y2668713D02*
Y2681213D01*
X2710191Y2670796D01*
X2714221Y2681213D01*
Y2668713D01*
G01X2719181Y2681213D02*
Y2672255D01*
X2719801Y2670379D01*
X2721041Y2669130D01*
X2722591Y2668713D01*
X2724141Y2669130D01*
X2725381Y2670379D01*
X2726001Y2672255D01*
Y2681213D01*
G01X2731736Y2670379D02*
X2732976Y2669338D01*
X2734371Y2668713D01*
X2735611D01*
X2736851Y2669338D01*
X2737781Y2670379D01*
X2738246Y2671838D01*
X2737936Y2673296D01*
X2737161Y2674546D01*
X2735766Y2675380D01*
X2733906Y2675796D01*
X2732821Y2676630D01*
X2732356Y2678088D01*
X2732666Y2679546D01*
X2733441Y2680588D01*
X2734526Y2681213D01*
X2735611D01*
X2736696Y2680796D01*
X2737626Y2679755D01*
G01X2747391Y2681213D02*
Y2668713D01*
G01X2743826Y2681213D02*
X2750956D01*
G01X2757776Y2672880D02*
X2761806D01*
G01X2768626Y2668713D02*
Y2681213D01*
X2775756Y2668713D01*
Y2681213D01*
G01X2784591Y2668713D02*
X2783351Y2668921D01*
X2782266Y2669754D01*
X2781336Y2671005D01*
X2780716Y2672463D01*
X2780406Y2674130D01*
Y2675796D01*
X2780716Y2677463D01*
X2781336Y2678921D01*
X2782266Y2680171D01*
X2783351Y2681005D01*
X2784591Y2681213D01*
X2785831Y2681005D01*
X2786916Y2680171D01*
X2787846Y2678921D01*
X2788466Y2677463D01*
X2788776Y2675796D01*
Y2674130D01*
X2788466Y2672463D01*
X2787846Y2671005D01*
X2786916Y2669754D01*
X2785831Y2668921D01*
X2784591Y2668713D01*
G01X2796991Y2681213D02*
Y2668713D01*
G01X2793426Y2681213D02*
X2800556D01*
G01X2807376Y2672880D02*
X2811406D01*
G01X2825201Y2680171D02*
X2824271Y2680796D01*
X2823186Y2681213D01*
X2821946D01*
X2820551Y2680588D01*
X2819466Y2679546D01*
X2818691Y2678296D01*
X2818071Y2676213D01*
X2817916Y2674338D01*
X2818226Y2672463D01*
X2818691Y2671213D01*
X2819621Y2669963D01*
X2820706Y2669130D01*
X2821791Y2668713D01*
X2822876D01*
X2823961Y2669130D01*
X2824891Y2669754D01*
X2825666Y2670588D01*
G01X2830781Y2681213D02*
Y2672255D01*
X2831401Y2670379D01*
X2832641Y2669130D01*
X2834191Y2668713D01*
X2835741Y2669130D01*
X2836981Y2670379D01*
X2837601Y2672255D01*
Y2681213D01*
G01X2846591D02*
Y2668713D01*
G01X2843026Y2681213D02*
X2850156D01*
G01X2856976Y2672880D02*
X2861006D01*
G01X2868291Y2681213D02*
Y2668713D01*
X2874491D01*
G01X2879916D02*
X2883791Y2681213D01*
X2887666Y2668713D01*
G01X2886271Y2673088D02*
X2881311D01*
G01X2896191Y2668713D02*
Y2674338D01*
X2893091Y2681213D01*
G01X2899291D02*
X2896191Y2674338D01*
G01X2911691Y2668713D02*
X2905491D01*
Y2681213D01*
X2911691D01*
G01X2909211Y2675171D02*
X2905491D01*
G01X2917891Y2668713D02*
Y2681213D01*
X2921766D01*
X2923006Y2680588D01*
X2923781Y2679755D01*
X2924091Y2678088D01*
X2923781Y2676421D01*
X2922851Y2675380D01*
X2921766Y2674755D01*
X2917891D01*
G01X2921766D02*
X2924091Y2668713D01*
G01X2545426Y2687463D02*
Y2699963D01*
X2552556Y2687463D01*
Y2699963D01*
G01X2561391Y2687463D02*
X2560151Y2687671D01*
X2559066Y2688504D01*
X2558136Y2689755D01*
X2557516Y2691213D01*
X2557206Y2692880D01*
Y2694546D01*
X2557516Y2696213D01*
X2558136Y2697671D01*
X2559066Y2698921D01*
X2560151Y2699755D01*
X2561391Y2699963D01*
X2562631Y2699755D01*
X2563716Y2698921D01*
X2564646Y2697671D01*
X2565266Y2696213D01*
X2565576Y2694546D01*
Y2692880D01*
X2565266Y2691213D01*
X2564646Y2689755D01*
X2563716Y2688504D01*
X2562631Y2687671D01*
X2561391Y2687463D01*
G01X2573791Y2699963D02*
Y2687463D01*
G01X2570226Y2699963D02*
X2577356D01*
G01X2589291Y2687463D02*
X2583091D01*
Y2699963D01*
X2589291D01*
G01X2586811Y2693921D02*
X2583091D01*
G01X2595336Y2689129D02*
X2596576Y2688088D01*
X2597971Y2687463D01*
X2599211D01*
X2600451Y2688088D01*
X2601381Y2689129D01*
X2601846Y2690588D01*
X2601536Y2692046D01*
X2600761Y2693296D01*
X2599366Y2694130D01*
X2597506Y2694546D01*
X2596421Y2695380D01*
X2595956Y2696838D01*
X2596266Y2698296D01*
X2597041Y2699338D01*
X2598126Y2699963D01*
X2599211D01*
X2600296Y2699546D01*
X2601226Y2698505D01*
G01X2610991Y2687046D02*
X2610681Y2687255D01*
Y2687671D01*
X2610991Y2687880D01*
X2611301Y2687671D01*
Y2687255D01*
X2610991Y2687046D01*
G01Y2692671D02*
X2610681Y2692880D01*
Y2693296D01*
X2610991Y2693505D01*
X2611301Y2693296D01*
Y2692880D01*
X2610991Y2692671D01*
G01X2732020Y1855733D02*
X2732640Y1856358D01*
X2733105Y1857399D01*
X2733415Y1858858D01*
X2733105Y1860108D01*
X2732485Y1860941D01*
X2731400Y1861566D01*
X2727215D01*
Y1849066D01*
X2732330D01*
X2733415Y1849899D01*
X2734035Y1851149D01*
X2734345Y1852608D01*
X2734035Y1854066D01*
X2733105Y1855316D01*
X2732020Y1855733D01*
X2727215D01*
G01X2739305Y1849066D02*
X2743180Y1861566D01*
X2747055Y1849066D01*
G01X2745660Y1853441D02*
X2740700D01*
G01X2758990Y1860524D02*
X2758060Y1861149D01*
X2756975Y1861566D01*
X2755735D01*
X2754340Y1860941D01*
X2753255Y1859899D01*
X2752480Y1858649D01*
X2751860Y1856566D01*
X2751705Y1854691D01*
X2752015Y1852816D01*
X2752480Y1851566D01*
X2753410Y1850316D01*
X2754495Y1849483D01*
X2755580Y1849066D01*
X2756665D01*
X2757750Y1849483D01*
X2758680Y1850107D01*
X2759455Y1850941D01*
G01X2764570Y1849066D02*
Y1861566D01*
G01X2770460D02*
X2764570Y1853857D01*
G01X2771390Y1849066D02*
X2767205Y1857399D01*
G01X2776970Y1849066D02*
Y1861566D01*
X2780070D01*
X2781310Y1860941D01*
X2782240Y1860108D01*
X2783015Y1858858D01*
X2783635Y1857399D01*
X2783790Y1855316D01*
X2783635Y1853233D01*
X2783015Y1851774D01*
X2782240Y1850524D01*
X2781310Y1849691D01*
X2780070Y1849066D01*
X2776970D01*
G01X2789680D02*
Y1861566D01*
X2793555D01*
X2794795Y1860941D01*
X2795570Y1860108D01*
X2795880Y1858441D01*
X2795570Y1856774D01*
X2794640Y1855733D01*
X2793555Y1855108D01*
X2789680D01*
G01X2793555D02*
X2795880Y1849066D01*
G01X2803320Y1861566D02*
X2807040D01*
G01X2805180D02*
Y1849066D01*
G01X2803320D02*
X2807040D01*
G01X2814480Y1861566D02*
Y1849066D01*
X2820680D01*
G01X2826880Y1861566D02*
Y1849066D01*
X2833080D01*
G01X2851525Y1850732D02*
X2852765Y1849691D01*
X2854160Y1849066D01*
X2855400D01*
X2856640Y1849691D01*
X2857570Y1850732D01*
X2858035Y1852191D01*
X2857725Y1853649D01*
X2856950Y1854899D01*
X2855555Y1855733D01*
X2853695Y1856149D01*
X2852610Y1856983D01*
X2852145Y1858441D01*
X2852455Y1859899D01*
X2853230Y1860941D01*
X2854315Y1861566D01*
X2855400D01*
X2856485Y1861149D01*
X2857415Y1860108D01*
G01X2867180Y1861566D02*
Y1849066D01*
G01X2863615Y1861566D02*
X2870745D01*
G01X2876170D02*
Y1852608D01*
X2876790Y1850732D01*
X2878030Y1849483D01*
X2879580Y1849066D01*
X2881130Y1849483D01*
X2882370Y1850732D01*
X2882990Y1852608D01*
Y1861566D01*
G01X2893220Y1855733D02*
X2893840Y1856358D01*
X2894305Y1857399D01*
X2894615Y1858858D01*
X2894305Y1860108D01*
X2893685Y1860941D01*
X2892600Y1861566D01*
X2888415D01*
Y1849066D01*
X2893530D01*
X2894615Y1849899D01*
X2895235Y1851149D01*
X2895545Y1852608D01*
X2895235Y1854066D01*
X2894305Y1855316D01*
X2893220Y1855733D01*
X2888415D01*
G01X2913680Y1861566D02*
Y1849066D01*
X2919880D01*
G01X2932280D02*
X2926080D01*
Y1861566D01*
X2932280D01*
G01X2929800Y1855524D02*
X2926080D01*
G01X2938015Y1849066D02*
Y1861566D01*
X2945145Y1849066D01*
Y1861566D01*
G01X2954910Y1855316D02*
X2958010D01*
Y1851566D01*
X2957080Y1850316D01*
X2955995Y1849483D01*
X2954445Y1849066D01*
X2952895Y1849483D01*
X2951810Y1850316D01*
X2950880Y1851566D01*
X2950260Y1853024D01*
X2949950Y1854691D01*
Y1856149D01*
X2950260Y1857399D01*
X2950880Y1858858D01*
X2951810Y1860108D01*
X2952740Y1860941D01*
X2953980Y1861566D01*
X2955065D01*
X2956305Y1861149D01*
X2957235Y1860316D01*
G01X2966380Y1861566D02*
Y1849066D01*
G01X2962815Y1861566D02*
X2969945D01*
G01X2975525Y1849066D02*
Y1861566D01*
G01X2982035D02*
Y1849066D01*
G01Y1855316D02*
X2975525D01*
G01X3003580Y1861566D02*
Y1849066D01*
G01X3000015Y1861566D02*
X3007145D01*
G01X3015980Y1849066D02*
X3014740Y1849274D01*
X3013655Y1850107D01*
X3012725Y1851358D01*
X3012105Y1852816D01*
X3011795Y1854483D01*
Y1856149D01*
X3012105Y1857816D01*
X3012725Y1859274D01*
X3013655Y1860524D01*
X3014740Y1861358D01*
X3015980Y1861566D01*
X3017220Y1861358D01*
X3018305Y1860524D01*
X3019235Y1859274D01*
X3019855Y1857816D01*
X3020165Y1856149D01*
Y1854483D01*
X3019855Y1852816D01*
X3019235Y1851358D01*
X3018305Y1850107D01*
X3017220Y1849274D01*
X3015980Y1849066D01*
G01X3025280Y1861566D02*
Y1849066D01*
X3031480D01*
G01X3043880D02*
X3037680D01*
Y1861566D01*
X3043880D01*
G01X3041400Y1855524D02*
X3037680D01*
G01X3050080Y1849066D02*
Y1861566D01*
X3053955D01*
X3055195Y1860941D01*
X3055970Y1860108D01*
X3056280Y1858441D01*
X3055970Y1856774D01*
X3055040Y1855733D01*
X3053955Y1855108D01*
X3050080D01*
G01X3053955D02*
X3056280Y1849066D01*
G01X3061705D02*
X3065580Y1861566D01*
X3069455Y1849066D01*
G01X3068060Y1853441D02*
X3063100D01*
G01X3074415Y1849066D02*
Y1861566D01*
X3081545Y1849066D01*
Y1861566D01*
G01X3093790Y1860524D02*
X3092860Y1861149D01*
X3091775Y1861566D01*
X3090535D01*
X3089140Y1860941D01*
X3088055Y1859899D01*
X3087280Y1858649D01*
X3086660Y1856566D01*
X3086505Y1854691D01*
X3086815Y1852816D01*
X3087280Y1851566D01*
X3088210Y1850316D01*
X3089295Y1849483D01*
X3090380Y1849066D01*
X3091465D01*
X3092550Y1849483D01*
X3093480Y1850107D01*
X3094255Y1850941D01*
G01X3105880Y1849066D02*
X3099680D01*
Y1861566D01*
X3105880D01*
G01X3103400Y1855524D02*
X3099680D01*
G01X3127580Y1861566D02*
Y1849066D01*
G01X3124015Y1861566D02*
X3131145D01*
G01X3139980Y1849066D02*
X3138740Y1849274D01*
X3137655Y1850107D01*
X3136725Y1851358D01*
X3136105Y1852816D01*
X3135795Y1854483D01*
Y1856149D01*
X3136105Y1857816D01*
X3136725Y1859274D01*
X3137655Y1860524D01*
X3138740Y1861358D01*
X3139980Y1861566D01*
X3141220Y1861358D01*
X3142305Y1860524D01*
X3143235Y1859274D01*
X3143855Y1857816D01*
X3144165Y1856149D01*
Y1854483D01*
X3143855Y1852816D01*
X3143235Y1851358D01*
X3142305Y1850107D01*
X3141220Y1849274D01*
X3139980Y1849066D01*
G01X3166020Y1855733D02*
X3166640Y1856358D01*
X3167105Y1857399D01*
X3167415Y1858858D01*
X3167105Y1860108D01*
X3166485Y1860941D01*
X3165400Y1861566D01*
X3161215D01*
Y1849066D01*
X3166330D01*
X3167415Y1849899D01*
X3168035Y1851149D01*
X3168345Y1852608D01*
X3168035Y1854066D01*
X3167105Y1855316D01*
X3166020Y1855733D01*
X3161215D01*
G01X3180280Y1849066D02*
X3174080D01*
Y1861566D01*
X3180280D01*
G01X3177800Y1855524D02*
X3174080D01*
G01X3201670Y1849066D02*
X3201980Y1851774D01*
X3202445Y1854066D01*
X3203065Y1856149D01*
X3203840Y1858441D01*
X3205080Y1861566D01*
X3198880D01*
G01X3225075Y1853233D02*
X3228795D01*
G01X3226780Y1855941D02*
Y1850524D01*
G01X3236390Y1848649D02*
X3241970Y1861566D01*
G01X3249565Y1853233D02*
X3253595D01*
G01X3260570Y1850941D02*
X3261500Y1849899D01*
X3262585Y1849274D01*
X3263980Y1849066D01*
X3265375Y1849483D01*
X3266460Y1850316D01*
X3267235Y1851774D01*
X3267390Y1853441D01*
X3267080Y1855108D01*
X3266305Y1856149D01*
X3265220Y1856983D01*
X3264135Y1857191D01*
X3263050Y1856983D01*
X3261655Y1856149D01*
X3262120Y1861566D01*
X3266305D01*
G01X3284750Y1849066D02*
Y1861566D01*
X3288780Y1851149D01*
X3292810Y1861566D01*
Y1849066D01*
G01X3299320Y1861566D02*
X3303040D01*
G01X3301180D02*
Y1849066D01*
G01X3299320D02*
X3303040D01*
G01X3310480Y1861566D02*
Y1849066D01*
X3316680D01*
G01X3322725Y1850732D02*
X3323965Y1849691D01*
X3325360Y1849066D01*
X3326600D01*
X3327840Y1849691D01*
X3328770Y1850732D01*
X3329235Y1852191D01*
X3328925Y1853649D01*
X3328150Y1854899D01*
X3326755Y1855733D01*
X3324895Y1856149D01*
X3323810Y1856983D01*
X3323345Y1858441D01*
X3323655Y1859899D01*
X3324430Y1860941D01*
X3325515Y1861566D01*
X3326600D01*
X3327685Y1861149D01*
X3328615Y1860108D01*
G01X2567565Y1871983D02*
X2571595D01*
G01X2590350Y1867816D02*
Y1880316D01*
X2594380Y1869899D01*
X2598410Y1880316D01*
Y1867816D01*
G01X2603835D02*
Y1880316D01*
X2609725D01*
G01X2607555Y1874274D02*
X2603835D01*
G01X2620110Y1874066D02*
X2623210D01*
Y1870316D01*
X2622280Y1869066D01*
X2621195Y1868233D01*
X2619645Y1867816D01*
X2618095Y1868233D01*
X2617010Y1869066D01*
X2616080Y1870316D01*
X2615460Y1871774D01*
X2615150Y1873441D01*
Y1874899D01*
X2615460Y1876149D01*
X2616080Y1877608D01*
X2617010Y1878858D01*
X2617940Y1879691D01*
X2619180Y1880316D01*
X2620265D01*
X2621505Y1879899D01*
X2622435Y1879066D01*
G01X2626930Y1863649D02*
X2636230D01*
G01X2640725Y1869482D02*
X2641965Y1868441D01*
X2643360Y1867816D01*
X2644600D01*
X2645840Y1868441D01*
X2646770Y1869482D01*
X2647235Y1870941D01*
X2646925Y1872399D01*
X2646150Y1873649D01*
X2644755Y1874483D01*
X2642895Y1874899D01*
X2641810Y1875733D01*
X2641345Y1877191D01*
X2641655Y1878649D01*
X2642430Y1879691D01*
X2643515Y1880316D01*
X2644600D01*
X2645685Y1879899D01*
X2646615Y1878858D01*
G01X2656380Y1880316D02*
Y1867816D01*
G01X2652815Y1880316D02*
X2659945D01*
G01X2665370D02*
Y1871358D01*
X2665990Y1869482D01*
X2667230Y1868233D01*
X2668780Y1867816D01*
X2670330Y1868233D01*
X2671570Y1869482D01*
X2672190Y1871358D01*
Y1880316D01*
G01X2682420Y1874483D02*
X2683040Y1875108D01*
X2683505Y1876149D01*
X2683815Y1877608D01*
X2683505Y1878858D01*
X2682885Y1879691D01*
X2681800Y1880316D01*
X2677615D01*
Y1867816D01*
X2682730D01*
X2683815Y1868649D01*
X2684435Y1869899D01*
X2684745Y1871358D01*
X2684435Y1872816D01*
X2683505Y1874066D01*
X2682420Y1874483D01*
X2677615D01*
G01X2705980Y1867399D02*
X2705670Y1867608D01*
Y1868024D01*
X2705980Y1868233D01*
X2706290Y1868024D01*
Y1867608D01*
X2705980Y1867399D01*
G01Y1873024D02*
X2705670Y1873233D01*
Y1873649D01*
X2705980Y1873858D01*
X2706290Y1873649D01*
Y1873233D01*
X2705980Y1873024D01*
G01X2726750Y1867816D02*
Y1880316D01*
X2730780Y1869899D01*
X2734810Y1880316D01*
Y1867816D01*
G01X2739305D02*
X2743180Y1880316D01*
X2747055Y1867816D01*
G01X2745660Y1872191D02*
X2740700D01*
G01X2752015Y1867816D02*
Y1880316D01*
X2759145Y1867816D01*
Y1880316D01*
G01X2764570D02*
Y1871358D01*
X2765190Y1869482D01*
X2766430Y1868233D01*
X2767980Y1867816D01*
X2769530Y1868233D01*
X2770770Y1869482D01*
X2771390Y1871358D01*
Y1880316D01*
G01X2777435Y1867816D02*
Y1880316D01*
X2783325D01*
G01X2781155Y1874274D02*
X2777435D01*
G01X2788905Y1867816D02*
X2792780Y1880316D01*
X2796655Y1867816D01*
G01X2795260Y1872191D02*
X2790300D01*
G01X2808590Y1879274D02*
X2807660Y1879899D01*
X2806575Y1880316D01*
X2805335D01*
X2803940Y1879691D01*
X2802855Y1878649D01*
X2802080Y1877399D01*
X2801460Y1875316D01*
X2801305Y1873441D01*
X2801615Y1871566D01*
X2802080Y1870316D01*
X2803010Y1869066D01*
X2804095Y1868233D01*
X2805180Y1867816D01*
X2806265D01*
X2807350Y1868233D01*
X2808280Y1868857D01*
X2809055Y1869691D01*
G01X2817580Y1880316D02*
Y1867816D01*
G01X2814015Y1880316D02*
X2821145D01*
G01X2826570D02*
Y1871358D01*
X2827190Y1869482D01*
X2828430Y1868233D01*
X2829980Y1867816D01*
X2831530Y1868233D01*
X2832770Y1869482D01*
X2833390Y1871358D01*
Y1880316D01*
G01X2839280Y1867816D02*
Y1880316D01*
X2843155D01*
X2844395Y1879691D01*
X2845170Y1878858D01*
X2845480Y1877191D01*
X2845170Y1875524D01*
X2844240Y1874483D01*
X2843155Y1873858D01*
X2839280D01*
G01X2843155D02*
X2845480Y1867816D01*
G01X2852920Y1880316D02*
X2856640D01*
G01X2854780D02*
Y1867816D01*
G01X2852920D02*
X2856640D01*
G01X2863615D02*
Y1880316D01*
X2870745Y1867816D01*
Y1880316D01*
G01X2880510Y1874066D02*
X2883610D01*
Y1870316D01*
X2882680Y1869066D01*
X2881595Y1868233D01*
X2880045Y1867816D01*
X2878495Y1868233D01*
X2877410Y1869066D01*
X2876480Y1870316D01*
X2875860Y1871774D01*
X2875550Y1873441D01*
Y1874899D01*
X2875860Y1876149D01*
X2876480Y1877608D01*
X2877410Y1878858D01*
X2878340Y1879691D01*
X2879580Y1880316D01*
X2880665D01*
X2881905Y1879899D01*
X2882835Y1879066D01*
G01X2901125Y1869482D02*
X2902365Y1868441D01*
X2903760Y1867816D01*
X2905000D01*
X2906240Y1868441D01*
X2907170Y1869482D01*
X2907635Y1870941D01*
X2907325Y1872399D01*
X2906550Y1873649D01*
X2905155Y1874483D01*
X2903295Y1874899D01*
X2902210Y1875733D01*
X2901745Y1877191D01*
X2902055Y1878649D01*
X2902830Y1879691D01*
X2903915Y1880316D01*
X2905000D01*
X2906085Y1879899D01*
X2907015Y1878858D01*
G01X2916780Y1880316D02*
Y1867816D01*
G01X2913215Y1880316D02*
X2920345D01*
G01X2925770D02*
Y1871358D01*
X2926390Y1869482D01*
X2927630Y1868233D01*
X2929180Y1867816D01*
X2930730Y1868233D01*
X2931970Y1869482D01*
X2932590Y1871358D01*
Y1880316D01*
G01X2942820Y1874483D02*
X2943440Y1875108D01*
X2943905Y1876149D01*
X2944215Y1877608D01*
X2943905Y1878858D01*
X2943285Y1879691D01*
X2942200Y1880316D01*
X2938015D01*
Y1867816D01*
X2943130D01*
X2944215Y1868649D01*
X2944835Y1869899D01*
X2945145Y1871358D01*
X2944835Y1872816D01*
X2943905Y1874066D01*
X2942820Y1874483D01*
X2938015D01*
G01X2963280Y1880316D02*
Y1867816D01*
X2969480D01*
G01X2981880D02*
X2975680D01*
Y1880316D01*
X2981880D01*
G01X2979400Y1874274D02*
X2975680D01*
G01X2987615Y1867816D02*
Y1880316D01*
X2994745Y1867816D01*
Y1880316D01*
G01X3004510Y1874066D02*
X3007610D01*
Y1870316D01*
X3006680Y1869066D01*
X3005595Y1868233D01*
X3004045Y1867816D01*
X3002495Y1868233D01*
X3001410Y1869066D01*
X3000480Y1870316D01*
X2999860Y1871774D01*
X2999550Y1873441D01*
Y1874899D01*
X2999860Y1876149D01*
X3000480Y1877608D01*
X3001410Y1878858D01*
X3002340Y1879691D01*
X3003580Y1880316D01*
X3004665D01*
X3005905Y1879899D01*
X3006835Y1879066D01*
G01X3015980Y1880316D02*
Y1867816D01*
G01X3012415Y1880316D02*
X3019545D01*
G01X3025125Y1867816D02*
Y1880316D01*
G01X3031635D02*
Y1867816D01*
G01Y1874066D02*
X3025125D01*
G01X2727525Y1888232D02*
X2728765Y1887191D01*
X2730160Y1886566D01*
X2731400D01*
X2732640Y1887191D01*
X2733570Y1888232D01*
X2734035Y1889691D01*
X2733725Y1891149D01*
X2732950Y1892399D01*
X2731555Y1893233D01*
X2729695Y1893649D01*
X2728610Y1894483D01*
X2728145Y1895941D01*
X2728455Y1897399D01*
X2729230Y1898441D01*
X2730315Y1899066D01*
X2731400D01*
X2732485Y1898649D01*
X2733415Y1897608D01*
G01X2739770Y1899066D02*
Y1890108D01*
X2740390Y1888232D01*
X2741630Y1886983D01*
X2743180Y1886566D01*
X2744730Y1886983D01*
X2745970Y1888232D01*
X2746590Y1890108D01*
Y1899066D01*
G01X2752480Y1886566D02*
Y1899066D01*
X2756355D01*
X2757595Y1898441D01*
X2758370Y1897608D01*
X2758680Y1895941D01*
X2758370Y1894274D01*
X2757440Y1893233D01*
X2756355Y1892608D01*
X2752480D01*
G01X2756355D02*
X2758680Y1886566D01*
G01X2765035D02*
Y1899066D01*
X2770925D01*
G01X2768755Y1893024D02*
X2765035D01*
G01X2776505Y1886566D02*
X2780380Y1899066D01*
X2784255Y1886566D01*
G01X2782860Y1890941D02*
X2777900D01*
G01X2796190Y1898024D02*
X2795260Y1898649D01*
X2794175Y1899066D01*
X2792935D01*
X2791540Y1898441D01*
X2790455Y1897399D01*
X2789680Y1896149D01*
X2789060Y1894066D01*
X2788905Y1892191D01*
X2789215Y1890316D01*
X2789680Y1889066D01*
X2790610Y1887816D01*
X2791695Y1886983D01*
X2792780Y1886566D01*
X2793865D01*
X2794950Y1886983D01*
X2795880Y1887607D01*
X2796655Y1888441D01*
G01X2808280Y1886566D02*
X2802080D01*
Y1899066D01*
X2808280D01*
G01X2805800Y1893024D02*
X2802080D01*
G01X2829980Y1886566D02*
X2828740Y1886774D01*
X2827655Y1887607D01*
X2826725Y1888858D01*
X2826105Y1890316D01*
X2825795Y1891983D01*
Y1893649D01*
X2826105Y1895316D01*
X2826725Y1896774D01*
X2827655Y1898024D01*
X2828740Y1898858D01*
X2829980Y1899066D01*
X2831220Y1898858D01*
X2832305Y1898024D01*
X2833235Y1896774D01*
X2833855Y1895316D01*
X2834165Y1893649D01*
Y1891983D01*
X2833855Y1890316D01*
X2833235Y1888858D01*
X2832305Y1887607D01*
X2831220Y1886774D01*
X2829980Y1886566D01*
G01X2839435D02*
Y1899066D01*
X2845325D01*
G01X2843155Y1893024D02*
X2839435D01*
G01X2863150Y1886566D02*
Y1899066D01*
X2867180Y1888649D01*
X2871210Y1899066D01*
Y1886566D01*
G01X2876170Y1899066D02*
Y1890108D01*
X2876790Y1888232D01*
X2878030Y1886983D01*
X2879580Y1886566D01*
X2881130Y1886983D01*
X2882370Y1888232D01*
X2882990Y1890108D01*
Y1899066D01*
G01X2888725Y1888232D02*
X2889965Y1887191D01*
X2891360Y1886566D01*
X2892600D01*
X2893840Y1887191D01*
X2894770Y1888232D01*
X2895235Y1889691D01*
X2894925Y1891149D01*
X2894150Y1892399D01*
X2892755Y1893233D01*
X2890895Y1893649D01*
X2889810Y1894483D01*
X2889345Y1895941D01*
X2889655Y1897399D01*
X2890430Y1898441D01*
X2891515Y1899066D01*
X2892600D01*
X2893685Y1898649D01*
X2894615Y1897608D01*
G01X2904380Y1899066D02*
Y1886566D01*
G01X2900815Y1899066D02*
X2907945D01*
G01X2914765Y1890733D02*
X2918795D01*
G01X2925615Y1886566D02*
Y1899066D01*
X2932745Y1886566D01*
Y1899066D01*
G01X2941580Y1886566D02*
X2940340Y1886774D01*
X2939255Y1887607D01*
X2938325Y1888858D01*
X2937705Y1890316D01*
X2937395Y1891983D01*
Y1893649D01*
X2937705Y1895316D01*
X2938325Y1896774D01*
X2939255Y1898024D01*
X2940340Y1898858D01*
X2941580Y1899066D01*
X2942820Y1898858D01*
X2943905Y1898024D01*
X2944835Y1896774D01*
X2945455Y1895316D01*
X2945765Y1893649D01*
Y1891983D01*
X2945455Y1890316D01*
X2944835Y1888858D01*
X2943905Y1887607D01*
X2942820Y1886774D01*
X2941580Y1886566D01*
G01X2953980Y1899066D02*
Y1886566D01*
G01X2950415Y1899066D02*
X2957545D01*
G01X2964365Y1890733D02*
X2968395D01*
G01X2982190Y1898024D02*
X2981260Y1898649D01*
X2980175Y1899066D01*
X2978935D01*
X2977540Y1898441D01*
X2976455Y1897399D01*
X2975680Y1896149D01*
X2975060Y1894066D01*
X2974905Y1892191D01*
X2975215Y1890316D01*
X2975680Y1889066D01*
X2976610Y1887816D01*
X2977695Y1886983D01*
X2978780Y1886566D01*
X2979865D01*
X2980950Y1886983D01*
X2981880Y1887607D01*
X2982655Y1888441D01*
G01X2987770Y1899066D02*
Y1890108D01*
X2988390Y1888232D01*
X2989630Y1886983D01*
X2991180Y1886566D01*
X2992730Y1886983D01*
X2993970Y1888232D01*
X2994590Y1890108D01*
Y1899066D01*
G01X3003580D02*
Y1886566D01*
G01X3000015Y1899066D02*
X3007145D01*
G01X3013965Y1890733D02*
X3017995D01*
G01X3025280Y1899066D02*
Y1886566D01*
X3031480D01*
G01X3036905D02*
X3040780Y1899066D01*
X3044655Y1886566D01*
G01X3043260Y1890941D02*
X3038300D01*
G01X3053180Y1886566D02*
Y1892191D01*
X3050080Y1899066D01*
G01X3056280D02*
X3053180Y1892191D01*
G01X3068680Y1886566D02*
X3062480D01*
Y1899066D01*
X3068680D01*
G01X3066200Y1893024D02*
X3062480D01*
G01X3074880Y1886566D02*
Y1899066D01*
X3078755D01*
X3079995Y1898441D01*
X3080770Y1897608D01*
X3081080Y1895941D01*
X3080770Y1894274D01*
X3079840Y1893233D01*
X3078755Y1892608D01*
X3074880D01*
G01X3078755D02*
X3081080Y1886566D01*
G01X2567565Y1909483D02*
X2571595D01*
G01X2590350Y1905316D02*
Y1917816D01*
X2594380Y1907399D01*
X2598410Y1917816D01*
Y1905316D01*
G01X2602905D02*
X2606780Y1917816D01*
X2610655Y1905316D01*
G01X2609260Y1909691D02*
X2604300D01*
G01X2615925Y1905316D02*
X2622435Y1917816D01*
G01X2615925D02*
X2622435Y1905316D01*
G01X2626930Y1901149D02*
X2636230D01*
G01X2640570Y1905316D02*
Y1917816D01*
X2643670D01*
X2644910Y1917191D01*
X2645840Y1916358D01*
X2646615Y1915108D01*
X2647235Y1913649D01*
X2647390Y1911566D01*
X2647235Y1909483D01*
X2646615Y1908024D01*
X2645840Y1906774D01*
X2644910Y1905941D01*
X2643670Y1905316D01*
X2640570D01*
G01X2659480D02*
X2653280D01*
Y1917816D01*
X2659480D01*
G01X2657000Y1911774D02*
X2653280D01*
G01X2665680Y1905316D02*
Y1917816D01*
X2669400D01*
X2670640Y1917191D01*
X2671570Y1915733D01*
X2671880Y1914066D01*
X2671570Y1912399D01*
X2670795Y1911149D01*
X2669400Y1910524D01*
X2665680D01*
G01X2681180Y1917816D02*
Y1905316D01*
G01X2677615Y1917816D02*
X2684745D01*
G01X2690325Y1905316D02*
Y1917816D01*
G01X2696835D02*
Y1905316D01*
G01Y1911566D02*
X2690325D01*
G01X2705980Y1904899D02*
X2705670Y1905108D01*
Y1905524D01*
X2705980Y1905733D01*
X2706290Y1905524D01*
Y1905108D01*
X2705980Y1904899D01*
G01Y1910524D02*
X2705670Y1910733D01*
Y1911149D01*
X2705980Y1911358D01*
X2706290Y1911149D01*
Y1910733D01*
X2705980Y1910524D01*
G01X2727370Y1905316D02*
Y1917816D01*
X2730470D01*
X2731710Y1917191D01*
X2732640Y1916358D01*
X2733415Y1915108D01*
X2734035Y1913649D01*
X2734190Y1911566D01*
X2734035Y1909483D01*
X2733415Y1908024D01*
X2732640Y1906774D01*
X2731710Y1905941D01*
X2730470Y1905316D01*
X2727370D01*
G01X2746280D02*
X2740080D01*
Y1917816D01*
X2746280D01*
G01X2743800Y1911774D02*
X2740080D01*
G01X2752480Y1905316D02*
Y1917816D01*
X2756200D01*
X2757440Y1917191D01*
X2758370Y1915733D01*
X2758680Y1914066D01*
X2758370Y1912399D01*
X2757595Y1911149D01*
X2756200Y1910524D01*
X2752480D01*
G01X2767980Y1917816D02*
Y1905316D01*
G01X2764415Y1917816D02*
X2771545D01*
G01X2777125Y1905316D02*
Y1917816D01*
G01X2783635D02*
Y1905316D01*
G01Y1911566D02*
X2777125D01*
G01X2802235Y1905316D02*
Y1917816D01*
X2808125D01*
G01X2805955Y1911774D02*
X2802235D01*
G01X2814480Y1905316D02*
Y1917816D01*
X2818355D01*
X2819595Y1917191D01*
X2820370Y1916358D01*
X2820680Y1914691D01*
X2820370Y1913024D01*
X2819440Y1911983D01*
X2818355Y1911358D01*
X2814480D01*
G01X2818355D02*
X2820680Y1905316D01*
G01X2829980D02*
X2828740Y1905524D01*
X2827655Y1906357D01*
X2826725Y1907608D01*
X2826105Y1909066D01*
X2825795Y1910733D01*
Y1912399D01*
X2826105Y1914066D01*
X2826725Y1915524D01*
X2827655Y1916774D01*
X2828740Y1917608D01*
X2829980Y1917816D01*
X2831220Y1917608D01*
X2832305Y1916774D01*
X2833235Y1915524D01*
X2833855Y1914066D01*
X2834165Y1912399D01*
Y1910733D01*
X2833855Y1909066D01*
X2833235Y1907608D01*
X2832305Y1906357D01*
X2831220Y1905524D01*
X2829980Y1905316D01*
G01X2838350D02*
Y1917816D01*
X2842380Y1907399D01*
X2846410Y1917816D01*
Y1905316D01*
G01X2863925Y1906982D02*
X2865165Y1905941D01*
X2866560Y1905316D01*
X2867800D01*
X2869040Y1905941D01*
X2869970Y1906982D01*
X2870435Y1908441D01*
X2870125Y1909899D01*
X2869350Y1911149D01*
X2867955Y1911983D01*
X2866095Y1912399D01*
X2865010Y1913233D01*
X2864545Y1914691D01*
X2864855Y1916149D01*
X2865630Y1917191D01*
X2866715Y1917816D01*
X2867800D01*
X2868885Y1917399D01*
X2869815Y1916358D01*
G01X2879580Y1917816D02*
Y1905316D01*
G01X2876015Y1917816D02*
X2883145D01*
G01X2888105Y1905316D02*
X2891980Y1917816D01*
X2895855Y1905316D01*
G01X2894460Y1909691D02*
X2889500D01*
G01X2901280Y1905316D02*
Y1917816D01*
X2905155D01*
X2906395Y1917191D01*
X2907170Y1916358D01*
X2907480Y1914691D01*
X2907170Y1913024D01*
X2906240Y1911983D01*
X2905155Y1911358D01*
X2901280D01*
G01X2905155D02*
X2907480Y1905316D01*
G01X2916780Y1917816D02*
Y1905316D01*
G01X2913215Y1917816D02*
X2920345D01*
G01X2938480D02*
Y1905316D01*
X2944680D01*
G01X2950105D02*
X2953980Y1917816D01*
X2957855Y1905316D01*
G01X2956460Y1909691D02*
X2951500D01*
G01X2966380Y1905316D02*
Y1910941D01*
X2963280Y1917816D01*
G01X2969480D02*
X2966380Y1910941D01*
G01X2981880Y1905316D02*
X2975680D01*
Y1917816D01*
X2981880D01*
G01X2979400Y1911774D02*
X2975680D01*
G01X2988080Y1905316D02*
Y1917816D01*
X2991955D01*
X2993195Y1917191D01*
X2993970Y1916358D01*
X2994280Y1914691D01*
X2993970Y1913024D01*
X2993040Y1911983D01*
X2991955Y1911358D01*
X2988080D01*
G01X2991955D02*
X2994280Y1905316D01*
G01X3015980Y1917816D02*
Y1905316D01*
G01X3012415Y1917816D02*
X3019545D01*
G01X3028380Y1905316D02*
X3027140Y1905524D01*
X3026055Y1906357D01*
X3025125Y1907608D01*
X3024505Y1909066D01*
X3024195Y1910733D01*
Y1912399D01*
X3024505Y1914066D01*
X3025125Y1915524D01*
X3026055Y1916774D01*
X3027140Y1917608D01*
X3028380Y1917816D01*
X3029620Y1917608D01*
X3030705Y1916774D01*
X3031635Y1915524D01*
X3032255Y1914066D01*
X3032565Y1912399D01*
Y1910733D01*
X3032255Y1909066D01*
X3031635Y1907608D01*
X3030705Y1906357D01*
X3029620Y1905524D01*
X3028380Y1905316D01*
G01X3053180Y1917816D02*
Y1905316D01*
G01X3049615Y1917816D02*
X3056745D01*
G01X3062325Y1905316D02*
Y1917816D01*
G01X3068835D02*
Y1905316D01*
G01Y1911566D02*
X3062325D01*
G01X3081080Y1905316D02*
X3074880D01*
Y1917816D01*
X3081080D01*
G01X3078600Y1911774D02*
X3074880D01*
G01X2567565Y1928233D02*
X2571595D01*
G01X2590350Y1924066D02*
Y1936566D01*
X2594380Y1926149D01*
X2598410Y1936566D01*
Y1924066D01*
G01X2603215D02*
Y1936566D01*
X2610345Y1924066D01*
Y1936566D01*
G01X2622590Y1935524D02*
X2621660Y1936149D01*
X2620575Y1936566D01*
X2619335D01*
X2617940Y1935941D01*
X2616855Y1934899D01*
X2616080Y1933649D01*
X2615460Y1931566D01*
X2615305Y1929691D01*
X2615615Y1927816D01*
X2616080Y1926566D01*
X2617010Y1925316D01*
X2618095Y1924483D01*
X2619180Y1924066D01*
X2620265D01*
X2621350Y1924483D01*
X2622280Y1925107D01*
X2623055Y1925941D01*
G01X2626930Y1919899D02*
X2636230D01*
G01X2640880Y1936566D02*
Y1924066D01*
X2647080D01*
G01X2652505D02*
X2656380Y1936566D01*
X2660255Y1924066D01*
G01X2658860Y1928441D02*
X2653900D01*
G01X2668780Y1924066D02*
Y1929691D01*
X2665680Y1936566D01*
G01X2671880D02*
X2668780Y1929691D01*
G01X2684280Y1924066D02*
X2678080D01*
Y1936566D01*
X2684280D01*
G01X2681800Y1930524D02*
X2678080D01*
G01X2690480Y1924066D02*
Y1936566D01*
X2694355D01*
X2695595Y1935941D01*
X2696370Y1935108D01*
X2696680Y1933441D01*
X2696370Y1931774D01*
X2695440Y1930733D01*
X2694355Y1930108D01*
X2690480D01*
G01X2694355D02*
X2696680Y1924066D01*
G01X2705980Y1923649D02*
X2705670Y1923858D01*
Y1924274D01*
X2705980Y1924483D01*
X2706290Y1924274D01*
Y1923858D01*
X2705980Y1923649D01*
G01Y1929274D02*
X2705670Y1929483D01*
Y1929899D01*
X2705980Y1930108D01*
X2706290Y1929899D01*
Y1929483D01*
X2705980Y1929274D01*
G01X2726750Y1924066D02*
Y1936566D01*
X2730780Y1926149D01*
X2734810Y1936566D01*
Y1924066D01*
G01X2739770Y1936566D02*
Y1927608D01*
X2740390Y1925732D01*
X2741630Y1924483D01*
X2743180Y1924066D01*
X2744730Y1924483D01*
X2745970Y1925732D01*
X2746590Y1927608D01*
Y1936566D01*
G01X2752325Y1925732D02*
X2753565Y1924691D01*
X2754960Y1924066D01*
X2756200D01*
X2757440Y1924691D01*
X2758370Y1925732D01*
X2758835Y1927191D01*
X2758525Y1928649D01*
X2757750Y1929899D01*
X2756355Y1930733D01*
X2754495Y1931149D01*
X2753410Y1931983D01*
X2752945Y1933441D01*
X2753255Y1934899D01*
X2754030Y1935941D01*
X2755115Y1936566D01*
X2756200D01*
X2757285Y1936149D01*
X2758215Y1935108D01*
G01X2767980Y1936566D02*
Y1924066D01*
G01X2764415Y1936566D02*
X2771545D01*
G01X2778365Y1928233D02*
X2782395D01*
G01X2789215Y1924066D02*
Y1936566D01*
X2796345Y1924066D01*
Y1936566D01*
G01X2805180Y1924066D02*
X2803940Y1924274D01*
X2802855Y1925107D01*
X2801925Y1926358D01*
X2801305Y1927816D01*
X2800995Y1929483D01*
Y1931149D01*
X2801305Y1932816D01*
X2801925Y1934274D01*
X2802855Y1935524D01*
X2803940Y1936358D01*
X2805180Y1936566D01*
X2806420Y1936358D01*
X2807505Y1935524D01*
X2808435Y1934274D01*
X2809055Y1932816D01*
X2809365Y1931149D01*
Y1929483D01*
X2809055Y1927816D01*
X2808435Y1926358D01*
X2807505Y1925107D01*
X2806420Y1924274D01*
X2805180Y1924066D01*
G01X2817580Y1936566D02*
Y1924066D01*
G01X2814015Y1936566D02*
X2821145D01*
G01X2827965Y1928233D02*
X2831995D01*
G01X2845790Y1935524D02*
X2844860Y1936149D01*
X2843775Y1936566D01*
X2842535D01*
X2841140Y1935941D01*
X2840055Y1934899D01*
X2839280Y1933649D01*
X2838660Y1931566D01*
X2838505Y1929691D01*
X2838815Y1927816D01*
X2839280Y1926566D01*
X2840210Y1925316D01*
X2841295Y1924483D01*
X2842380Y1924066D01*
X2843465D01*
X2844550Y1924483D01*
X2845480Y1925107D01*
X2846255Y1925941D01*
G01X2851370Y1936566D02*
Y1927608D01*
X2851990Y1925732D01*
X2853230Y1924483D01*
X2854780Y1924066D01*
X2856330Y1924483D01*
X2857570Y1925732D01*
X2858190Y1927608D01*
Y1936566D01*
G01X2867180D02*
Y1924066D01*
G01X2863615Y1936566D02*
X2870745D01*
G01X2877565Y1928233D02*
X2881595D01*
G01X2888880Y1936566D02*
Y1924066D01*
X2895080D01*
G01X2900505D02*
X2904380Y1936566D01*
X2908255Y1924066D01*
G01X2906860Y1928441D02*
X2901900D01*
G01X2916780Y1924066D02*
Y1929691D01*
X2913680Y1936566D01*
G01X2919880D02*
X2916780Y1929691D01*
G01X2932280Y1924066D02*
X2926080D01*
Y1936566D01*
X2932280D01*
G01X2929800Y1930524D02*
X2926080D01*
G01X2938480Y1924066D02*
Y1936566D01*
X2942355D01*
X2943595Y1935941D01*
X2944370Y1935108D01*
X2944680Y1933441D01*
X2944370Y1931774D01*
X2943440Y1930733D01*
X2942355Y1930108D01*
X2938480D01*
G01X2942355D02*
X2944680Y1924066D01*
G01X2566015Y1942816D02*
Y1955316D01*
X2573145Y1942816D01*
Y1955316D01*
G01X2581980Y1942816D02*
X2580740Y1943024D01*
X2579655Y1943857D01*
X2578725Y1945108D01*
X2578105Y1946566D01*
X2577795Y1948233D01*
Y1949899D01*
X2578105Y1951566D01*
X2578725Y1953024D01*
X2579655Y1954274D01*
X2580740Y1955108D01*
X2581980Y1955316D01*
X2583220Y1955108D01*
X2584305Y1954274D01*
X2585235Y1953024D01*
X2585855Y1951566D01*
X2586165Y1949899D01*
Y1948233D01*
X2585855Y1946566D01*
X2585235Y1945108D01*
X2584305Y1943857D01*
X2583220Y1943024D01*
X2581980Y1942816D01*
G01X2594380Y1955316D02*
Y1942816D01*
G01X2590815Y1955316D02*
X2597945D01*
G01X2609880Y1942816D02*
X2603680D01*
Y1955316D01*
X2609880D01*
G01X2607400Y1949274D02*
X2603680D01*
G01X2615925Y1944482D02*
X2617165Y1943441D01*
X2618560Y1942816D01*
X2619800D01*
X2621040Y1943441D01*
X2621970Y1944482D01*
X2622435Y1945941D01*
X2622125Y1947399D01*
X2621350Y1948649D01*
X2619955Y1949483D01*
X2618095Y1949899D01*
X2617010Y1950733D01*
X2616545Y1952191D01*
X2616855Y1953649D01*
X2617630Y1954691D01*
X2618715Y1955316D01*
X2619800D01*
X2620885Y1954899D01*
X2621815Y1953858D01*
G01X2631580Y1942399D02*
X2631270Y1942608D01*
Y1943024D01*
X2631580Y1943233D01*
X2631890Y1943024D01*
Y1942608D01*
X2631580Y1942399D01*
G01Y1948024D02*
X2631270Y1948233D01*
Y1948649D01*
X2631580Y1948858D01*
X2631890Y1948649D01*
Y1948233D01*
X2631580Y1948024D01*
G01X2555346Y2787463D02*
Y2799963D01*
X2561236D01*
G01X2559066Y2793921D02*
X2555346D01*
G01X2568831Y2799963D02*
X2572551D01*
G01X2570691D02*
Y2787463D01*
G01X2568831D02*
X2572551D01*
G01X2584021Y2793713D02*
X2587121D01*
Y2789963D01*
X2586191Y2788713D01*
X2585106Y2787880D01*
X2583556Y2787463D01*
X2582006Y2787880D01*
X2580921Y2788713D01*
X2579991Y2789963D01*
X2579371Y2791421D01*
X2579061Y2793088D01*
Y2794546D01*
X2579371Y2795796D01*
X2579991Y2797255D01*
X2580921Y2798505D01*
X2581851Y2799338D01*
X2583091Y2799963D01*
X2584176D01*
X2585416Y2799546D01*
X2586346Y2798713D01*
G01X2592081Y2799963D02*
Y2791005D01*
X2592701Y2789129D01*
X2593941Y2787880D01*
X2595491Y2787463D01*
X2597041Y2787880D01*
X2598281Y2789129D01*
X2598901Y2791005D01*
Y2799963D01*
G01X2604791Y2787463D02*
Y2799963D01*
X2608666D01*
X2609906Y2799338D01*
X2610681Y2798505D01*
X2610991Y2796838D01*
X2610681Y2795171D01*
X2609751Y2794130D01*
X2608666Y2793505D01*
X2604791D01*
G01X2608666D02*
X2610991Y2787463D01*
G01X2623391D02*
X2617191D01*
Y2799963D01*
X2623391D01*
G01X2620911Y2793921D02*
X2617191D01*
G01X2575935Y2042816D02*
Y2055316D01*
X2581825D01*
G01X2579655Y2049274D02*
X2575935D01*
G01X2589420Y2055316D02*
X2593140D01*
G01X2591280D02*
Y2042816D01*
G01X2589420D02*
X2593140D01*
G01X2604610Y2049066D02*
X2607710D01*
Y2045316D01*
X2606780Y2044066D01*
X2605695Y2043233D01*
X2604145Y2042816D01*
X2602595Y2043233D01*
X2601510Y2044066D01*
X2600580Y2045316D01*
X2599960Y2046774D01*
X2599650Y2048441D01*
Y2049899D01*
X2599960Y2051149D01*
X2600580Y2052608D01*
X2601510Y2053858D01*
X2602440Y2054691D01*
X2603680Y2055316D01*
X2604765D01*
X2606005Y2054899D01*
X2606935Y2054066D01*
G01X2612670Y2055316D02*
Y2046358D01*
X2613290Y2044482D01*
X2614530Y2043233D01*
X2616080Y2042816D01*
X2617630Y2043233D01*
X2618870Y2044482D01*
X2619490Y2046358D01*
Y2055316D01*
G01X2625380Y2042816D02*
Y2055316D01*
X2629255D01*
X2630495Y2054691D01*
X2631270Y2053858D01*
X2631580Y2052191D01*
X2631270Y2050524D01*
X2630340Y2049483D01*
X2629255Y2048858D01*
X2625380D01*
G01X2629255D02*
X2631580Y2042816D01*
G01X2643980D02*
X2637780D01*
Y2055316D01*
X2643980D01*
G01X2641500Y2049274D02*
X2637780D01*
G01X2766336Y1141970D02*
X2766956Y1142595D01*
X2767421Y1143636D01*
X2767731Y1145095D01*
X2767421Y1146345D01*
X2766801Y1147178D01*
X2765716Y1147803D01*
X2761531D01*
Y1135303D01*
X2766646D01*
X2767731Y1136136D01*
X2768351Y1137386D01*
X2768661Y1138845D01*
X2768351Y1140303D01*
X2767421Y1141553D01*
X2766336Y1141970D01*
X2761531D01*
G01X2773621Y1135303D02*
X2777496Y1147803D01*
X2781371Y1135303D01*
G01X2779976Y1139678D02*
X2775016D01*
G01X2793306Y1146761D02*
X2792376Y1147386D01*
X2791291Y1147803D01*
X2790051D01*
X2788656Y1147178D01*
X2787571Y1146136D01*
X2786796Y1144886D01*
X2786176Y1142803D01*
X2786021Y1140928D01*
X2786331Y1139053D01*
X2786796Y1137803D01*
X2787726Y1136553D01*
X2788811Y1135720D01*
X2789896Y1135303D01*
X2790981D01*
X2792066Y1135720D01*
X2792996Y1136344D01*
X2793771Y1137178D01*
G01X2798886Y1135303D02*
Y1147803D01*
G01X2804776D02*
X2798886Y1140094D01*
G01X2805706Y1135303D02*
X2801521Y1143636D01*
G01X2811286Y1135303D02*
Y1147803D01*
X2814386D01*
X2815626Y1147178D01*
X2816556Y1146345D01*
X2817331Y1145095D01*
X2817951Y1143636D01*
X2818106Y1141553D01*
X2817951Y1139470D01*
X2817331Y1138011D01*
X2816556Y1136761D01*
X2815626Y1135928D01*
X2814386Y1135303D01*
X2811286D01*
G01X2823996D02*
Y1147803D01*
X2827871D01*
X2829111Y1147178D01*
X2829886Y1146345D01*
X2830196Y1144678D01*
X2829886Y1143011D01*
X2828956Y1141970D01*
X2827871Y1141345D01*
X2823996D01*
G01X2827871D02*
X2830196Y1135303D01*
G01X2837636Y1147803D02*
X2841356D01*
G01X2839496D02*
Y1135303D01*
G01X2837636D02*
X2841356D01*
G01X2848796Y1147803D02*
Y1135303D01*
X2854996D01*
G01X2861196Y1147803D02*
Y1135303D01*
X2867396D01*
G01X2885841Y1136969D02*
X2887081Y1135928D01*
X2888476Y1135303D01*
X2889716D01*
X2890956Y1135928D01*
X2891886Y1136969D01*
X2892351Y1138428D01*
X2892041Y1139886D01*
X2891266Y1141136D01*
X2889871Y1141970D01*
X2888011Y1142386D01*
X2886926Y1143220D01*
X2886461Y1144678D01*
X2886771Y1146136D01*
X2887546Y1147178D01*
X2888631Y1147803D01*
X2889716D01*
X2890801Y1147386D01*
X2891731Y1146345D01*
G01X2901496Y1147803D02*
Y1135303D01*
G01X2897931Y1147803D02*
X2905061D01*
G01X2910486D02*
Y1138845D01*
X2911106Y1136969D01*
X2912346Y1135720D01*
X2913896Y1135303D01*
X2915446Y1135720D01*
X2916686Y1136969D01*
X2917306Y1138845D01*
Y1147803D01*
G01X2927536Y1141970D02*
X2928156Y1142595D01*
X2928621Y1143636D01*
X2928931Y1145095D01*
X2928621Y1146345D01*
X2928001Y1147178D01*
X2926916Y1147803D01*
X2922731D01*
Y1135303D01*
X2927846D01*
X2928931Y1136136D01*
X2929551Y1137386D01*
X2929861Y1138845D01*
X2929551Y1140303D01*
X2928621Y1141553D01*
X2927536Y1141970D01*
X2922731D01*
G01X2947996Y1147803D02*
Y1135303D01*
X2954196D01*
G01X2966596D02*
X2960396D01*
Y1147803D01*
X2966596D01*
G01X2964116Y1141761D02*
X2960396D01*
G01X2972331Y1135303D02*
Y1147803D01*
X2979461Y1135303D01*
Y1147803D01*
G01X2989226Y1141553D02*
X2992326D01*
Y1137803D01*
X2991396Y1136553D01*
X2990311Y1135720D01*
X2988761Y1135303D01*
X2987211Y1135720D01*
X2986126Y1136553D01*
X2985196Y1137803D01*
X2984576Y1139261D01*
X2984266Y1140928D01*
Y1142386D01*
X2984576Y1143636D01*
X2985196Y1145095D01*
X2986126Y1146345D01*
X2987056Y1147178D01*
X2988296Y1147803D01*
X2989381D01*
X2990621Y1147386D01*
X2991551Y1146553D01*
G01X3000696Y1147803D02*
Y1135303D01*
G01X2997131Y1147803D02*
X3004261D01*
G01X3009841Y1135303D02*
Y1147803D01*
G01X3016351D02*
Y1135303D01*
G01Y1141553D02*
X3009841D01*
G01X3037896Y1147803D02*
Y1135303D01*
G01X3034331Y1147803D02*
X3041461D01*
G01X3050296Y1135303D02*
X3049056Y1135511D01*
X3047971Y1136344D01*
X3047041Y1137595D01*
X3046421Y1139053D01*
X3046111Y1140720D01*
Y1142386D01*
X3046421Y1144053D01*
X3047041Y1145511D01*
X3047971Y1146761D01*
X3049056Y1147595D01*
X3050296Y1147803D01*
X3051536Y1147595D01*
X3052621Y1146761D01*
X3053551Y1145511D01*
X3054171Y1144053D01*
X3054481Y1142386D01*
Y1140720D01*
X3054171Y1139053D01*
X3053551Y1137595D01*
X3052621Y1136344D01*
X3051536Y1135511D01*
X3050296Y1135303D01*
G01X3059596Y1147803D02*
Y1135303D01*
X3065796D01*
G01X3078196D02*
X3071996D01*
Y1147803D01*
X3078196D01*
G01X3075716Y1141761D02*
X3071996D01*
G01X3084396Y1135303D02*
Y1147803D01*
X3088271D01*
X3089511Y1147178D01*
X3090286Y1146345D01*
X3090596Y1144678D01*
X3090286Y1143011D01*
X3089356Y1141970D01*
X3088271Y1141345D01*
X3084396D01*
G01X3088271D02*
X3090596Y1135303D01*
G01X3096021D02*
X3099896Y1147803D01*
X3103771Y1135303D01*
G01X3102376Y1139678D02*
X3097416D01*
G01X3108731Y1135303D02*
Y1147803D01*
X3115861Y1135303D01*
Y1147803D01*
G01X3128106Y1146761D02*
X3127176Y1147386D01*
X3126091Y1147803D01*
X3124851D01*
X3123456Y1147178D01*
X3122371Y1146136D01*
X3121596Y1144886D01*
X3120976Y1142803D01*
X3120821Y1140928D01*
X3121131Y1139053D01*
X3121596Y1137803D01*
X3122526Y1136553D01*
X3123611Y1135720D01*
X3124696Y1135303D01*
X3125781D01*
X3126866Y1135720D01*
X3127796Y1136344D01*
X3128571Y1137178D01*
G01X3140196Y1135303D02*
X3133996D01*
Y1147803D01*
X3140196D01*
G01X3137716Y1141761D02*
X3133996D01*
G01X3161896Y1147803D02*
Y1135303D01*
G01X3158331Y1147803D02*
X3165461D01*
G01X3174296Y1135303D02*
X3173056Y1135511D01*
X3171971Y1136344D01*
X3171041Y1137595D01*
X3170421Y1139053D01*
X3170111Y1140720D01*
Y1142386D01*
X3170421Y1144053D01*
X3171041Y1145511D01*
X3171971Y1146761D01*
X3173056Y1147595D01*
X3174296Y1147803D01*
X3175536Y1147595D01*
X3176621Y1146761D01*
X3177551Y1145511D01*
X3178171Y1144053D01*
X3178481Y1142386D01*
Y1140720D01*
X3178171Y1139053D01*
X3177551Y1137595D01*
X3176621Y1136344D01*
X3175536Y1135511D01*
X3174296Y1135303D01*
G01X3200336Y1141970D02*
X3200956Y1142595D01*
X3201421Y1143636D01*
X3201731Y1145095D01*
X3201421Y1146345D01*
X3200801Y1147178D01*
X3199716Y1147803D01*
X3195531D01*
Y1135303D01*
X3200646D01*
X3201731Y1136136D01*
X3202351Y1137386D01*
X3202661Y1138845D01*
X3202351Y1140303D01*
X3201421Y1141553D01*
X3200336Y1141970D01*
X3195531D01*
G01X3214596Y1135303D02*
X3208396D01*
Y1147803D01*
X3214596D01*
G01X3212116Y1141761D02*
X3208396D01*
G01X3235986Y1135303D02*
X3236296Y1138011D01*
X3236761Y1140303D01*
X3237381Y1142386D01*
X3238156Y1144678D01*
X3239396Y1147803D01*
X3233196D01*
G01X3259391Y1139470D02*
X3263111D01*
G01X3261096Y1142178D02*
Y1136761D01*
G01X3270706Y1134886D02*
X3276286Y1147803D01*
G01X3283881Y1139470D02*
X3287911D01*
G01X3294886Y1137178D02*
X3295816Y1136136D01*
X3296901Y1135511D01*
X3298296Y1135303D01*
X3299691Y1135720D01*
X3300776Y1136553D01*
X3301551Y1138011D01*
X3301706Y1139678D01*
X3301396Y1141345D01*
X3300621Y1142386D01*
X3299536Y1143220D01*
X3298451Y1143428D01*
X3297366Y1143220D01*
X3295971Y1142386D01*
X3296436Y1147803D01*
X3300621D01*
G01X3319066Y1135303D02*
Y1147803D01*
X3323096Y1137386D01*
X3327126Y1147803D01*
Y1135303D01*
G01X3333636Y1147803D02*
X3337356D01*
G01X3335496D02*
Y1135303D01*
G01X3333636D02*
X3337356D01*
G01X3344796Y1147803D02*
Y1135303D01*
X3350996D01*
G01X3357041Y1136969D02*
X3358281Y1135928D01*
X3359676Y1135303D01*
X3360916D01*
X3362156Y1135928D01*
X3363086Y1136969D01*
X3363551Y1138428D01*
X3363241Y1139886D01*
X3362466Y1141136D01*
X3361071Y1141970D01*
X3359211Y1142386D01*
X3358126Y1143220D01*
X3357661Y1144678D01*
X3357971Y1146136D01*
X3358746Y1147178D01*
X3359831Y1147803D01*
X3360916D01*
X3362001Y1147386D01*
X3362931Y1146345D01*
G01X2601881Y1158220D02*
X2605911D01*
G01X2624666Y1154053D02*
Y1166553D01*
X2628696Y1156136D01*
X2632726Y1166553D01*
Y1154053D01*
G01X2638151D02*
Y1166553D01*
X2644041D01*
G01X2641871Y1160511D02*
X2638151D01*
G01X2654426Y1160303D02*
X2657526D01*
Y1156553D01*
X2656596Y1155303D01*
X2655511Y1154470D01*
X2653961Y1154053D01*
X2652411Y1154470D01*
X2651326Y1155303D01*
X2650396Y1156553D01*
X2649776Y1158011D01*
X2649466Y1159678D01*
Y1161136D01*
X2649776Y1162386D01*
X2650396Y1163845D01*
X2651326Y1165095D01*
X2652256Y1165928D01*
X2653496Y1166553D01*
X2654581D01*
X2655821Y1166136D01*
X2656751Y1165303D01*
G01X2661246Y1149886D02*
X2670546D01*
G01X2675041Y1155719D02*
X2676281Y1154678D01*
X2677676Y1154053D01*
X2678916D01*
X2680156Y1154678D01*
X2681086Y1155719D01*
X2681551Y1157178D01*
X2681241Y1158636D01*
X2680466Y1159886D01*
X2679071Y1160720D01*
X2677211Y1161136D01*
X2676126Y1161970D01*
X2675661Y1163428D01*
X2675971Y1164886D01*
X2676746Y1165928D01*
X2677831Y1166553D01*
X2678916D01*
X2680001Y1166136D01*
X2680931Y1165095D01*
G01X2690696Y1166553D02*
Y1154053D01*
G01X2687131Y1166553D02*
X2694261D01*
G01X2699686D02*
Y1157595D01*
X2700306Y1155719D01*
X2701546Y1154470D01*
X2703096Y1154053D01*
X2704646Y1154470D01*
X2705886Y1155719D01*
X2706506Y1157595D01*
Y1166553D01*
G01X2716736Y1160720D02*
X2717356Y1161345D01*
X2717821Y1162386D01*
X2718131Y1163845D01*
X2717821Y1165095D01*
X2717201Y1165928D01*
X2716116Y1166553D01*
X2711931D01*
Y1154053D01*
X2717046D01*
X2718131Y1154886D01*
X2718751Y1156136D01*
X2719061Y1157595D01*
X2718751Y1159053D01*
X2717821Y1160303D01*
X2716736Y1160720D01*
X2711931D01*
G01X2740296Y1153636D02*
X2739986Y1153845D01*
Y1154261D01*
X2740296Y1154470D01*
X2740606Y1154261D01*
Y1153845D01*
X2740296Y1153636D01*
G01Y1159261D02*
X2739986Y1159470D01*
Y1159886D01*
X2740296Y1160095D01*
X2740606Y1159886D01*
Y1159470D01*
X2740296Y1159261D01*
G01X2761066Y1154053D02*
Y1166553D01*
X2765096Y1156136D01*
X2769126Y1166553D01*
Y1154053D01*
G01X2773621D02*
X2777496Y1166553D01*
X2781371Y1154053D01*
G01X2779976Y1158428D02*
X2775016D01*
G01X2786331Y1154053D02*
Y1166553D01*
X2793461Y1154053D01*
Y1166553D01*
G01X2798886D02*
Y1157595D01*
X2799506Y1155719D01*
X2800746Y1154470D01*
X2802296Y1154053D01*
X2803846Y1154470D01*
X2805086Y1155719D01*
X2805706Y1157595D01*
Y1166553D01*
G01X2811751Y1154053D02*
Y1166553D01*
X2817641D01*
G01X2815471Y1160511D02*
X2811751D01*
G01X2823221Y1154053D02*
X2827096Y1166553D01*
X2830971Y1154053D01*
G01X2829576Y1158428D02*
X2824616D01*
G01X2842906Y1165511D02*
X2841976Y1166136D01*
X2840891Y1166553D01*
X2839651D01*
X2838256Y1165928D01*
X2837171Y1164886D01*
X2836396Y1163636D01*
X2835776Y1161553D01*
X2835621Y1159678D01*
X2835931Y1157803D01*
X2836396Y1156553D01*
X2837326Y1155303D01*
X2838411Y1154470D01*
X2839496Y1154053D01*
X2840581D01*
X2841666Y1154470D01*
X2842596Y1155094D01*
X2843371Y1155928D01*
G01X2851896Y1166553D02*
Y1154053D01*
G01X2848331Y1166553D02*
X2855461D01*
G01X2860886D02*
Y1157595D01*
X2861506Y1155719D01*
X2862746Y1154470D01*
X2864296Y1154053D01*
X2865846Y1154470D01*
X2867086Y1155719D01*
X2867706Y1157595D01*
Y1166553D01*
G01X2873596Y1154053D02*
Y1166553D01*
X2877471D01*
X2878711Y1165928D01*
X2879486Y1165095D01*
X2879796Y1163428D01*
X2879486Y1161761D01*
X2878556Y1160720D01*
X2877471Y1160095D01*
X2873596D01*
G01X2877471D02*
X2879796Y1154053D01*
G01X2887236Y1166553D02*
X2890956D01*
G01X2889096D02*
Y1154053D01*
G01X2887236D02*
X2890956D01*
G01X2897931D02*
Y1166553D01*
X2905061Y1154053D01*
Y1166553D01*
G01X2914826Y1160303D02*
X2917926D01*
Y1156553D01*
X2916996Y1155303D01*
X2915911Y1154470D01*
X2914361Y1154053D01*
X2912811Y1154470D01*
X2911726Y1155303D01*
X2910796Y1156553D01*
X2910176Y1158011D01*
X2909866Y1159678D01*
Y1161136D01*
X2910176Y1162386D01*
X2910796Y1163845D01*
X2911726Y1165095D01*
X2912656Y1165928D01*
X2913896Y1166553D01*
X2914981D01*
X2916221Y1166136D01*
X2917151Y1165303D01*
G01X2935441Y1155719D02*
X2936681Y1154678D01*
X2938076Y1154053D01*
X2939316D01*
X2940556Y1154678D01*
X2941486Y1155719D01*
X2941951Y1157178D01*
X2941641Y1158636D01*
X2940866Y1159886D01*
X2939471Y1160720D01*
X2937611Y1161136D01*
X2936526Y1161970D01*
X2936061Y1163428D01*
X2936371Y1164886D01*
X2937146Y1165928D01*
X2938231Y1166553D01*
X2939316D01*
X2940401Y1166136D01*
X2941331Y1165095D01*
G01X2951096Y1166553D02*
Y1154053D01*
G01X2947531Y1166553D02*
X2954661D01*
G01X2960086D02*
Y1157595D01*
X2960706Y1155719D01*
X2961946Y1154470D01*
X2963496Y1154053D01*
X2965046Y1154470D01*
X2966286Y1155719D01*
X2966906Y1157595D01*
Y1166553D01*
G01X2977136Y1160720D02*
X2977756Y1161345D01*
X2978221Y1162386D01*
X2978531Y1163845D01*
X2978221Y1165095D01*
X2977601Y1165928D01*
X2976516Y1166553D01*
X2972331D01*
Y1154053D01*
X2977446D01*
X2978531Y1154886D01*
X2979151Y1156136D01*
X2979461Y1157595D01*
X2979151Y1159053D01*
X2978221Y1160303D01*
X2977136Y1160720D01*
X2972331D01*
G01X2997596Y1166553D02*
Y1154053D01*
X3003796D01*
G01X3016196D02*
X3009996D01*
Y1166553D01*
X3016196D01*
G01X3013716Y1160511D02*
X3009996D01*
G01X3021931Y1154053D02*
Y1166553D01*
X3029061Y1154053D01*
Y1166553D01*
G01X3038826Y1160303D02*
X3041926D01*
Y1156553D01*
X3040996Y1155303D01*
X3039911Y1154470D01*
X3038361Y1154053D01*
X3036811Y1154470D01*
X3035726Y1155303D01*
X3034796Y1156553D01*
X3034176Y1158011D01*
X3033866Y1159678D01*
Y1161136D01*
X3034176Y1162386D01*
X3034796Y1163845D01*
X3035726Y1165095D01*
X3036656Y1165928D01*
X3037896Y1166553D01*
X3038981D01*
X3040221Y1166136D01*
X3041151Y1165303D01*
G01X3050296Y1166553D02*
Y1154053D01*
G01X3046731Y1166553D02*
X3053861D01*
G01X3059441Y1154053D02*
Y1166553D01*
G01X3065951D02*
Y1154053D01*
G01Y1160303D02*
X3059441D01*
G01X2761841Y1174469D02*
X2763081Y1173428D01*
X2764476Y1172803D01*
X2765716D01*
X2766956Y1173428D01*
X2767886Y1174469D01*
X2768351Y1175928D01*
X2768041Y1177386D01*
X2767266Y1178636D01*
X2765871Y1179470D01*
X2764011Y1179886D01*
X2762926Y1180720D01*
X2762461Y1182178D01*
X2762771Y1183636D01*
X2763546Y1184678D01*
X2764631Y1185303D01*
X2765716D01*
X2766801Y1184886D01*
X2767731Y1183845D01*
G01X2774086Y1185303D02*
Y1176345D01*
X2774706Y1174469D01*
X2775946Y1173220D01*
X2777496Y1172803D01*
X2779046Y1173220D01*
X2780286Y1174469D01*
X2780906Y1176345D01*
Y1185303D01*
G01X2786796Y1172803D02*
Y1185303D01*
X2790671D01*
X2791911Y1184678D01*
X2792686Y1183845D01*
X2792996Y1182178D01*
X2792686Y1180511D01*
X2791756Y1179470D01*
X2790671Y1178845D01*
X2786796D01*
G01X2790671D02*
X2792996Y1172803D01*
G01X2799351D02*
Y1185303D01*
X2805241D01*
G01X2803071Y1179261D02*
X2799351D01*
G01X2810821Y1172803D02*
X2814696Y1185303D01*
X2818571Y1172803D01*
G01X2817176Y1177178D02*
X2812216D01*
G01X2830506Y1184261D02*
X2829576Y1184886D01*
X2828491Y1185303D01*
X2827251D01*
X2825856Y1184678D01*
X2824771Y1183636D01*
X2823996Y1182386D01*
X2823376Y1180303D01*
X2823221Y1178428D01*
X2823531Y1176553D01*
X2823996Y1175303D01*
X2824926Y1174053D01*
X2826011Y1173220D01*
X2827096Y1172803D01*
X2828181D01*
X2829266Y1173220D01*
X2830196Y1173844D01*
X2830971Y1174678D01*
G01X2842596Y1172803D02*
X2836396D01*
Y1185303D01*
X2842596D01*
G01X2840116Y1179261D02*
X2836396D01*
G01X2864296Y1172803D02*
X2863056Y1173011D01*
X2861971Y1173844D01*
X2861041Y1175095D01*
X2860421Y1176553D01*
X2860111Y1178220D01*
Y1179886D01*
X2860421Y1181553D01*
X2861041Y1183011D01*
X2861971Y1184261D01*
X2863056Y1185095D01*
X2864296Y1185303D01*
X2865536Y1185095D01*
X2866621Y1184261D01*
X2867551Y1183011D01*
X2868171Y1181553D01*
X2868481Y1179886D01*
Y1178220D01*
X2868171Y1176553D01*
X2867551Y1175095D01*
X2866621Y1173844D01*
X2865536Y1173011D01*
X2864296Y1172803D01*
G01X2873751D02*
Y1185303D01*
X2879641D01*
G01X2877471Y1179261D02*
X2873751D01*
G01X2897466Y1172803D02*
Y1185303D01*
X2901496Y1174886D01*
X2905526Y1185303D01*
Y1172803D01*
G01X2910486Y1185303D02*
Y1176345D01*
X2911106Y1174469D01*
X2912346Y1173220D01*
X2913896Y1172803D01*
X2915446Y1173220D01*
X2916686Y1174469D01*
X2917306Y1176345D01*
Y1185303D01*
G01X2923041Y1174469D02*
X2924281Y1173428D01*
X2925676Y1172803D01*
X2926916D01*
X2928156Y1173428D01*
X2929086Y1174469D01*
X2929551Y1175928D01*
X2929241Y1177386D01*
X2928466Y1178636D01*
X2927071Y1179470D01*
X2925211Y1179886D01*
X2924126Y1180720D01*
X2923661Y1182178D01*
X2923971Y1183636D01*
X2924746Y1184678D01*
X2925831Y1185303D01*
X2926916D01*
X2928001Y1184886D01*
X2928931Y1183845D01*
G01X2938696Y1185303D02*
Y1172803D01*
G01X2935131Y1185303D02*
X2942261D01*
G01X2949081Y1176970D02*
X2953111D01*
G01X2959931Y1172803D02*
Y1185303D01*
X2967061Y1172803D01*
Y1185303D01*
G01X2975896Y1172803D02*
X2974656Y1173011D01*
X2973571Y1173844D01*
X2972641Y1175095D01*
X2972021Y1176553D01*
X2971711Y1178220D01*
Y1179886D01*
X2972021Y1181553D01*
X2972641Y1183011D01*
X2973571Y1184261D01*
X2974656Y1185095D01*
X2975896Y1185303D01*
X2977136Y1185095D01*
X2978221Y1184261D01*
X2979151Y1183011D01*
X2979771Y1181553D01*
X2980081Y1179886D01*
Y1178220D01*
X2979771Y1176553D01*
X2979151Y1175095D01*
X2978221Y1173844D01*
X2977136Y1173011D01*
X2975896Y1172803D01*
G01X2988296Y1185303D02*
Y1172803D01*
G01X2984731Y1185303D02*
X2991861D01*
G01X2998681Y1176970D02*
X3002711D01*
G01X3016506Y1184261D02*
X3015576Y1184886D01*
X3014491Y1185303D01*
X3013251D01*
X3011856Y1184678D01*
X3010771Y1183636D01*
X3009996Y1182386D01*
X3009376Y1180303D01*
X3009221Y1178428D01*
X3009531Y1176553D01*
X3009996Y1175303D01*
X3010926Y1174053D01*
X3012011Y1173220D01*
X3013096Y1172803D01*
X3014181D01*
X3015266Y1173220D01*
X3016196Y1173844D01*
X3016971Y1174678D01*
G01X3022086Y1185303D02*
Y1176345D01*
X3022706Y1174469D01*
X3023946Y1173220D01*
X3025496Y1172803D01*
X3027046Y1173220D01*
X3028286Y1174469D01*
X3028906Y1176345D01*
Y1185303D01*
G01X3037896D02*
Y1172803D01*
G01X3034331Y1185303D02*
X3041461D01*
G01X3048281Y1176970D02*
X3052311D01*
G01X3059596Y1185303D02*
Y1172803D01*
X3065796D01*
G01X3071221D02*
X3075096Y1185303D01*
X3078971Y1172803D01*
G01X3077576Y1177178D02*
X3072616D01*
G01X3087496Y1172803D02*
Y1178428D01*
X3084396Y1185303D01*
G01X3090596D02*
X3087496Y1178428D01*
G01X3102996Y1172803D02*
X3096796D01*
Y1185303D01*
X3102996D01*
G01X3100516Y1179261D02*
X3096796D01*
G01X3109196Y1172803D02*
Y1185303D01*
X3113071D01*
X3114311Y1184678D01*
X3115086Y1183845D01*
X3115396Y1182178D01*
X3115086Y1180511D01*
X3114156Y1179470D01*
X3113071Y1178845D01*
X3109196D01*
G01X3113071D02*
X3115396Y1172803D01*
G01X2601881Y1195720D02*
X2605911D01*
G01X2624666Y1191553D02*
Y1204053D01*
X2628696Y1193636D01*
X2632726Y1204053D01*
Y1191553D01*
G01X2637221D02*
X2641096Y1204053D01*
X2644971Y1191553D01*
G01X2643576Y1195928D02*
X2638616D01*
G01X2650241Y1191553D02*
X2656751Y1204053D01*
G01X2650241D02*
X2656751Y1191553D01*
G01X2661246Y1187386D02*
X2670546D01*
G01X2674886Y1191553D02*
Y1204053D01*
X2677986D01*
X2679226Y1203428D01*
X2680156Y1202595D01*
X2680931Y1201345D01*
X2681551Y1199886D01*
X2681706Y1197803D01*
X2681551Y1195720D01*
X2680931Y1194261D01*
X2680156Y1193011D01*
X2679226Y1192178D01*
X2677986Y1191553D01*
X2674886D01*
G01X2693796D02*
X2687596D01*
Y1204053D01*
X2693796D01*
G01X2691316Y1198011D02*
X2687596D01*
G01X2699996Y1191553D02*
Y1204053D01*
X2703716D01*
X2704956Y1203428D01*
X2705886Y1201970D01*
X2706196Y1200303D01*
X2705886Y1198636D01*
X2705111Y1197386D01*
X2703716Y1196761D01*
X2699996D01*
G01X2715496Y1204053D02*
Y1191553D01*
G01X2711931Y1204053D02*
X2719061D01*
G01X2724641Y1191553D02*
Y1204053D01*
G01X2731151D02*
Y1191553D01*
G01Y1197803D02*
X2724641D01*
G01X2740296Y1191136D02*
X2739986Y1191345D01*
Y1191761D01*
X2740296Y1191970D01*
X2740606Y1191761D01*
Y1191345D01*
X2740296Y1191136D01*
G01Y1196761D02*
X2739986Y1196970D01*
Y1197386D01*
X2740296Y1197595D01*
X2740606Y1197386D01*
Y1196970D01*
X2740296Y1196761D01*
G01X2761686Y1191553D02*
Y1204053D01*
X2764786D01*
X2766026Y1203428D01*
X2766956Y1202595D01*
X2767731Y1201345D01*
X2768351Y1199886D01*
X2768506Y1197803D01*
X2768351Y1195720D01*
X2767731Y1194261D01*
X2766956Y1193011D01*
X2766026Y1192178D01*
X2764786Y1191553D01*
X2761686D01*
G01X2780596D02*
X2774396D01*
Y1204053D01*
X2780596D01*
G01X2778116Y1198011D02*
X2774396D01*
G01X2786796Y1191553D02*
Y1204053D01*
X2790516D01*
X2791756Y1203428D01*
X2792686Y1201970D01*
X2792996Y1200303D01*
X2792686Y1198636D01*
X2791911Y1197386D01*
X2790516Y1196761D01*
X2786796D01*
G01X2802296Y1204053D02*
Y1191553D01*
G01X2798731Y1204053D02*
X2805861D01*
G01X2811441Y1191553D02*
Y1204053D01*
G01X2817951D02*
Y1191553D01*
G01Y1197803D02*
X2811441D01*
G01X2836551Y1191553D02*
Y1204053D01*
X2842441D01*
G01X2840271Y1198011D02*
X2836551D01*
G01X2848796Y1191553D02*
Y1204053D01*
X2852671D01*
X2853911Y1203428D01*
X2854686Y1202595D01*
X2854996Y1200928D01*
X2854686Y1199261D01*
X2853756Y1198220D01*
X2852671Y1197595D01*
X2848796D01*
G01X2852671D02*
X2854996Y1191553D01*
G01X2864296D02*
X2863056Y1191761D01*
X2861971Y1192594D01*
X2861041Y1193845D01*
X2860421Y1195303D01*
X2860111Y1196970D01*
Y1198636D01*
X2860421Y1200303D01*
X2861041Y1201761D01*
X2861971Y1203011D01*
X2863056Y1203845D01*
X2864296Y1204053D01*
X2865536Y1203845D01*
X2866621Y1203011D01*
X2867551Y1201761D01*
X2868171Y1200303D01*
X2868481Y1198636D01*
Y1196970D01*
X2868171Y1195303D01*
X2867551Y1193845D01*
X2866621Y1192594D01*
X2865536Y1191761D01*
X2864296Y1191553D01*
G01X2872666D02*
Y1204053D01*
X2876696Y1193636D01*
X2880726Y1204053D01*
Y1191553D01*
G01X2898241Y1193219D02*
X2899481Y1192178D01*
X2900876Y1191553D01*
X2902116D01*
X2903356Y1192178D01*
X2904286Y1193219D01*
X2904751Y1194678D01*
X2904441Y1196136D01*
X2903666Y1197386D01*
X2902271Y1198220D01*
X2900411Y1198636D01*
X2899326Y1199470D01*
X2898861Y1200928D01*
X2899171Y1202386D01*
X2899946Y1203428D01*
X2901031Y1204053D01*
X2902116D01*
X2903201Y1203636D01*
X2904131Y1202595D01*
G01X2913896Y1204053D02*
Y1191553D01*
G01X2910331Y1204053D02*
X2917461D01*
G01X2922421Y1191553D02*
X2926296Y1204053D01*
X2930171Y1191553D01*
G01X2928776Y1195928D02*
X2923816D01*
G01X2935596Y1191553D02*
Y1204053D01*
X2939471D01*
X2940711Y1203428D01*
X2941486Y1202595D01*
X2941796Y1200928D01*
X2941486Y1199261D01*
X2940556Y1198220D01*
X2939471Y1197595D01*
X2935596D01*
G01X2939471D02*
X2941796Y1191553D01*
G01X2951096Y1204053D02*
Y1191553D01*
G01X2947531Y1204053D02*
X2954661D01*
G01X2972796D02*
Y1191553D01*
X2978996D01*
G01X2984421D02*
X2988296Y1204053D01*
X2992171Y1191553D01*
G01X2990776Y1195928D02*
X2985816D01*
G01X3000696Y1191553D02*
Y1197178D01*
X2997596Y1204053D01*
G01X3003796D02*
X3000696Y1197178D01*
G01X3016196Y1191553D02*
X3009996D01*
Y1204053D01*
X3016196D01*
G01X3013716Y1198011D02*
X3009996D01*
G01X3022396Y1191553D02*
Y1204053D01*
X3026271D01*
X3027511Y1203428D01*
X3028286Y1202595D01*
X3028596Y1200928D01*
X3028286Y1199261D01*
X3027356Y1198220D01*
X3026271Y1197595D01*
X3022396D01*
G01X3026271D02*
X3028596Y1191553D01*
G01X3050296Y1204053D02*
Y1191553D01*
G01X3046731Y1204053D02*
X3053861D01*
G01X3062696Y1191553D02*
X3061456Y1191761D01*
X3060371Y1192594D01*
X3059441Y1193845D01*
X3058821Y1195303D01*
X3058511Y1196970D01*
Y1198636D01*
X3058821Y1200303D01*
X3059441Y1201761D01*
X3060371Y1203011D01*
X3061456Y1203845D01*
X3062696Y1204053D01*
X3063936Y1203845D01*
X3065021Y1203011D01*
X3065951Y1201761D01*
X3066571Y1200303D01*
X3066881Y1198636D01*
Y1196970D01*
X3066571Y1195303D01*
X3065951Y1193845D01*
X3065021Y1192594D01*
X3063936Y1191761D01*
X3062696Y1191553D01*
G01X3087496Y1204053D02*
Y1191553D01*
G01X3083931Y1204053D02*
X3091061D01*
G01X3096641Y1191553D02*
Y1204053D01*
G01X3103151D02*
Y1191553D01*
G01Y1197803D02*
X3096641D01*
G01X3115396Y1191553D02*
X3109196D01*
Y1204053D01*
X3115396D01*
G01X3112916Y1198011D02*
X3109196D01*
G01X2601881Y1214470D02*
X2605911D01*
G01X2624666Y1210303D02*
Y1222803D01*
X2628696Y1212386D01*
X2632726Y1222803D01*
Y1210303D01*
G01X2637531D02*
Y1222803D01*
X2644661Y1210303D01*
Y1222803D01*
G01X2656906Y1221761D02*
X2655976Y1222386D01*
X2654891Y1222803D01*
X2653651D01*
X2652256Y1222178D01*
X2651171Y1221136D01*
X2650396Y1219886D01*
X2649776Y1217803D01*
X2649621Y1215928D01*
X2649931Y1214053D01*
X2650396Y1212803D01*
X2651326Y1211553D01*
X2652411Y1210720D01*
X2653496Y1210303D01*
X2654581D01*
X2655666Y1210720D01*
X2656596Y1211344D01*
X2657371Y1212178D01*
G01X2661246Y1206136D02*
X2670546D01*
G01X2675196Y1222803D02*
Y1210303D01*
X2681396D01*
G01X2686821D02*
X2690696Y1222803D01*
X2694571Y1210303D01*
G01X2693176Y1214678D02*
X2688216D01*
G01X2703096Y1210303D02*
Y1215928D01*
X2699996Y1222803D01*
G01X2706196D02*
X2703096Y1215928D01*
G01X2718596Y1210303D02*
X2712396D01*
Y1222803D01*
X2718596D01*
G01X2716116Y1216761D02*
X2712396D01*
G01X2724796Y1210303D02*
Y1222803D01*
X2728671D01*
X2729911Y1222178D01*
X2730686Y1221345D01*
X2730996Y1219678D01*
X2730686Y1218011D01*
X2729756Y1216970D01*
X2728671Y1216345D01*
X2724796D01*
G01X2728671D02*
X2730996Y1210303D01*
G01X2740296Y1209886D02*
X2739986Y1210095D01*
Y1210511D01*
X2740296Y1210720D01*
X2740606Y1210511D01*
Y1210095D01*
X2740296Y1209886D01*
G01Y1215511D02*
X2739986Y1215720D01*
Y1216136D01*
X2740296Y1216345D01*
X2740606Y1216136D01*
Y1215720D01*
X2740296Y1215511D01*
G01X2761066Y1210303D02*
Y1222803D01*
X2765096Y1212386D01*
X2769126Y1222803D01*
Y1210303D01*
G01X2774086Y1222803D02*
Y1213845D01*
X2774706Y1211969D01*
X2775946Y1210720D01*
X2777496Y1210303D01*
X2779046Y1210720D01*
X2780286Y1211969D01*
X2780906Y1213845D01*
Y1222803D01*
G01X2786641Y1211969D02*
X2787881Y1210928D01*
X2789276Y1210303D01*
X2790516D01*
X2791756Y1210928D01*
X2792686Y1211969D01*
X2793151Y1213428D01*
X2792841Y1214886D01*
X2792066Y1216136D01*
X2790671Y1216970D01*
X2788811Y1217386D01*
X2787726Y1218220D01*
X2787261Y1219678D01*
X2787571Y1221136D01*
X2788346Y1222178D01*
X2789431Y1222803D01*
X2790516D01*
X2791601Y1222386D01*
X2792531Y1221345D01*
G01X2802296Y1222803D02*
Y1210303D01*
G01X2798731Y1222803D02*
X2805861D01*
G01X2812681Y1214470D02*
X2816711D01*
G01X2823531Y1210303D02*
Y1222803D01*
X2830661Y1210303D01*
Y1222803D01*
G01X2839496Y1210303D02*
X2838256Y1210511D01*
X2837171Y1211344D01*
X2836241Y1212595D01*
X2835621Y1214053D01*
X2835311Y1215720D01*
Y1217386D01*
X2835621Y1219053D01*
X2836241Y1220511D01*
X2837171Y1221761D01*
X2838256Y1222595D01*
X2839496Y1222803D01*
X2840736Y1222595D01*
X2841821Y1221761D01*
X2842751Y1220511D01*
X2843371Y1219053D01*
X2843681Y1217386D01*
Y1215720D01*
X2843371Y1214053D01*
X2842751Y1212595D01*
X2841821Y1211344D01*
X2840736Y1210511D01*
X2839496Y1210303D01*
G01X2851896Y1222803D02*
Y1210303D01*
G01X2848331Y1222803D02*
X2855461D01*
G01X2862281Y1214470D02*
X2866311D01*
G01X2880106Y1221761D02*
X2879176Y1222386D01*
X2878091Y1222803D01*
X2876851D01*
X2875456Y1222178D01*
X2874371Y1221136D01*
X2873596Y1219886D01*
X2872976Y1217803D01*
X2872821Y1215928D01*
X2873131Y1214053D01*
X2873596Y1212803D01*
X2874526Y1211553D01*
X2875611Y1210720D01*
X2876696Y1210303D01*
X2877781D01*
X2878866Y1210720D01*
X2879796Y1211344D01*
X2880571Y1212178D01*
G01X2885686Y1222803D02*
Y1213845D01*
X2886306Y1211969D01*
X2887546Y1210720D01*
X2889096Y1210303D01*
X2890646Y1210720D01*
X2891886Y1211969D01*
X2892506Y1213845D01*
Y1222803D01*
G01X2901496D02*
Y1210303D01*
G01X2897931Y1222803D02*
X2905061D01*
G01X2911881Y1214470D02*
X2915911D01*
G01X2923196Y1222803D02*
Y1210303D01*
X2929396D01*
G01X2934821D02*
X2938696Y1222803D01*
X2942571Y1210303D01*
G01X2941176Y1214678D02*
X2936216D01*
G01X2951096Y1210303D02*
Y1215928D01*
X2947996Y1222803D01*
G01X2954196D02*
X2951096Y1215928D01*
G01X2966596Y1210303D02*
X2960396D01*
Y1222803D01*
X2966596D01*
G01X2964116Y1216761D02*
X2960396D01*
G01X2972796Y1210303D02*
Y1222803D01*
X2976671D01*
X2977911Y1222178D01*
X2978686Y1221345D01*
X2978996Y1219678D01*
X2978686Y1218011D01*
X2977756Y1216970D01*
X2976671Y1216345D01*
X2972796D01*
G01X2976671D02*
X2978996Y1210303D01*
G01X2600331Y1229053D02*
Y1241553D01*
X2607461Y1229053D01*
Y1241553D01*
G01X2616296Y1229053D02*
X2615056Y1229261D01*
X2613971Y1230094D01*
X2613041Y1231345D01*
X2612421Y1232803D01*
X2612111Y1234470D01*
Y1236136D01*
X2612421Y1237803D01*
X2613041Y1239261D01*
X2613971Y1240511D01*
X2615056Y1241345D01*
X2616296Y1241553D01*
X2617536Y1241345D01*
X2618621Y1240511D01*
X2619551Y1239261D01*
X2620171Y1237803D01*
X2620481Y1236136D01*
Y1234470D01*
X2620171Y1232803D01*
X2619551Y1231345D01*
X2618621Y1230094D01*
X2617536Y1229261D01*
X2616296Y1229053D01*
G01X2628696Y1241553D02*
Y1229053D01*
G01X2625131Y1241553D02*
X2632261D01*
G01X2644196Y1229053D02*
X2637996D01*
Y1241553D01*
X2644196D01*
G01X2641716Y1235511D02*
X2637996D01*
G01X2650241Y1230719D02*
X2651481Y1229678D01*
X2652876Y1229053D01*
X2654116D01*
X2655356Y1229678D01*
X2656286Y1230719D01*
X2656751Y1232178D01*
X2656441Y1233636D01*
X2655666Y1234886D01*
X2654271Y1235720D01*
X2652411Y1236136D01*
X2651326Y1236970D01*
X2650861Y1238428D01*
X2651171Y1239886D01*
X2651946Y1240928D01*
X2653031Y1241553D01*
X2654116D01*
X2655201Y1241136D01*
X2656131Y1240095D01*
G01X2665896Y1228636D02*
X2665586Y1228845D01*
Y1229261D01*
X2665896Y1229470D01*
X2666206Y1229261D01*
Y1228845D01*
X2665896Y1228636D01*
G01Y1234261D02*
X2665586Y1234470D01*
Y1234886D01*
X2665896Y1235095D01*
X2666206Y1234886D01*
Y1234470D01*
X2665896Y1234261D01*
G01X2766336Y1491988D02*
X2766956Y1492613D01*
X2767421Y1493654D01*
X2767731Y1495113D01*
X2767421Y1496363D01*
X2766801Y1497196D01*
X2765716Y1497821D01*
X2761531D01*
Y1485321D01*
X2766646D01*
X2767731Y1486154D01*
X2768351Y1487404D01*
X2768661Y1488863D01*
X2768351Y1490321D01*
X2767421Y1491571D01*
X2766336Y1491988D01*
X2761531D01*
G01X2773621Y1485321D02*
X2777496Y1497821D01*
X2781371Y1485321D01*
G01X2779976Y1489696D02*
X2775016D01*
G01X2793306Y1496779D02*
X2792376Y1497404D01*
X2791291Y1497821D01*
X2790051D01*
X2788656Y1497196D01*
X2787571Y1496154D01*
X2786796Y1494904D01*
X2786176Y1492821D01*
X2786021Y1490946D01*
X2786331Y1489071D01*
X2786796Y1487821D01*
X2787726Y1486571D01*
X2788811Y1485738D01*
X2789896Y1485321D01*
X2790981D01*
X2792066Y1485738D01*
X2792996Y1486362D01*
X2793771Y1487196D01*
G01X2798886Y1485321D02*
Y1497821D01*
G01X2804776D02*
X2798886Y1490112D01*
G01X2805706Y1485321D02*
X2801521Y1493654D01*
G01X2811286Y1485321D02*
Y1497821D01*
X2814386D01*
X2815626Y1497196D01*
X2816556Y1496363D01*
X2817331Y1495113D01*
X2817951Y1493654D01*
X2818106Y1491571D01*
X2817951Y1489488D01*
X2817331Y1488029D01*
X2816556Y1486779D01*
X2815626Y1485946D01*
X2814386Y1485321D01*
X2811286D01*
G01X2823996D02*
Y1497821D01*
X2827871D01*
X2829111Y1497196D01*
X2829886Y1496363D01*
X2830196Y1494696D01*
X2829886Y1493029D01*
X2828956Y1491988D01*
X2827871Y1491363D01*
X2823996D01*
G01X2827871D02*
X2830196Y1485321D01*
G01X2837636Y1497821D02*
X2841356D01*
G01X2839496D02*
Y1485321D01*
G01X2837636D02*
X2841356D01*
G01X2848796Y1497821D02*
Y1485321D01*
X2854996D01*
G01X2861196Y1497821D02*
Y1485321D01*
X2867396D01*
G01X2885841Y1486987D02*
X2887081Y1485946D01*
X2888476Y1485321D01*
X2889716D01*
X2890956Y1485946D01*
X2891886Y1486987D01*
X2892351Y1488446D01*
X2892041Y1489904D01*
X2891266Y1491154D01*
X2889871Y1491988D01*
X2888011Y1492404D01*
X2886926Y1493238D01*
X2886461Y1494696D01*
X2886771Y1496154D01*
X2887546Y1497196D01*
X2888631Y1497821D01*
X2889716D01*
X2890801Y1497404D01*
X2891731Y1496363D01*
G01X2901496Y1497821D02*
Y1485321D01*
G01X2897931Y1497821D02*
X2905061D01*
G01X2910486D02*
Y1488863D01*
X2911106Y1486987D01*
X2912346Y1485738D01*
X2913896Y1485321D01*
X2915446Y1485738D01*
X2916686Y1486987D01*
X2917306Y1488863D01*
Y1497821D01*
G01X2927536Y1491988D02*
X2928156Y1492613D01*
X2928621Y1493654D01*
X2928931Y1495113D01*
X2928621Y1496363D01*
X2928001Y1497196D01*
X2926916Y1497821D01*
X2922731D01*
Y1485321D01*
X2927846D01*
X2928931Y1486154D01*
X2929551Y1487404D01*
X2929861Y1488863D01*
X2929551Y1490321D01*
X2928621Y1491571D01*
X2927536Y1491988D01*
X2922731D01*
G01X2947996Y1497821D02*
Y1485321D01*
X2954196D01*
G01X2966596D02*
X2960396D01*
Y1497821D01*
X2966596D01*
G01X2964116Y1491779D02*
X2960396D01*
G01X2972331Y1485321D02*
Y1497821D01*
X2979461Y1485321D01*
Y1497821D01*
G01X2989226Y1491571D02*
X2992326D01*
Y1487821D01*
X2991396Y1486571D01*
X2990311Y1485738D01*
X2988761Y1485321D01*
X2987211Y1485738D01*
X2986126Y1486571D01*
X2985196Y1487821D01*
X2984576Y1489279D01*
X2984266Y1490946D01*
Y1492404D01*
X2984576Y1493654D01*
X2985196Y1495113D01*
X2986126Y1496363D01*
X2987056Y1497196D01*
X2988296Y1497821D01*
X2989381D01*
X2990621Y1497404D01*
X2991551Y1496571D01*
G01X3000696Y1497821D02*
Y1485321D01*
G01X2997131Y1497821D02*
X3004261D01*
G01X3009841Y1485321D02*
Y1497821D01*
G01X3016351D02*
Y1485321D01*
G01Y1491571D02*
X3009841D01*
G01X3037896Y1497821D02*
Y1485321D01*
G01X3034331Y1497821D02*
X3041461D01*
G01X3050296Y1485321D02*
X3049056Y1485529D01*
X3047971Y1486362D01*
X3047041Y1487613D01*
X3046421Y1489071D01*
X3046111Y1490738D01*
Y1492404D01*
X3046421Y1494071D01*
X3047041Y1495529D01*
X3047971Y1496779D01*
X3049056Y1497613D01*
X3050296Y1497821D01*
X3051536Y1497613D01*
X3052621Y1496779D01*
X3053551Y1495529D01*
X3054171Y1494071D01*
X3054481Y1492404D01*
Y1490738D01*
X3054171Y1489071D01*
X3053551Y1487613D01*
X3052621Y1486362D01*
X3051536Y1485529D01*
X3050296Y1485321D01*
G01X3059596Y1497821D02*
Y1485321D01*
X3065796D01*
G01X3078196D02*
X3071996D01*
Y1497821D01*
X3078196D01*
G01X3075716Y1491779D02*
X3071996D01*
G01X3084396Y1485321D02*
Y1497821D01*
X3088271D01*
X3089511Y1497196D01*
X3090286Y1496363D01*
X3090596Y1494696D01*
X3090286Y1493029D01*
X3089356Y1491988D01*
X3088271Y1491363D01*
X3084396D01*
G01X3088271D02*
X3090596Y1485321D01*
G01X3096021D02*
X3099896Y1497821D01*
X3103771Y1485321D01*
G01X3102376Y1489696D02*
X3097416D01*
G01X3108731Y1485321D02*
Y1497821D01*
X3115861Y1485321D01*
Y1497821D01*
G01X3128106Y1496779D02*
X3127176Y1497404D01*
X3126091Y1497821D01*
X3124851D01*
X3123456Y1497196D01*
X3122371Y1496154D01*
X3121596Y1494904D01*
X3120976Y1492821D01*
X3120821Y1490946D01*
X3121131Y1489071D01*
X3121596Y1487821D01*
X3122526Y1486571D01*
X3123611Y1485738D01*
X3124696Y1485321D01*
X3125781D01*
X3126866Y1485738D01*
X3127796Y1486362D01*
X3128571Y1487196D01*
G01X3140196Y1485321D02*
X3133996D01*
Y1497821D01*
X3140196D01*
G01X3137716Y1491779D02*
X3133996D01*
G01X3161896Y1497821D02*
Y1485321D01*
G01X3158331Y1497821D02*
X3165461D01*
G01X3174296Y1485321D02*
X3173056Y1485529D01*
X3171971Y1486362D01*
X3171041Y1487613D01*
X3170421Y1489071D01*
X3170111Y1490738D01*
Y1492404D01*
X3170421Y1494071D01*
X3171041Y1495529D01*
X3171971Y1496779D01*
X3173056Y1497613D01*
X3174296Y1497821D01*
X3175536Y1497613D01*
X3176621Y1496779D01*
X3177551Y1495529D01*
X3178171Y1494071D01*
X3178481Y1492404D01*
Y1490738D01*
X3178171Y1489071D01*
X3177551Y1487613D01*
X3176621Y1486362D01*
X3175536Y1485529D01*
X3174296Y1485321D01*
G01X3200336Y1491988D02*
X3200956Y1492613D01*
X3201421Y1493654D01*
X3201731Y1495113D01*
X3201421Y1496363D01*
X3200801Y1497196D01*
X3199716Y1497821D01*
X3195531D01*
Y1485321D01*
X3200646D01*
X3201731Y1486154D01*
X3202351Y1487404D01*
X3202661Y1488863D01*
X3202351Y1490321D01*
X3201421Y1491571D01*
X3200336Y1491988D01*
X3195531D01*
G01X3214596Y1485321D02*
X3208396D01*
Y1497821D01*
X3214596D01*
G01X3212116Y1491779D02*
X3208396D01*
G01X3235986Y1485321D02*
X3236296Y1488029D01*
X3236761Y1490321D01*
X3237381Y1492404D01*
X3238156Y1494696D01*
X3239396Y1497821D01*
X3233196D01*
G01X3259391Y1489488D02*
X3263111D01*
G01X3261096Y1492196D02*
Y1486779D01*
G01X3270706Y1484904D02*
X3276286Y1497821D01*
G01X3283881Y1489488D02*
X3287911D01*
G01X3294886Y1487196D02*
X3295816Y1486154D01*
X3296901Y1485529D01*
X3298296Y1485321D01*
X3299691Y1485738D01*
X3300776Y1486571D01*
X3301551Y1488029D01*
X3301706Y1489696D01*
X3301396Y1491363D01*
X3300621Y1492404D01*
X3299536Y1493238D01*
X3298451Y1493446D01*
X3297366Y1493238D01*
X3295971Y1492404D01*
X3296436Y1497821D01*
X3300621D01*
G01X3319066Y1485321D02*
Y1497821D01*
X3323096Y1487404D01*
X3327126Y1497821D01*
Y1485321D01*
G01X3333636Y1497821D02*
X3337356D01*
G01X3335496D02*
Y1485321D01*
G01X3333636D02*
X3337356D01*
G01X3344796Y1497821D02*
Y1485321D01*
X3350996D01*
G01X3357041Y1486987D02*
X3358281Y1485946D01*
X3359676Y1485321D01*
X3360916D01*
X3362156Y1485946D01*
X3363086Y1486987D01*
X3363551Y1488446D01*
X3363241Y1489904D01*
X3362466Y1491154D01*
X3361071Y1491988D01*
X3359211Y1492404D01*
X3358126Y1493238D01*
X3357661Y1494696D01*
X3357971Y1496154D01*
X3358746Y1497196D01*
X3359831Y1497821D01*
X3360916D01*
X3362001Y1497404D01*
X3362931Y1496363D01*
G01X2601881Y1508238D02*
X2605911D01*
G01X2624666Y1504071D02*
Y1516571D01*
X2628696Y1506154D01*
X2632726Y1516571D01*
Y1504071D01*
G01X2638151D02*
Y1516571D01*
X2644041D01*
G01X2641871Y1510529D02*
X2638151D01*
G01X2654426Y1510321D02*
X2657526D01*
Y1506571D01*
X2656596Y1505321D01*
X2655511Y1504488D01*
X2653961Y1504071D01*
X2652411Y1504488D01*
X2651326Y1505321D01*
X2650396Y1506571D01*
X2649776Y1508029D01*
X2649466Y1509696D01*
Y1511154D01*
X2649776Y1512404D01*
X2650396Y1513863D01*
X2651326Y1515113D01*
X2652256Y1515946D01*
X2653496Y1516571D01*
X2654581D01*
X2655821Y1516154D01*
X2656751Y1515321D01*
G01X2661246Y1499904D02*
X2670546D01*
G01X2675041Y1505737D02*
X2676281Y1504696D01*
X2677676Y1504071D01*
X2678916D01*
X2680156Y1504696D01*
X2681086Y1505737D01*
X2681551Y1507196D01*
X2681241Y1508654D01*
X2680466Y1509904D01*
X2679071Y1510738D01*
X2677211Y1511154D01*
X2676126Y1511988D01*
X2675661Y1513446D01*
X2675971Y1514904D01*
X2676746Y1515946D01*
X2677831Y1516571D01*
X2678916D01*
X2680001Y1516154D01*
X2680931Y1515113D01*
G01X2690696Y1516571D02*
Y1504071D01*
G01X2687131Y1516571D02*
X2694261D01*
G01X2699686D02*
Y1507613D01*
X2700306Y1505737D01*
X2701546Y1504488D01*
X2703096Y1504071D01*
X2704646Y1504488D01*
X2705886Y1505737D01*
X2706506Y1507613D01*
Y1516571D01*
G01X2716736Y1510738D02*
X2717356Y1511363D01*
X2717821Y1512404D01*
X2718131Y1513863D01*
X2717821Y1515113D01*
X2717201Y1515946D01*
X2716116Y1516571D01*
X2711931D01*
Y1504071D01*
X2717046D01*
X2718131Y1504904D01*
X2718751Y1506154D01*
X2719061Y1507613D01*
X2718751Y1509071D01*
X2717821Y1510321D01*
X2716736Y1510738D01*
X2711931D01*
G01X2740296Y1503654D02*
X2739986Y1503863D01*
Y1504279D01*
X2740296Y1504488D01*
X2740606Y1504279D01*
Y1503863D01*
X2740296Y1503654D01*
G01Y1509279D02*
X2739986Y1509488D01*
Y1509904D01*
X2740296Y1510113D01*
X2740606Y1509904D01*
Y1509488D01*
X2740296Y1509279D01*
G01X2761066Y1504071D02*
Y1516571D01*
X2765096Y1506154D01*
X2769126Y1516571D01*
Y1504071D01*
G01X2773621D02*
X2777496Y1516571D01*
X2781371Y1504071D01*
G01X2779976Y1508446D02*
X2775016D01*
G01X2786331Y1504071D02*
Y1516571D01*
X2793461Y1504071D01*
Y1516571D01*
G01X2798886D02*
Y1507613D01*
X2799506Y1505737D01*
X2800746Y1504488D01*
X2802296Y1504071D01*
X2803846Y1504488D01*
X2805086Y1505737D01*
X2805706Y1507613D01*
Y1516571D01*
G01X2811751Y1504071D02*
Y1516571D01*
X2817641D01*
G01X2815471Y1510529D02*
X2811751D01*
G01X2823221Y1504071D02*
X2827096Y1516571D01*
X2830971Y1504071D01*
G01X2829576Y1508446D02*
X2824616D01*
G01X2842906Y1515529D02*
X2841976Y1516154D01*
X2840891Y1516571D01*
X2839651D01*
X2838256Y1515946D01*
X2837171Y1514904D01*
X2836396Y1513654D01*
X2835776Y1511571D01*
X2835621Y1509696D01*
X2835931Y1507821D01*
X2836396Y1506571D01*
X2837326Y1505321D01*
X2838411Y1504488D01*
X2839496Y1504071D01*
X2840581D01*
X2841666Y1504488D01*
X2842596Y1505112D01*
X2843371Y1505946D01*
G01X2851896Y1516571D02*
Y1504071D01*
G01X2848331Y1516571D02*
X2855461D01*
G01X2860886D02*
Y1507613D01*
X2861506Y1505737D01*
X2862746Y1504488D01*
X2864296Y1504071D01*
X2865846Y1504488D01*
X2867086Y1505737D01*
X2867706Y1507613D01*
Y1516571D01*
G01X2873596Y1504071D02*
Y1516571D01*
X2877471D01*
X2878711Y1515946D01*
X2879486Y1515113D01*
X2879796Y1513446D01*
X2879486Y1511779D01*
X2878556Y1510738D01*
X2877471Y1510113D01*
X2873596D01*
G01X2877471D02*
X2879796Y1504071D01*
G01X2887236Y1516571D02*
X2890956D01*
G01X2889096D02*
Y1504071D01*
G01X2887236D02*
X2890956D01*
G01X2897931D02*
Y1516571D01*
X2905061Y1504071D01*
Y1516571D01*
G01X2914826Y1510321D02*
X2917926D01*
Y1506571D01*
X2916996Y1505321D01*
X2915911Y1504488D01*
X2914361Y1504071D01*
X2912811Y1504488D01*
X2911726Y1505321D01*
X2910796Y1506571D01*
X2910176Y1508029D01*
X2909866Y1509696D01*
Y1511154D01*
X2910176Y1512404D01*
X2910796Y1513863D01*
X2911726Y1515113D01*
X2912656Y1515946D01*
X2913896Y1516571D01*
X2914981D01*
X2916221Y1516154D01*
X2917151Y1515321D01*
G01X2935441Y1505737D02*
X2936681Y1504696D01*
X2938076Y1504071D01*
X2939316D01*
X2940556Y1504696D01*
X2941486Y1505737D01*
X2941951Y1507196D01*
X2941641Y1508654D01*
X2940866Y1509904D01*
X2939471Y1510738D01*
X2937611Y1511154D01*
X2936526Y1511988D01*
X2936061Y1513446D01*
X2936371Y1514904D01*
X2937146Y1515946D01*
X2938231Y1516571D01*
X2939316D01*
X2940401Y1516154D01*
X2941331Y1515113D01*
G01X2951096Y1516571D02*
Y1504071D01*
G01X2947531Y1516571D02*
X2954661D01*
G01X2960086D02*
Y1507613D01*
X2960706Y1505737D01*
X2961946Y1504488D01*
X2963496Y1504071D01*
X2965046Y1504488D01*
X2966286Y1505737D01*
X2966906Y1507613D01*
Y1516571D01*
G01X2977136Y1510738D02*
X2977756Y1511363D01*
X2978221Y1512404D01*
X2978531Y1513863D01*
X2978221Y1515113D01*
X2977601Y1515946D01*
X2976516Y1516571D01*
X2972331D01*
Y1504071D01*
X2977446D01*
X2978531Y1504904D01*
X2979151Y1506154D01*
X2979461Y1507613D01*
X2979151Y1509071D01*
X2978221Y1510321D01*
X2977136Y1510738D01*
X2972331D01*
G01X2997596Y1516571D02*
Y1504071D01*
X3003796D01*
G01X3016196D02*
X3009996D01*
Y1516571D01*
X3016196D01*
G01X3013716Y1510529D02*
X3009996D01*
G01X3021931Y1504071D02*
Y1516571D01*
X3029061Y1504071D01*
Y1516571D01*
G01X3038826Y1510321D02*
X3041926D01*
Y1506571D01*
X3040996Y1505321D01*
X3039911Y1504488D01*
X3038361Y1504071D01*
X3036811Y1504488D01*
X3035726Y1505321D01*
X3034796Y1506571D01*
X3034176Y1508029D01*
X3033866Y1509696D01*
Y1511154D01*
X3034176Y1512404D01*
X3034796Y1513863D01*
X3035726Y1515113D01*
X3036656Y1515946D01*
X3037896Y1516571D01*
X3038981D01*
X3040221Y1516154D01*
X3041151Y1515321D01*
G01X3050296Y1516571D02*
Y1504071D01*
G01X3046731Y1516571D02*
X3053861D01*
G01X3059441Y1504071D02*
Y1516571D01*
G01X3065951D02*
Y1504071D01*
G01Y1510321D02*
X3059441D01*
G01X2761841Y1524487D02*
X2763081Y1523446D01*
X2764476Y1522821D01*
X2765716D01*
X2766956Y1523446D01*
X2767886Y1524487D01*
X2768351Y1525946D01*
X2768041Y1527404D01*
X2767266Y1528654D01*
X2765871Y1529488D01*
X2764011Y1529904D01*
X2762926Y1530738D01*
X2762461Y1532196D01*
X2762771Y1533654D01*
X2763546Y1534696D01*
X2764631Y1535321D01*
X2765716D01*
X2766801Y1534904D01*
X2767731Y1533863D01*
G01X2774086Y1535321D02*
Y1526363D01*
X2774706Y1524487D01*
X2775946Y1523238D01*
X2777496Y1522821D01*
X2779046Y1523238D01*
X2780286Y1524487D01*
X2780906Y1526363D01*
Y1535321D01*
G01X2786796Y1522821D02*
Y1535321D01*
X2790671D01*
X2791911Y1534696D01*
X2792686Y1533863D01*
X2792996Y1532196D01*
X2792686Y1530529D01*
X2791756Y1529488D01*
X2790671Y1528863D01*
X2786796D01*
G01X2790671D02*
X2792996Y1522821D01*
G01X2799351D02*
Y1535321D01*
X2805241D01*
G01X2803071Y1529279D02*
X2799351D01*
G01X2810821Y1522821D02*
X2814696Y1535321D01*
X2818571Y1522821D01*
G01X2817176Y1527196D02*
X2812216D01*
G01X2830506Y1534279D02*
X2829576Y1534904D01*
X2828491Y1535321D01*
X2827251D01*
X2825856Y1534696D01*
X2824771Y1533654D01*
X2823996Y1532404D01*
X2823376Y1530321D01*
X2823221Y1528446D01*
X2823531Y1526571D01*
X2823996Y1525321D01*
X2824926Y1524071D01*
X2826011Y1523238D01*
X2827096Y1522821D01*
X2828181D01*
X2829266Y1523238D01*
X2830196Y1523862D01*
X2830971Y1524696D01*
G01X2842596Y1522821D02*
X2836396D01*
Y1535321D01*
X2842596D01*
G01X2840116Y1529279D02*
X2836396D01*
G01X2864296Y1522821D02*
X2863056Y1523029D01*
X2861971Y1523862D01*
X2861041Y1525113D01*
X2860421Y1526571D01*
X2860111Y1528238D01*
Y1529904D01*
X2860421Y1531571D01*
X2861041Y1533029D01*
X2861971Y1534279D01*
X2863056Y1535113D01*
X2864296Y1535321D01*
X2865536Y1535113D01*
X2866621Y1534279D01*
X2867551Y1533029D01*
X2868171Y1531571D01*
X2868481Y1529904D01*
Y1528238D01*
X2868171Y1526571D01*
X2867551Y1525113D01*
X2866621Y1523862D01*
X2865536Y1523029D01*
X2864296Y1522821D01*
G01X2873751D02*
Y1535321D01*
X2879641D01*
G01X2877471Y1529279D02*
X2873751D01*
G01X2897466Y1522821D02*
Y1535321D01*
X2901496Y1524904D01*
X2905526Y1535321D01*
Y1522821D01*
G01X2910486Y1535321D02*
Y1526363D01*
X2911106Y1524487D01*
X2912346Y1523238D01*
X2913896Y1522821D01*
X2915446Y1523238D01*
X2916686Y1524487D01*
X2917306Y1526363D01*
Y1535321D01*
G01X2923041Y1524487D02*
X2924281Y1523446D01*
X2925676Y1522821D01*
X2926916D01*
X2928156Y1523446D01*
X2929086Y1524487D01*
X2929551Y1525946D01*
X2929241Y1527404D01*
X2928466Y1528654D01*
X2927071Y1529488D01*
X2925211Y1529904D01*
X2924126Y1530738D01*
X2923661Y1532196D01*
X2923971Y1533654D01*
X2924746Y1534696D01*
X2925831Y1535321D01*
X2926916D01*
X2928001Y1534904D01*
X2928931Y1533863D01*
G01X2938696Y1535321D02*
Y1522821D01*
G01X2935131Y1535321D02*
X2942261D01*
G01X2949081Y1526988D02*
X2953111D01*
G01X2959931Y1522821D02*
Y1535321D01*
X2967061Y1522821D01*
Y1535321D01*
G01X2975896Y1522821D02*
X2974656Y1523029D01*
X2973571Y1523862D01*
X2972641Y1525113D01*
X2972021Y1526571D01*
X2971711Y1528238D01*
Y1529904D01*
X2972021Y1531571D01*
X2972641Y1533029D01*
X2973571Y1534279D01*
X2974656Y1535113D01*
X2975896Y1535321D01*
X2977136Y1535113D01*
X2978221Y1534279D01*
X2979151Y1533029D01*
X2979771Y1531571D01*
X2980081Y1529904D01*
Y1528238D01*
X2979771Y1526571D01*
X2979151Y1525113D01*
X2978221Y1523862D01*
X2977136Y1523029D01*
X2975896Y1522821D01*
G01X2988296Y1535321D02*
Y1522821D01*
G01X2984731Y1535321D02*
X2991861D01*
G01X2998681Y1526988D02*
X3002711D01*
G01X3016506Y1534279D02*
X3015576Y1534904D01*
X3014491Y1535321D01*
X3013251D01*
X3011856Y1534696D01*
X3010771Y1533654D01*
X3009996Y1532404D01*
X3009376Y1530321D01*
X3009221Y1528446D01*
X3009531Y1526571D01*
X3009996Y1525321D01*
X3010926Y1524071D01*
X3012011Y1523238D01*
X3013096Y1522821D01*
X3014181D01*
X3015266Y1523238D01*
X3016196Y1523862D01*
X3016971Y1524696D01*
G01X3022086Y1535321D02*
Y1526363D01*
X3022706Y1524487D01*
X3023946Y1523238D01*
X3025496Y1522821D01*
X3027046Y1523238D01*
X3028286Y1524487D01*
X3028906Y1526363D01*
Y1535321D01*
G01X3037896D02*
Y1522821D01*
G01X3034331Y1535321D02*
X3041461D01*
G01X3048281Y1526988D02*
X3052311D01*
G01X3059596Y1535321D02*
Y1522821D01*
X3065796D01*
G01X3071221D02*
X3075096Y1535321D01*
X3078971Y1522821D01*
G01X3077576Y1527196D02*
X3072616D01*
G01X3087496Y1522821D02*
Y1528446D01*
X3084396Y1535321D01*
G01X3090596D02*
X3087496Y1528446D01*
G01X3102996Y1522821D02*
X3096796D01*
Y1535321D01*
X3102996D01*
G01X3100516Y1529279D02*
X3096796D01*
G01X3109196Y1522821D02*
Y1535321D01*
X3113071D01*
X3114311Y1534696D01*
X3115086Y1533863D01*
X3115396Y1532196D01*
X3115086Y1530529D01*
X3114156Y1529488D01*
X3113071Y1528863D01*
X3109196D01*
G01X3113071D02*
X3115396Y1522821D01*
G01X2601881Y1545738D02*
X2605911D01*
G01X2624666Y1541571D02*
Y1554071D01*
X2628696Y1543654D01*
X2632726Y1554071D01*
Y1541571D01*
G01X2637221D02*
X2641096Y1554071D01*
X2644971Y1541571D01*
G01X2643576Y1545946D02*
X2638616D01*
G01X2650241Y1541571D02*
X2656751Y1554071D01*
G01X2650241D02*
X2656751Y1541571D01*
G01X2661246Y1537404D02*
X2670546D01*
G01X2674886Y1541571D02*
Y1554071D01*
X2677986D01*
X2679226Y1553446D01*
X2680156Y1552613D01*
X2680931Y1551363D01*
X2681551Y1549904D01*
X2681706Y1547821D01*
X2681551Y1545738D01*
X2680931Y1544279D01*
X2680156Y1543029D01*
X2679226Y1542196D01*
X2677986Y1541571D01*
X2674886D01*
G01X2693796D02*
X2687596D01*
Y1554071D01*
X2693796D01*
G01X2691316Y1548029D02*
X2687596D01*
G01X2699996Y1541571D02*
Y1554071D01*
X2703716D01*
X2704956Y1553446D01*
X2705886Y1551988D01*
X2706196Y1550321D01*
X2705886Y1548654D01*
X2705111Y1547404D01*
X2703716Y1546779D01*
X2699996D01*
G01X2715496Y1554071D02*
Y1541571D01*
G01X2711931Y1554071D02*
X2719061D01*
G01X2724641Y1541571D02*
Y1554071D01*
G01X2731151D02*
Y1541571D01*
G01Y1547821D02*
X2724641D01*
G01X2740296Y1541154D02*
X2739986Y1541363D01*
Y1541779D01*
X2740296Y1541988D01*
X2740606Y1541779D01*
Y1541363D01*
X2740296Y1541154D01*
G01Y1546779D02*
X2739986Y1546988D01*
Y1547404D01*
X2740296Y1547613D01*
X2740606Y1547404D01*
Y1546988D01*
X2740296Y1546779D01*
G01X2761686Y1541571D02*
Y1554071D01*
X2764786D01*
X2766026Y1553446D01*
X2766956Y1552613D01*
X2767731Y1551363D01*
X2768351Y1549904D01*
X2768506Y1547821D01*
X2768351Y1545738D01*
X2767731Y1544279D01*
X2766956Y1543029D01*
X2766026Y1542196D01*
X2764786Y1541571D01*
X2761686D01*
G01X2780596D02*
X2774396D01*
Y1554071D01*
X2780596D01*
G01X2778116Y1548029D02*
X2774396D01*
G01X2786796Y1541571D02*
Y1554071D01*
X2790516D01*
X2791756Y1553446D01*
X2792686Y1551988D01*
X2792996Y1550321D01*
X2792686Y1548654D01*
X2791911Y1547404D01*
X2790516Y1546779D01*
X2786796D01*
G01X2802296Y1554071D02*
Y1541571D01*
G01X2798731Y1554071D02*
X2805861D01*
G01X2811441Y1541571D02*
Y1554071D01*
G01X2817951D02*
Y1541571D01*
G01Y1547821D02*
X2811441D01*
G01X2836551Y1541571D02*
Y1554071D01*
X2842441D01*
G01X2840271Y1548029D02*
X2836551D01*
G01X2848796Y1541571D02*
Y1554071D01*
X2852671D01*
X2853911Y1553446D01*
X2854686Y1552613D01*
X2854996Y1550946D01*
X2854686Y1549279D01*
X2853756Y1548238D01*
X2852671Y1547613D01*
X2848796D01*
G01X2852671D02*
X2854996Y1541571D01*
G01X2864296D02*
X2863056Y1541779D01*
X2861971Y1542612D01*
X2861041Y1543863D01*
X2860421Y1545321D01*
X2860111Y1546988D01*
Y1548654D01*
X2860421Y1550321D01*
X2861041Y1551779D01*
X2861971Y1553029D01*
X2863056Y1553863D01*
X2864296Y1554071D01*
X2865536Y1553863D01*
X2866621Y1553029D01*
X2867551Y1551779D01*
X2868171Y1550321D01*
X2868481Y1548654D01*
Y1546988D01*
X2868171Y1545321D01*
X2867551Y1543863D01*
X2866621Y1542612D01*
X2865536Y1541779D01*
X2864296Y1541571D01*
G01X2872666D02*
Y1554071D01*
X2876696Y1543654D01*
X2880726Y1554071D01*
Y1541571D01*
G01X2898241Y1543237D02*
X2899481Y1542196D01*
X2900876Y1541571D01*
X2902116D01*
X2903356Y1542196D01*
X2904286Y1543237D01*
X2904751Y1544696D01*
X2904441Y1546154D01*
X2903666Y1547404D01*
X2902271Y1548238D01*
X2900411Y1548654D01*
X2899326Y1549488D01*
X2898861Y1550946D01*
X2899171Y1552404D01*
X2899946Y1553446D01*
X2901031Y1554071D01*
X2902116D01*
X2903201Y1553654D01*
X2904131Y1552613D01*
G01X2913896Y1554071D02*
Y1541571D01*
G01X2910331Y1554071D02*
X2917461D01*
G01X2922421Y1541571D02*
X2926296Y1554071D01*
X2930171Y1541571D01*
G01X2928776Y1545946D02*
X2923816D01*
G01X2935596Y1541571D02*
Y1554071D01*
X2939471D01*
X2940711Y1553446D01*
X2941486Y1552613D01*
X2941796Y1550946D01*
X2941486Y1549279D01*
X2940556Y1548238D01*
X2939471Y1547613D01*
X2935596D01*
G01X2939471D02*
X2941796Y1541571D01*
G01X2951096Y1554071D02*
Y1541571D01*
G01X2947531Y1554071D02*
X2954661D01*
G01X2972796D02*
Y1541571D01*
X2978996D01*
G01X2984421D02*
X2988296Y1554071D01*
X2992171Y1541571D01*
G01X2990776Y1545946D02*
X2985816D01*
G01X3000696Y1541571D02*
Y1547196D01*
X2997596Y1554071D01*
G01X3003796D02*
X3000696Y1547196D01*
G01X3016196Y1541571D02*
X3009996D01*
Y1554071D01*
X3016196D01*
G01X3013716Y1548029D02*
X3009996D01*
G01X3022396Y1541571D02*
Y1554071D01*
X3026271D01*
X3027511Y1553446D01*
X3028286Y1552613D01*
X3028596Y1550946D01*
X3028286Y1549279D01*
X3027356Y1548238D01*
X3026271Y1547613D01*
X3022396D01*
G01X3026271D02*
X3028596Y1541571D01*
G01X3050296Y1554071D02*
Y1541571D01*
G01X3046731Y1554071D02*
X3053861D01*
G01X3062696Y1541571D02*
X3061456Y1541779D01*
X3060371Y1542612D01*
X3059441Y1543863D01*
X3058821Y1545321D01*
X3058511Y1546988D01*
Y1548654D01*
X3058821Y1550321D01*
X3059441Y1551779D01*
X3060371Y1553029D01*
X3061456Y1553863D01*
X3062696Y1554071D01*
X3063936Y1553863D01*
X3065021Y1553029D01*
X3065951Y1551779D01*
X3066571Y1550321D01*
X3066881Y1548654D01*
Y1546988D01*
X3066571Y1545321D01*
X3065951Y1543863D01*
X3065021Y1542612D01*
X3063936Y1541779D01*
X3062696Y1541571D01*
G01X3087496Y1554071D02*
Y1541571D01*
G01X3083931Y1554071D02*
X3091061D01*
G01X3096641Y1541571D02*
Y1554071D01*
G01X3103151D02*
Y1541571D01*
G01Y1547821D02*
X3096641D01*
G01X3115396Y1541571D02*
X3109196D01*
Y1554071D01*
X3115396D01*
G01X3112916Y1548029D02*
X3109196D01*
G01X2601881Y1564488D02*
X2605911D01*
G01X2624666Y1560321D02*
Y1572821D01*
X2628696Y1562404D01*
X2632726Y1572821D01*
Y1560321D01*
G01X2637531D02*
Y1572821D01*
X2644661Y1560321D01*
Y1572821D01*
G01X2656906Y1571779D02*
X2655976Y1572404D01*
X2654891Y1572821D01*
X2653651D01*
X2652256Y1572196D01*
X2651171Y1571154D01*
X2650396Y1569904D01*
X2649776Y1567821D01*
X2649621Y1565946D01*
X2649931Y1564071D01*
X2650396Y1562821D01*
X2651326Y1561571D01*
X2652411Y1560738D01*
X2653496Y1560321D01*
X2654581D01*
X2655666Y1560738D01*
X2656596Y1561362D01*
X2657371Y1562196D01*
G01X2661246Y1556154D02*
X2670546D01*
G01X2675196Y1572821D02*
Y1560321D01*
X2681396D01*
G01X2686821D02*
X2690696Y1572821D01*
X2694571Y1560321D01*
G01X2693176Y1564696D02*
X2688216D01*
G01X2703096Y1560321D02*
Y1565946D01*
X2699996Y1572821D01*
G01X2706196D02*
X2703096Y1565946D01*
G01X2718596Y1560321D02*
X2712396D01*
Y1572821D01*
X2718596D01*
G01X2716116Y1566779D02*
X2712396D01*
G01X2724796Y1560321D02*
Y1572821D01*
X2728671D01*
X2729911Y1572196D01*
X2730686Y1571363D01*
X2730996Y1569696D01*
X2730686Y1568029D01*
X2729756Y1566988D01*
X2728671Y1566363D01*
X2724796D01*
G01X2728671D02*
X2730996Y1560321D01*
G01X2740296Y1559904D02*
X2739986Y1560113D01*
Y1560529D01*
X2740296Y1560738D01*
X2740606Y1560529D01*
Y1560113D01*
X2740296Y1559904D01*
G01Y1565529D02*
X2739986Y1565738D01*
Y1566154D01*
X2740296Y1566363D01*
X2740606Y1566154D01*
Y1565738D01*
X2740296Y1565529D01*
G01X2761066Y1560321D02*
Y1572821D01*
X2765096Y1562404D01*
X2769126Y1572821D01*
Y1560321D01*
G01X2774086Y1572821D02*
Y1563863D01*
X2774706Y1561987D01*
X2775946Y1560738D01*
X2777496Y1560321D01*
X2779046Y1560738D01*
X2780286Y1561987D01*
X2780906Y1563863D01*
Y1572821D01*
G01X2786641Y1561987D02*
X2787881Y1560946D01*
X2789276Y1560321D01*
X2790516D01*
X2791756Y1560946D01*
X2792686Y1561987D01*
X2793151Y1563446D01*
X2792841Y1564904D01*
X2792066Y1566154D01*
X2790671Y1566988D01*
X2788811Y1567404D01*
X2787726Y1568238D01*
X2787261Y1569696D01*
X2787571Y1571154D01*
X2788346Y1572196D01*
X2789431Y1572821D01*
X2790516D01*
X2791601Y1572404D01*
X2792531Y1571363D01*
G01X2802296Y1572821D02*
Y1560321D01*
G01X2798731Y1572821D02*
X2805861D01*
G01X2812681Y1564488D02*
X2816711D01*
G01X2823531Y1560321D02*
Y1572821D01*
X2830661Y1560321D01*
Y1572821D01*
G01X2839496Y1560321D02*
X2838256Y1560529D01*
X2837171Y1561362D01*
X2836241Y1562613D01*
X2835621Y1564071D01*
X2835311Y1565738D01*
Y1567404D01*
X2835621Y1569071D01*
X2836241Y1570529D01*
X2837171Y1571779D01*
X2838256Y1572613D01*
X2839496Y1572821D01*
X2840736Y1572613D01*
X2841821Y1571779D01*
X2842751Y1570529D01*
X2843371Y1569071D01*
X2843681Y1567404D01*
Y1565738D01*
X2843371Y1564071D01*
X2842751Y1562613D01*
X2841821Y1561362D01*
X2840736Y1560529D01*
X2839496Y1560321D01*
G01X2851896Y1572821D02*
Y1560321D01*
G01X2848331Y1572821D02*
X2855461D01*
G01X2862281Y1564488D02*
X2866311D01*
G01X2880106Y1571779D02*
X2879176Y1572404D01*
X2878091Y1572821D01*
X2876851D01*
X2875456Y1572196D01*
X2874371Y1571154D01*
X2873596Y1569904D01*
X2872976Y1567821D01*
X2872821Y1565946D01*
X2873131Y1564071D01*
X2873596Y1562821D01*
X2874526Y1561571D01*
X2875611Y1560738D01*
X2876696Y1560321D01*
X2877781D01*
X2878866Y1560738D01*
X2879796Y1561362D01*
X2880571Y1562196D01*
G01X2885686Y1572821D02*
Y1563863D01*
X2886306Y1561987D01*
X2887546Y1560738D01*
X2889096Y1560321D01*
X2890646Y1560738D01*
X2891886Y1561987D01*
X2892506Y1563863D01*
Y1572821D01*
G01X2901496D02*
Y1560321D01*
G01X2897931Y1572821D02*
X2905061D01*
G01X2911881Y1564488D02*
X2915911D01*
G01X2923196Y1572821D02*
Y1560321D01*
X2929396D01*
G01X2934821D02*
X2938696Y1572821D01*
X2942571Y1560321D01*
G01X2941176Y1564696D02*
X2936216D01*
G01X2951096Y1560321D02*
Y1565946D01*
X2947996Y1572821D01*
G01X2954196D02*
X2951096Y1565946D01*
G01X2966596Y1560321D02*
X2960396D01*
Y1572821D01*
X2966596D01*
G01X2964116Y1566779D02*
X2960396D01*
G01X2972796Y1560321D02*
Y1572821D01*
X2976671D01*
X2977911Y1572196D01*
X2978686Y1571363D01*
X2978996Y1569696D01*
X2978686Y1568029D01*
X2977756Y1566988D01*
X2976671Y1566363D01*
X2972796D01*
G01X2976671D02*
X2978996Y1560321D01*
G01X2600331Y1579071D02*
Y1591571D01*
X2607461Y1579071D01*
Y1591571D01*
G01X2616296Y1579071D02*
X2615056Y1579279D01*
X2613971Y1580112D01*
X2613041Y1581363D01*
X2612421Y1582821D01*
X2612111Y1584488D01*
Y1586154D01*
X2612421Y1587821D01*
X2613041Y1589279D01*
X2613971Y1590529D01*
X2615056Y1591363D01*
X2616296Y1591571D01*
X2617536Y1591363D01*
X2618621Y1590529D01*
X2619551Y1589279D01*
X2620171Y1587821D01*
X2620481Y1586154D01*
Y1584488D01*
X2620171Y1582821D01*
X2619551Y1581363D01*
X2618621Y1580112D01*
X2617536Y1579279D01*
X2616296Y1579071D01*
G01X2628696Y1591571D02*
Y1579071D01*
G01X2625131Y1591571D02*
X2632261D01*
G01X2644196Y1579071D02*
X2637996D01*
Y1591571D01*
X2644196D01*
G01X2641716Y1585529D02*
X2637996D01*
G01X2650241Y1580737D02*
X2651481Y1579696D01*
X2652876Y1579071D01*
X2654116D01*
X2655356Y1579696D01*
X2656286Y1580737D01*
X2656751Y1582196D01*
X2656441Y1583654D01*
X2655666Y1584904D01*
X2654271Y1585738D01*
X2652411Y1586154D01*
X2651326Y1586988D01*
X2650861Y1588446D01*
X2651171Y1589904D01*
X2651946Y1590946D01*
X2653031Y1591571D01*
X2654116D01*
X2655201Y1591154D01*
X2656131Y1590113D01*
G01X2665896Y1578654D02*
X2665586Y1578863D01*
Y1579279D01*
X2665896Y1579488D01*
X2666206Y1579279D01*
Y1578863D01*
X2665896Y1578654D01*
G01Y1584279D02*
X2665586Y1584488D01*
Y1584904D01*
X2665896Y1585113D01*
X2666206Y1584904D01*
Y1584488D01*
X2665896Y1584279D01*
G01X2610251Y1329053D02*
Y1341553D01*
X2616141D01*
G01X2613971Y1335511D02*
X2610251D01*
G01X2623736Y1341553D02*
X2627456D01*
G01X2625596D02*
Y1329053D01*
G01X2623736D02*
X2627456D01*
G01X2638926Y1335303D02*
X2642026D01*
Y1331553D01*
X2641096Y1330303D01*
X2640011Y1329470D01*
X2638461Y1329053D01*
X2636911Y1329470D01*
X2635826Y1330303D01*
X2634896Y1331553D01*
X2634276Y1333011D01*
X2633966Y1334678D01*
Y1336136D01*
X2634276Y1337386D01*
X2634896Y1338845D01*
X2635826Y1340095D01*
X2636756Y1340928D01*
X2637996Y1341553D01*
X2639081D01*
X2640321Y1341136D01*
X2641251Y1340303D01*
G01X2646986Y1341553D02*
Y1332595D01*
X2647606Y1330719D01*
X2648846Y1329470D01*
X2650396Y1329053D01*
X2651946Y1329470D01*
X2653186Y1330719D01*
X2653806Y1332595D01*
Y1341553D01*
G01X2659696Y1329053D02*
Y1341553D01*
X2663571D01*
X2664811Y1340928D01*
X2665586Y1340095D01*
X2665896Y1338428D01*
X2665586Y1336761D01*
X2664656Y1335720D01*
X2663571Y1335095D01*
X2659696D01*
G01X2663571D02*
X2665896Y1329053D01*
G01X2678296D02*
X2672096D01*
Y1341553D01*
X2678296D01*
G01X2675816Y1335511D02*
X2672096D01*
G01X2610251Y1679071D02*
Y1691571D01*
X2616141D01*
G01X2613971Y1685529D02*
X2610251D01*
G01X2623736Y1691571D02*
X2627456D01*
G01X2625596D02*
Y1679071D01*
G01X2623736D02*
X2627456D01*
G01X2638926Y1685321D02*
X2642026D01*
Y1681571D01*
X2641096Y1680321D01*
X2640011Y1679488D01*
X2638461Y1679071D01*
X2636911Y1679488D01*
X2635826Y1680321D01*
X2634896Y1681571D01*
X2634276Y1683029D01*
X2633966Y1684696D01*
Y1686154D01*
X2634276Y1687404D01*
X2634896Y1688863D01*
X2635826Y1690113D01*
X2636756Y1690946D01*
X2637996Y1691571D01*
X2639081D01*
X2640321Y1691154D01*
X2641251Y1690321D01*
G01X2646986Y1691571D02*
Y1682613D01*
X2647606Y1680737D01*
X2648846Y1679488D01*
X2650396Y1679071D01*
X2651946Y1679488D01*
X2653186Y1680737D01*
X2653806Y1682613D01*
Y1691571D01*
G01X2659696Y1679071D02*
Y1691571D01*
X2663571D01*
X2664811Y1690946D01*
X2665586Y1690113D01*
X2665896Y1688446D01*
X2665586Y1686779D01*
X2664656Y1685738D01*
X2663571Y1685113D01*
X2659696D01*
G01X2663571D02*
X2665896Y1679071D01*
G01X2678296D02*
X2672096D01*
Y1691571D01*
X2678296D01*
G01X2675816Y1685529D02*
X2672096D01*
G01X2648104Y2433818D02*
X2648724Y2434443D01*
X2649189Y2435484D01*
X2649499Y2436943D01*
X2649189Y2438193D01*
X2648569Y2439026D01*
X2647484Y2439651D01*
X2643299D01*
Y2427151D01*
X2648414D01*
X2649499Y2427984D01*
X2650119Y2429234D01*
X2650429Y2430693D01*
X2650119Y2432151D01*
X2649189Y2433401D01*
X2648104Y2433818D01*
X2643299D01*
G01X2655854Y2427151D02*
Y2439651D01*
X2658954D01*
X2660194Y2439026D01*
X2661124Y2438193D01*
X2661899Y2436943D01*
X2662519Y2435484D01*
X2662674Y2433401D01*
X2662519Y2431318D01*
X2661899Y2429859D01*
X2661124Y2428609D01*
X2660194Y2427776D01*
X2658954Y2427151D01*
X2655854D01*
G01X2667014Y2422984D02*
X2676314D01*
G01X2680809Y2428817D02*
X2682049Y2427776D01*
X2683444Y2427151D01*
X2684684D01*
X2685924Y2427776D01*
X2686854Y2428817D01*
X2687319Y2430276D01*
X2687009Y2431734D01*
X2686234Y2432984D01*
X2684839Y2433818D01*
X2682979Y2434234D01*
X2681894Y2435068D01*
X2681429Y2436526D01*
X2681739Y2437984D01*
X2682514Y2439026D01*
X2683599Y2439651D01*
X2684684D01*
X2685769Y2439234D01*
X2686699Y2438193D01*
G01X2694604Y2439651D02*
X2698324D01*
G01X2696464D02*
Y2427151D01*
G01X2694604D02*
X2698324D01*
G01X2705919Y2439651D02*
X2711809D01*
X2705919Y2427151D01*
X2711809D01*
G01X2724364D02*
X2718164D01*
Y2439651D01*
X2724364D01*
G01X2721884Y2433609D02*
X2718164D01*
G01X2665464Y2352151D02*
Y2364651D01*
X2663604Y2362151D01*
G01Y2352151D02*
X2667324D01*
G01X2675229Y2353609D02*
X2676314Y2352568D01*
X2677554Y2352151D01*
X2678794Y2352568D01*
X2679879Y2353817D01*
X2680654Y2355693D01*
X2680964Y2357568D01*
Y2359859D01*
X2680654Y2361734D01*
X2679879Y2363401D01*
X2678949Y2364234D01*
X2677864Y2364651D01*
X2676624Y2364234D01*
X2675694Y2363401D01*
X2675074Y2362151D01*
X2674764Y2360484D01*
X2675074Y2359026D01*
X2675849Y2357568D01*
X2676779Y2356734D01*
X2677864Y2356526D01*
X2679104Y2356942D01*
X2680034Y2357984D01*
X2680964Y2359859D01*
G01X2690264Y2351734D02*
X2689954Y2351943D01*
Y2352359D01*
X2690264Y2352568D01*
X2690574Y2352359D01*
Y2351943D01*
X2690264Y2351734D01*
G01X2700029Y2353609D02*
X2701114Y2352568D01*
X2702354Y2352151D01*
X2703594Y2352568D01*
X2704679Y2353817D01*
X2705454Y2355693D01*
X2705764Y2357568D01*
Y2359859D01*
X2705454Y2361734D01*
X2704679Y2363401D01*
X2703749Y2364234D01*
X2702664Y2364651D01*
X2701424Y2364234D01*
X2700494Y2363401D01*
X2699874Y2362151D01*
X2699564Y2360484D01*
X2699874Y2359026D01*
X2700649Y2357568D01*
X2701579Y2356734D01*
X2702664Y2356526D01*
X2703904Y2356942D01*
X2704834Y2357984D01*
X2705764Y2359859D01*
G01X2665464Y2377151D02*
Y2389651D01*
X2663604Y2387151D01*
G01Y2377151D02*
X2667324D01*
G01X2677554D02*
X2677864Y2379859D01*
X2678329Y2382151D01*
X2678949Y2384234D01*
X2679724Y2386526D01*
X2680964Y2389651D01*
X2674764D01*
G01X2690264Y2376734D02*
X2689954Y2376943D01*
Y2377359D01*
X2690264Y2377568D01*
X2690574Y2377359D01*
Y2376943D01*
X2690264Y2376734D01*
G01X2702354Y2377151D02*
X2702664Y2379859D01*
X2703129Y2382151D01*
X2703749Y2384234D01*
X2704524Y2386526D01*
X2705764Y2389651D01*
X2699564D01*
G01X2665464Y2402151D02*
Y2414651D01*
X2663604Y2412151D01*
G01Y2402151D02*
X2667324D01*
G01X2674454Y2404026D02*
X2675384Y2402984D01*
X2676469Y2402359D01*
X2677864Y2402151D01*
X2679259Y2402568D01*
X2680344Y2403401D01*
X2681119Y2404859D01*
X2681274Y2406526D01*
X2680964Y2408193D01*
X2680189Y2409234D01*
X2679104Y2410068D01*
X2678019Y2410276D01*
X2676934Y2410068D01*
X2675539Y2409234D01*
X2676004Y2414651D01*
X2680189D01*
G01X2690264Y2401734D02*
X2689954Y2401943D01*
Y2402359D01*
X2690264Y2402568D01*
X2690574Y2402359D01*
Y2401943D01*
X2690264Y2401734D01*
G01X2702354Y2402151D02*
X2702664Y2404859D01*
X2703129Y2407151D01*
X2703749Y2409234D01*
X2704524Y2411526D01*
X2705764Y2414651D01*
X2699564D01*
G01X2661831Y2794130D02*
X2662451Y2794755D01*
X2662916Y2795796D01*
X2663226Y2797255D01*
X2662916Y2798505D01*
X2662296Y2799338D01*
X2661211Y2799963D01*
X2657026D01*
Y2787463D01*
X2662141D01*
X2663226Y2788296D01*
X2663846Y2789546D01*
X2664156Y2791005D01*
X2663846Y2792463D01*
X2662916Y2793713D01*
X2661831Y2794130D01*
X2657026D01*
G01X2669581Y2787463D02*
Y2799963D01*
X2672681D01*
X2673921Y2799338D01*
X2674851Y2798505D01*
X2675626Y2797255D01*
X2676246Y2795796D01*
X2676401Y2793713D01*
X2676246Y2791630D01*
X2675626Y2790171D01*
X2674851Y2788921D01*
X2673921Y2788088D01*
X2672681Y2787463D01*
X2669581D01*
G01X2680741Y2783296D02*
X2690041D01*
G01X2694536Y2789129D02*
X2695776Y2788088D01*
X2697171Y2787463D01*
X2698411D01*
X2699651Y2788088D01*
X2700581Y2789129D01*
X2701046Y2790588D01*
X2700736Y2792046D01*
X2699961Y2793296D01*
X2698566Y2794130D01*
X2696706Y2794546D01*
X2695621Y2795380D01*
X2695156Y2796838D01*
X2695466Y2798296D01*
X2696241Y2799338D01*
X2697326Y2799963D01*
X2698411D01*
X2699496Y2799546D01*
X2700426Y2798505D01*
G01X2708331Y2799963D02*
X2712051D01*
G01X2710191D02*
Y2787463D01*
G01X2708331D02*
X2712051D01*
G01X2719646Y2799963D02*
X2725536D01*
X2719646Y2787463D01*
X2725536D01*
G01X2738091D02*
X2731891D01*
Y2799963D01*
X2738091D01*
G01X2735611Y2793921D02*
X2731891D01*
G01X2682420Y2049483D02*
X2683040Y2050108D01*
X2683505Y2051149D01*
X2683815Y2052608D01*
X2683505Y2053858D01*
X2682885Y2054691D01*
X2681800Y2055316D01*
X2677615D01*
Y2042816D01*
X2682730D01*
X2683815Y2043649D01*
X2684435Y2044899D01*
X2684745Y2046358D01*
X2684435Y2047816D01*
X2683505Y2049066D01*
X2682420Y2049483D01*
X2677615D01*
G01X2690170Y2042816D02*
Y2055316D01*
X2693270D01*
X2694510Y2054691D01*
X2695440Y2053858D01*
X2696215Y2052608D01*
X2696835Y2051149D01*
X2696990Y2049066D01*
X2696835Y2046983D01*
X2696215Y2045524D01*
X2695440Y2044274D01*
X2694510Y2043441D01*
X2693270Y2042816D01*
X2690170D01*
G01X2701330Y2038649D02*
X2710630D01*
G01X2715125Y2044482D02*
X2716365Y2043441D01*
X2717760Y2042816D01*
X2719000D01*
X2720240Y2043441D01*
X2721170Y2044482D01*
X2721635Y2045941D01*
X2721325Y2047399D01*
X2720550Y2048649D01*
X2719155Y2049483D01*
X2717295Y2049899D01*
X2716210Y2050733D01*
X2715745Y2052191D01*
X2716055Y2053649D01*
X2716830Y2054691D01*
X2717915Y2055316D01*
X2719000D01*
X2720085Y2054899D01*
X2721015Y2053858D01*
G01X2728920Y2055316D02*
X2732640D01*
G01X2730780D02*
Y2042816D01*
G01X2728920D02*
X2732640D01*
G01X2740235Y2055316D02*
X2746125D01*
X2740235Y2042816D01*
X2746125D01*
G01X2758680D02*
X2752480D01*
Y2055316D01*
X2758680D01*
G01X2756200Y2049274D02*
X2752480D01*
G01X2679191Y2712463D02*
Y2724963D01*
X2677331Y2722463D01*
G01Y2712463D02*
X2681051D01*
G01X2688956Y2713921D02*
X2690041Y2712880D01*
X2691281Y2712463D01*
X2692521Y2712880D01*
X2693606Y2714129D01*
X2694381Y2716005D01*
X2694691Y2717880D01*
Y2720171D01*
X2694381Y2722046D01*
X2693606Y2723713D01*
X2692676Y2724546D01*
X2691591Y2724963D01*
X2690351Y2724546D01*
X2689421Y2723713D01*
X2688801Y2722463D01*
X2688491Y2720796D01*
X2688801Y2719338D01*
X2689576Y2717880D01*
X2690506Y2717046D01*
X2691591Y2716838D01*
X2692831Y2717254D01*
X2693761Y2718296D01*
X2694691Y2720171D01*
G01X2703991Y2712046D02*
X2703681Y2712255D01*
Y2712671D01*
X2703991Y2712880D01*
X2704301Y2712671D01*
Y2712255D01*
X2703991Y2712046D01*
G01X2713756Y2713921D02*
X2714841Y2712880D01*
X2716081Y2712463D01*
X2717321Y2712880D01*
X2718406Y2714129D01*
X2719181Y2716005D01*
X2719491Y2717880D01*
Y2720171D01*
X2719181Y2722046D01*
X2718406Y2723713D01*
X2717476Y2724546D01*
X2716391Y2724963D01*
X2715151Y2724546D01*
X2714221Y2723713D01*
X2713601Y2722463D01*
X2713291Y2720796D01*
X2713601Y2719338D01*
X2714376Y2717880D01*
X2715306Y2717046D01*
X2716391Y2716838D01*
X2717631Y2717254D01*
X2718561Y2718296D01*
X2719491Y2720171D01*
G01X2679191Y2737463D02*
Y2749963D01*
X2677331Y2747463D01*
G01Y2737463D02*
X2681051D01*
G01X2691281D02*
X2691591Y2740171D01*
X2692056Y2742463D01*
X2692676Y2744546D01*
X2693451Y2746838D01*
X2694691Y2749963D01*
X2688491D01*
G01X2703991Y2737046D02*
X2703681Y2737255D01*
Y2737671D01*
X2703991Y2737880D01*
X2704301Y2737671D01*
Y2737255D01*
X2703991Y2737046D01*
G01X2716081Y2737463D02*
X2716391Y2740171D01*
X2716856Y2742463D01*
X2717476Y2744546D01*
X2718251Y2746838D01*
X2719491Y2749963D01*
X2713291D01*
G01X2679191Y2762463D02*
Y2774963D01*
X2677331Y2772463D01*
G01Y2762463D02*
X2681051D01*
G01X2688181Y2764338D02*
X2689111Y2763296D01*
X2690196Y2762671D01*
X2691591Y2762463D01*
X2692986Y2762880D01*
X2694071Y2763713D01*
X2694846Y2765171D01*
X2695001Y2766838D01*
X2694691Y2768505D01*
X2693916Y2769546D01*
X2692831Y2770380D01*
X2691746Y2770588D01*
X2690661Y2770380D01*
X2689266Y2769546D01*
X2689731Y2774963D01*
X2693916D01*
G01X2703991Y2762046D02*
X2703681Y2762255D01*
Y2762671D01*
X2703991Y2762880D01*
X2704301Y2762671D01*
Y2762255D01*
X2703991Y2762046D01*
G01X2716081Y2762463D02*
X2716391Y2765171D01*
X2716856Y2767463D01*
X2717476Y2769546D01*
X2718251Y2771838D01*
X2719491Y2774963D01*
X2713291D01*
G01X2699780Y1967816D02*
Y1980316D01*
X2697920Y1977816D01*
G01Y1967816D02*
X2701640D01*
G01X2709545Y1969274D02*
X2710630Y1968233D01*
X2711870Y1967816D01*
X2713110Y1968233D01*
X2714195Y1969482D01*
X2714970Y1971358D01*
X2715280Y1973233D01*
Y1975524D01*
X2714970Y1977399D01*
X2714195Y1979066D01*
X2713265Y1979899D01*
X2712180Y1980316D01*
X2710940Y1979899D01*
X2710010Y1979066D01*
X2709390Y1977816D01*
X2709080Y1976149D01*
X2709390Y1974691D01*
X2710165Y1973233D01*
X2711095Y1972399D01*
X2712180Y1972191D01*
X2713420Y1972607D01*
X2714350Y1973649D01*
X2715280Y1975524D01*
G01X2724580Y1967399D02*
X2724270Y1967608D01*
Y1968024D01*
X2724580Y1968233D01*
X2724890Y1968024D01*
Y1967608D01*
X2724580Y1967399D01*
G01X2734345Y1969274D02*
X2735430Y1968233D01*
X2736670Y1967816D01*
X2737910Y1968233D01*
X2738995Y1969482D01*
X2739770Y1971358D01*
X2740080Y1973233D01*
Y1975524D01*
X2739770Y1977399D01*
X2738995Y1979066D01*
X2738065Y1979899D01*
X2736980Y1980316D01*
X2735740Y1979899D01*
X2734810Y1979066D01*
X2734190Y1977816D01*
X2733880Y1976149D01*
X2734190Y1974691D01*
X2734965Y1973233D01*
X2735895Y1972399D01*
X2736980Y1972191D01*
X2738220Y1972607D01*
X2739150Y1973649D01*
X2740080Y1975524D01*
G01X2699780Y1992816D02*
Y2005316D01*
X2697920Y2002816D01*
G01Y1992816D02*
X2701640D01*
G01X2711870D02*
X2712180Y1995524D01*
X2712645Y1997816D01*
X2713265Y1999899D01*
X2714040Y2002191D01*
X2715280Y2005316D01*
X2709080D01*
G01X2724580Y1992399D02*
X2724270Y1992608D01*
Y1993024D01*
X2724580Y1993233D01*
X2724890Y1993024D01*
Y1992608D01*
X2724580Y1992399D01*
G01X2736670Y1992816D02*
X2736980Y1995524D01*
X2737445Y1997816D01*
X2738065Y1999899D01*
X2738840Y2002191D01*
X2740080Y2005316D01*
X2733880D01*
G01X2699780Y2017816D02*
Y2030316D01*
X2697920Y2027816D01*
G01Y2017816D02*
X2701640D01*
G01X2708770Y2019691D02*
X2709700Y2018649D01*
X2710785Y2018024D01*
X2712180Y2017816D01*
X2713575Y2018233D01*
X2714660Y2019066D01*
X2715435Y2020524D01*
X2715590Y2022191D01*
X2715280Y2023858D01*
X2714505Y2024899D01*
X2713420Y2025733D01*
X2712335Y2025941D01*
X2711250Y2025733D01*
X2709855Y2024899D01*
X2710320Y2030316D01*
X2714505D01*
G01X2724580Y2017399D02*
X2724270Y2017608D01*
Y2018024D01*
X2724580Y2018233D01*
X2724890Y2018024D01*
Y2017608D01*
X2724580Y2017399D01*
G01X2736670Y2017816D02*
X2736980Y2020524D01*
X2737445Y2022816D01*
X2738065Y2024899D01*
X2738840Y2027191D01*
X2740080Y2030316D01*
X2733880D01*
G01X2716736Y1335720D02*
X2717356Y1336345D01*
X2717821Y1337386D01*
X2718131Y1338845D01*
X2717821Y1340095D01*
X2717201Y1340928D01*
X2716116Y1341553D01*
X2711931D01*
Y1329053D01*
X2717046D01*
X2718131Y1329886D01*
X2718751Y1331136D01*
X2719061Y1332595D01*
X2718751Y1334053D01*
X2717821Y1335303D01*
X2716736Y1335720D01*
X2711931D01*
G01X2724486Y1329053D02*
Y1341553D01*
X2727586D01*
X2728826Y1340928D01*
X2729756Y1340095D01*
X2730531Y1338845D01*
X2731151Y1337386D01*
X2731306Y1335303D01*
X2731151Y1333220D01*
X2730531Y1331761D01*
X2729756Y1330511D01*
X2728826Y1329678D01*
X2727586Y1329053D01*
X2724486D01*
G01X2735646Y1324886D02*
X2744946D01*
G01X2749441Y1330719D02*
X2750681Y1329678D01*
X2752076Y1329053D01*
X2753316D01*
X2754556Y1329678D01*
X2755486Y1330719D01*
X2755951Y1332178D01*
X2755641Y1333636D01*
X2754866Y1334886D01*
X2753471Y1335720D01*
X2751611Y1336136D01*
X2750526Y1336970D01*
X2750061Y1338428D01*
X2750371Y1339886D01*
X2751146Y1340928D01*
X2752231Y1341553D01*
X2753316D01*
X2754401Y1341136D01*
X2755331Y1340095D01*
G01X2763236Y1341553D02*
X2766956D01*
G01X2765096D02*
Y1329053D01*
G01X2763236D02*
X2766956D01*
G01X2774551Y1341553D02*
X2780441D01*
X2774551Y1329053D01*
X2780441D01*
G01X2792996D02*
X2786796D01*
Y1341553D01*
X2792996D01*
G01X2790516Y1335511D02*
X2786796D01*
G01X2716736Y1685738D02*
X2717356Y1686363D01*
X2717821Y1687404D01*
X2718131Y1688863D01*
X2717821Y1690113D01*
X2717201Y1690946D01*
X2716116Y1691571D01*
X2711931D01*
Y1679071D01*
X2717046D01*
X2718131Y1679904D01*
X2718751Y1681154D01*
X2719061Y1682613D01*
X2718751Y1684071D01*
X2717821Y1685321D01*
X2716736Y1685738D01*
X2711931D01*
G01X2724486Y1679071D02*
Y1691571D01*
X2727586D01*
X2728826Y1690946D01*
X2729756Y1690113D01*
X2730531Y1688863D01*
X2731151Y1687404D01*
X2731306Y1685321D01*
X2731151Y1683238D01*
X2730531Y1681779D01*
X2729756Y1680529D01*
X2728826Y1679696D01*
X2727586Y1679071D01*
X2724486D01*
G01X2735646Y1674904D02*
X2744946D01*
G01X2749441Y1680737D02*
X2750681Y1679696D01*
X2752076Y1679071D01*
X2753316D01*
X2754556Y1679696D01*
X2755486Y1680737D01*
X2755951Y1682196D01*
X2755641Y1683654D01*
X2754866Y1684904D01*
X2753471Y1685738D01*
X2751611Y1686154D01*
X2750526Y1686988D01*
X2750061Y1688446D01*
X2750371Y1689904D01*
X2751146Y1690946D01*
X2752231Y1691571D01*
X2753316D01*
X2754401Y1691154D01*
X2755331Y1690113D01*
G01X2763236Y1691571D02*
X2766956D01*
G01X2765096D02*
Y1679071D01*
G01X2763236D02*
X2766956D01*
G01X2774551Y1691571D02*
X2780441D01*
X2774551Y1679071D01*
X2780441D01*
G01X2792996D02*
X2786796D01*
Y1691571D01*
X2792996D01*
G01X2790516Y1685529D02*
X2786796D01*
G01X2734096Y1254053D02*
Y1266553D01*
X2732236Y1264053D01*
G01Y1254053D02*
X2735956D01*
G01X2743861Y1255511D02*
X2744946Y1254470D01*
X2746186Y1254053D01*
X2747426Y1254470D01*
X2748511Y1255719D01*
X2749286Y1257595D01*
X2749596Y1259470D01*
Y1261761D01*
X2749286Y1263636D01*
X2748511Y1265303D01*
X2747581Y1266136D01*
X2746496Y1266553D01*
X2745256Y1266136D01*
X2744326Y1265303D01*
X2743706Y1264053D01*
X2743396Y1262386D01*
X2743706Y1260928D01*
X2744481Y1259470D01*
X2745411Y1258636D01*
X2746496Y1258428D01*
X2747736Y1258844D01*
X2748666Y1259886D01*
X2749596Y1261761D01*
G01X2758896Y1253636D02*
X2758586Y1253845D01*
Y1254261D01*
X2758896Y1254470D01*
X2759206Y1254261D01*
Y1253845D01*
X2758896Y1253636D01*
G01X2768661Y1255511D02*
X2769746Y1254470D01*
X2770986Y1254053D01*
X2772226Y1254470D01*
X2773311Y1255719D01*
X2774086Y1257595D01*
X2774396Y1259470D01*
Y1261761D01*
X2774086Y1263636D01*
X2773311Y1265303D01*
X2772381Y1266136D01*
X2771296Y1266553D01*
X2770056Y1266136D01*
X2769126Y1265303D01*
X2768506Y1264053D01*
X2768196Y1262386D01*
X2768506Y1260928D01*
X2769281Y1259470D01*
X2770211Y1258636D01*
X2771296Y1258428D01*
X2772536Y1258844D01*
X2773466Y1259886D01*
X2774396Y1261761D01*
G01X2734096Y1279053D02*
Y1291553D01*
X2732236Y1289053D01*
G01Y1279053D02*
X2735956D01*
G01X2746186D02*
X2746496Y1281761D01*
X2746961Y1284053D01*
X2747581Y1286136D01*
X2748356Y1288428D01*
X2749596Y1291553D01*
X2743396D01*
G01X2758896Y1278636D02*
X2758586Y1278845D01*
Y1279261D01*
X2758896Y1279470D01*
X2759206Y1279261D01*
Y1278845D01*
X2758896Y1278636D01*
G01X2770986Y1279053D02*
X2771296Y1281761D01*
X2771761Y1284053D01*
X2772381Y1286136D01*
X2773156Y1288428D01*
X2774396Y1291553D01*
X2768196D01*
G01X2734096Y1304053D02*
Y1316553D01*
X2732236Y1314053D01*
G01Y1304053D02*
X2735956D01*
G01X2743086Y1305928D02*
X2744016Y1304886D01*
X2745101Y1304261D01*
X2746496Y1304053D01*
X2747891Y1304470D01*
X2748976Y1305303D01*
X2749751Y1306761D01*
X2749906Y1308428D01*
X2749596Y1310095D01*
X2748821Y1311136D01*
X2747736Y1311970D01*
X2746651Y1312178D01*
X2745566Y1311970D01*
X2744171Y1311136D01*
X2744636Y1316553D01*
X2748821D01*
G01X2758896Y1303636D02*
X2758586Y1303845D01*
Y1304261D01*
X2758896Y1304470D01*
X2759206Y1304261D01*
Y1303845D01*
X2758896Y1303636D01*
G01X2770986Y1304053D02*
X2771296Y1306761D01*
X2771761Y1309053D01*
X2772381Y1311136D01*
X2773156Y1313428D01*
X2774396Y1316553D01*
X2768196D01*
G01X2734096Y1604071D02*
Y1616571D01*
X2732236Y1614071D01*
G01Y1604071D02*
X2735956D01*
G01X2743861Y1605529D02*
X2744946Y1604488D01*
X2746186Y1604071D01*
X2747426Y1604488D01*
X2748511Y1605737D01*
X2749286Y1607613D01*
X2749596Y1609488D01*
Y1611779D01*
X2749286Y1613654D01*
X2748511Y1615321D01*
X2747581Y1616154D01*
X2746496Y1616571D01*
X2745256Y1616154D01*
X2744326Y1615321D01*
X2743706Y1614071D01*
X2743396Y1612404D01*
X2743706Y1610946D01*
X2744481Y1609488D01*
X2745411Y1608654D01*
X2746496Y1608446D01*
X2747736Y1608862D01*
X2748666Y1609904D01*
X2749596Y1611779D01*
G01X2758896Y1603654D02*
X2758586Y1603863D01*
Y1604279D01*
X2758896Y1604488D01*
X2759206Y1604279D01*
Y1603863D01*
X2758896Y1603654D01*
G01X2768661Y1605529D02*
X2769746Y1604488D01*
X2770986Y1604071D01*
X2772226Y1604488D01*
X2773311Y1605737D01*
X2774086Y1607613D01*
X2774396Y1609488D01*
Y1611779D01*
X2774086Y1613654D01*
X2773311Y1615321D01*
X2772381Y1616154D01*
X2771296Y1616571D01*
X2770056Y1616154D01*
X2769126Y1615321D01*
X2768506Y1614071D01*
X2768196Y1612404D01*
X2768506Y1610946D01*
X2769281Y1609488D01*
X2770211Y1608654D01*
X2771296Y1608446D01*
X2772536Y1608862D01*
X2773466Y1609904D01*
X2774396Y1611779D01*
G01X2734096Y1629071D02*
Y1641571D01*
X2732236Y1639071D01*
G01Y1629071D02*
X2735956D01*
G01X2746186D02*
X2746496Y1631779D01*
X2746961Y1634071D01*
X2747581Y1636154D01*
X2748356Y1638446D01*
X2749596Y1641571D01*
X2743396D01*
G01X2758896Y1628654D02*
X2758586Y1628863D01*
Y1629279D01*
X2758896Y1629488D01*
X2759206Y1629279D01*
Y1628863D01*
X2758896Y1628654D01*
G01X2770986Y1629071D02*
X2771296Y1631779D01*
X2771761Y1634071D01*
X2772381Y1636154D01*
X2773156Y1638446D01*
X2774396Y1641571D01*
X2768196D01*
G01X2734096Y1654071D02*
Y1666571D01*
X2732236Y1664071D01*
G01Y1654071D02*
X2735956D01*
G01X2743086Y1655946D02*
X2744016Y1654904D01*
X2745101Y1654279D01*
X2746496Y1654071D01*
X2747891Y1654488D01*
X2748976Y1655321D01*
X2749751Y1656779D01*
X2749906Y1658446D01*
X2749596Y1660113D01*
X2748821Y1661154D01*
X2747736Y1661988D01*
X2746651Y1662196D01*
X2745566Y1661988D01*
X2744171Y1661154D01*
X2744636Y1666571D01*
X2748821D01*
G01X2758896Y1653654D02*
X2758586Y1653863D01*
Y1654279D01*
X2758896Y1654488D01*
X2759206Y1654279D01*
Y1653863D01*
X2758896Y1653654D01*
G01X2770986Y1654071D02*
X2771296Y1656779D01*
X2771761Y1659071D01*
X2772381Y1661154D01*
X2773156Y1663446D01*
X2774396Y1666571D01*
X2768196D01*
G01X2751223Y987938D02*
Y1000438D01*
X2757113D01*
G01X2754943Y994396D02*
X2751223D01*
G01X2764708Y1000438D02*
X2768428D01*
G01X2766568D02*
Y987938D01*
G01X2764708D02*
X2768428D01*
G01X2779898Y994188D02*
X2782998D01*
Y990438D01*
X2782068Y989188D01*
X2780983Y988355D01*
X2779433Y987938D01*
X2777883Y988355D01*
X2776798Y989188D01*
X2775868Y990438D01*
X2775248Y991896D01*
X2774938Y993563D01*
Y995021D01*
X2775248Y996271D01*
X2775868Y997730D01*
X2776798Y998980D01*
X2777728Y999813D01*
X2778968Y1000438D01*
X2780053D01*
X2781293Y1000021D01*
X2782223Y999188D01*
G01X2787958Y1000438D02*
Y991480D01*
X2788578Y989604D01*
X2789818Y988355D01*
X2791368Y987938D01*
X2792918Y988355D01*
X2794158Y989604D01*
X2794778Y991480D01*
Y1000438D01*
G01X2800668Y987938D02*
Y1000438D01*
X2804543D01*
X2805783Y999813D01*
X2806558Y998980D01*
X2806868Y997313D01*
X2806558Y995646D01*
X2805628Y994605D01*
X2804543Y993980D01*
X2800668D01*
G01X2804543D02*
X2806868Y987938D01*
G01X2819268D02*
X2813068D01*
Y1000438D01*
X2819268D01*
G01X2816788Y994396D02*
X2813068D01*
G01X2758154Y2483818D02*
X2758774Y2484443D01*
X2759239Y2485484D01*
X2759549Y2486943D01*
X2759239Y2488193D01*
X2758619Y2489026D01*
X2757534Y2489651D01*
X2753349D01*
Y2477151D01*
X2758464D01*
X2759549Y2477984D01*
X2760169Y2479234D01*
X2760479Y2480693D01*
X2760169Y2482151D01*
X2759239Y2483401D01*
X2758154Y2483818D01*
X2753349D01*
G01X2765439Y2477151D02*
X2769314Y2489651D01*
X2773189Y2477151D01*
G01X2771794Y2481526D02*
X2766834D01*
G01X2785124Y2488609D02*
X2784194Y2489234D01*
X2783109Y2489651D01*
X2781869D01*
X2780474Y2489026D01*
X2779389Y2487984D01*
X2778614Y2486734D01*
X2777994Y2484651D01*
X2777839Y2482776D01*
X2778149Y2480901D01*
X2778614Y2479651D01*
X2779544Y2478401D01*
X2780629Y2477568D01*
X2781714Y2477151D01*
X2782799D01*
X2783884Y2477568D01*
X2784814Y2478192D01*
X2785589Y2479026D01*
G01X2790704Y2477151D02*
Y2489651D01*
G01X2796594D02*
X2790704Y2481942D01*
G01X2797524Y2477151D02*
X2793339Y2485484D01*
G01X2803104Y2477151D02*
Y2489651D01*
X2806204D01*
X2807444Y2489026D01*
X2808374Y2488193D01*
X2809149Y2486943D01*
X2809769Y2485484D01*
X2809924Y2483401D01*
X2809769Y2481318D01*
X2809149Y2479859D01*
X2808374Y2478609D01*
X2807444Y2477776D01*
X2806204Y2477151D01*
X2803104D01*
G01X2815814D02*
Y2489651D01*
X2819689D01*
X2820929Y2489026D01*
X2821704Y2488193D01*
X2822014Y2486526D01*
X2821704Y2484859D01*
X2820774Y2483818D01*
X2819689Y2483193D01*
X2815814D01*
G01X2819689D02*
X2822014Y2477151D01*
G01X2829454Y2489651D02*
X2833174D01*
G01X2831314D02*
Y2477151D01*
G01X2829454D02*
X2833174D01*
G01X2840614Y2489651D02*
Y2477151D01*
X2846814D01*
G01X2853014Y2489651D02*
Y2477151D01*
X2859214D01*
G01X2868514Y2476734D02*
X2868204Y2476943D01*
Y2477359D01*
X2868514Y2477568D01*
X2868824Y2477359D01*
Y2476943D01*
X2868514Y2476734D01*
G01Y2482359D02*
X2868204Y2482568D01*
Y2482984D01*
X2868514Y2483193D01*
X2868824Y2482984D01*
Y2482568D01*
X2868514Y2482359D01*
G01X2894554Y2483818D02*
X2895174Y2484443D01*
X2895639Y2485484D01*
X2895949Y2486943D01*
X2895639Y2488193D01*
X2895019Y2489026D01*
X2893934Y2489651D01*
X2889749D01*
Y2477151D01*
X2894864D01*
X2895949Y2477984D01*
X2896569Y2479234D01*
X2896879Y2480693D01*
X2896569Y2482151D01*
X2895639Y2483401D01*
X2894554Y2483818D01*
X2889749D01*
G01X2905714Y2477151D02*
X2904474Y2477359D01*
X2903389Y2478192D01*
X2902459Y2479443D01*
X2901839Y2480901D01*
X2901529Y2482568D01*
Y2484234D01*
X2901839Y2485901D01*
X2902459Y2487359D01*
X2903389Y2488609D01*
X2904474Y2489443D01*
X2905714Y2489651D01*
X2906954Y2489443D01*
X2908039Y2488609D01*
X2908969Y2487359D01*
X2909589Y2485901D01*
X2909899Y2484234D01*
Y2482568D01*
X2909589Y2480901D01*
X2908969Y2479443D01*
X2908039Y2478192D01*
X2906954Y2477359D01*
X2905714Y2477151D01*
G01X2918114Y2489651D02*
Y2477151D01*
G01X2914549Y2489651D02*
X2921679D01*
G01X2930514D02*
Y2477151D01*
G01X2926949Y2489651D02*
X2934079D01*
G01X2942914Y2477151D02*
X2941674Y2477359D01*
X2940589Y2478192D01*
X2939659Y2479443D01*
X2939039Y2480901D01*
X2938729Y2482568D01*
Y2484234D01*
X2939039Y2485901D01*
X2939659Y2487359D01*
X2940589Y2488609D01*
X2941674Y2489443D01*
X2942914Y2489651D01*
X2944154Y2489443D01*
X2945239Y2488609D01*
X2946169Y2487359D01*
X2946789Y2485901D01*
X2947099Y2484234D01*
Y2482568D01*
X2946789Y2480901D01*
X2946169Y2479443D01*
X2945239Y2478192D01*
X2944154Y2477359D01*
X2942914Y2477151D01*
G01X2951284D02*
Y2489651D01*
X2955314Y2479234D01*
X2959344Y2489651D01*
Y2477151D01*
G01X2980114Y2489651D02*
Y2477151D01*
G01X2977944Y2485484D02*
X2982284D01*
G01X2992514Y2477151D02*
X2991584Y2477359D01*
X2990654Y2478192D01*
X2990034Y2479651D01*
X2989724Y2481318D01*
X2990034Y2482984D01*
X2990654Y2484443D01*
X2991584Y2485276D01*
X2992514Y2485484D01*
X2993444Y2485276D01*
X2994374Y2484443D01*
X2994994Y2482984D01*
X2995149Y2481318D01*
X2994994Y2479651D01*
X2994374Y2478192D01*
X2993444Y2477359D01*
X2992514Y2477151D01*
G01X3018244Y2483401D02*
X3021344D01*
Y2479651D01*
X3020414Y2478401D01*
X3019329Y2477568D01*
X3017779Y2477151D01*
X3016229Y2477568D01*
X3015144Y2478401D01*
X3014214Y2479651D01*
X3013594Y2481109D01*
X3013284Y2482776D01*
Y2484234D01*
X3013594Y2485484D01*
X3014214Y2486943D01*
X3015144Y2488193D01*
X3016074Y2489026D01*
X3017314Y2489651D01*
X3018399D01*
X3019639Y2489234D01*
X3020569Y2488401D01*
G01X3026149Y2477151D02*
Y2489651D01*
X3033279Y2477151D01*
Y2489651D01*
G01X3038704Y2477151D02*
Y2489651D01*
X3041804D01*
X3043044Y2489026D01*
X3043974Y2488193D01*
X3044749Y2486943D01*
X3045369Y2485484D01*
X3045524Y2483401D01*
X3045369Y2481318D01*
X3044749Y2479859D01*
X3043974Y2478609D01*
X3043044Y2477776D01*
X3041804Y2477151D01*
X3038704D01*
G01X3051569Y2482359D02*
X3052654Y2483818D01*
X3053584Y2484651D01*
X3054824Y2485068D01*
X3055909Y2484651D01*
X3056684Y2483818D01*
X3057304Y2482568D01*
X3057459Y2481109D01*
X3057304Y2479859D01*
X3056684Y2478609D01*
X3055754Y2477568D01*
X3054669Y2477151D01*
X3053429Y2477568D01*
X3052344Y2478817D01*
X3051724Y2480693D01*
X3051569Y2482776D01*
X3051879Y2485484D01*
X3052344Y2486943D01*
X3053119Y2488401D01*
X3054204Y2489443D01*
X3055289Y2489651D01*
X3056374Y2489234D01*
X3057149Y2488193D01*
G01X2777839Y2452151D02*
X2781714Y2464651D01*
X2785589Y2452151D01*
G01X2784194Y2456526D02*
X2779234D01*
G01X2791014Y2464651D02*
Y2452151D01*
X2797214D01*
G01X2803414Y2464651D02*
Y2452151D01*
X2809614D01*
G01X2827904Y2464651D02*
Y2455693D01*
X2828524Y2453817D01*
X2829764Y2452568D01*
X2831314Y2452151D01*
X2832864Y2452568D01*
X2834104Y2453817D01*
X2834724Y2455693D01*
Y2464651D01*
G01X2840149Y2452151D02*
Y2464651D01*
X2847279Y2452151D01*
Y2464651D01*
G01X2854254D02*
X2857974D01*
G01X2856114D02*
Y2452151D01*
G01X2854254D02*
X2857974D01*
G01X2868514Y2464651D02*
Y2452151D01*
G01X2864949Y2464651D02*
X2872079D01*
G01X2877659Y2453817D02*
X2878899Y2452776D01*
X2880294Y2452151D01*
X2881534D01*
X2882774Y2452776D01*
X2883704Y2453817D01*
X2884169Y2455276D01*
X2883859Y2456734D01*
X2883084Y2457984D01*
X2881689Y2458818D01*
X2879829Y2459234D01*
X2878744Y2460068D01*
X2878279Y2461526D01*
X2878589Y2462984D01*
X2879364Y2464026D01*
X2880449Y2464651D01*
X2881534D01*
X2882619Y2464234D01*
X2883549Y2463193D01*
G01X2901839Y2452151D02*
X2905714Y2464651D01*
X2909589Y2452151D01*
G01X2908194Y2456526D02*
X2903234D01*
G01X2915014Y2452151D02*
Y2464651D01*
X2918889D01*
X2920129Y2464026D01*
X2920904Y2463193D01*
X2921214Y2461526D01*
X2920904Y2459859D01*
X2919974Y2458818D01*
X2918889Y2458193D01*
X2915014D01*
G01X2918889D02*
X2921214Y2452151D01*
G01X2933614D02*
X2927414D01*
Y2464651D01*
X2933614D01*
G01X2931134Y2458609D02*
X2927414D01*
G01X2953454Y2464651D02*
X2957174D01*
G01X2955314D02*
Y2452151D01*
G01X2953454D02*
X2957174D01*
G01X2964149D02*
Y2464651D01*
X2971279Y2452151D01*
Y2464651D01*
G01X2988484Y2452151D02*
Y2464651D01*
X2992514Y2454234D01*
X2996544Y2464651D01*
Y2452151D01*
G01X3003054Y2464651D02*
X3006774D01*
G01X3004914D02*
Y2452151D01*
G01X3003054D02*
X3006774D01*
G01X3014214Y2464651D02*
Y2452151D01*
X3020414D01*
G01X3026459Y2453817D02*
X3027699Y2452776D01*
X3029094Y2452151D01*
X3030334D01*
X3031574Y2452776D01*
X3032504Y2453817D01*
X3032969Y2455276D01*
X3032659Y2456734D01*
X3031884Y2457984D01*
X3030489Y2458818D01*
X3028629Y2459234D01*
X3027544Y2460068D01*
X3027079Y2461526D01*
X3027389Y2462984D01*
X3028164Y2464026D01*
X3029249Y2464651D01*
X3030334D01*
X3031419Y2464234D01*
X3032349Y2463193D01*
G01X2771881Y2844130D02*
X2772501Y2844755D01*
X2772966Y2845796D01*
X2773276Y2847255D01*
X2772966Y2848505D01*
X2772346Y2849338D01*
X2771261Y2849963D01*
X2767076D01*
Y2837463D01*
X2772191D01*
X2773276Y2838296D01*
X2773896Y2839546D01*
X2774206Y2841005D01*
X2773896Y2842463D01*
X2772966Y2843713D01*
X2771881Y2844130D01*
X2767076D01*
G01X2779166Y2837463D02*
X2783041Y2849963D01*
X2786916Y2837463D01*
G01X2785521Y2841838D02*
X2780561D01*
G01X2798851Y2848921D02*
X2797921Y2849546D01*
X2796836Y2849963D01*
X2795596D01*
X2794201Y2849338D01*
X2793116Y2848296D01*
X2792341Y2847046D01*
X2791721Y2844963D01*
X2791566Y2843088D01*
X2791876Y2841213D01*
X2792341Y2839963D01*
X2793271Y2838713D01*
X2794356Y2837880D01*
X2795441Y2837463D01*
X2796526D01*
X2797611Y2837880D01*
X2798541Y2838504D01*
X2799316Y2839338D01*
G01X2804431Y2837463D02*
Y2849963D01*
G01X2810321D02*
X2804431Y2842254D01*
G01X2811251Y2837463D02*
X2807066Y2845796D01*
G01X2816831Y2837463D02*
Y2849963D01*
X2819931D01*
X2821171Y2849338D01*
X2822101Y2848505D01*
X2822876Y2847255D01*
X2823496Y2845796D01*
X2823651Y2843713D01*
X2823496Y2841630D01*
X2822876Y2840171D01*
X2822101Y2838921D01*
X2821171Y2838088D01*
X2819931Y2837463D01*
X2816831D01*
G01X2829541D02*
Y2849963D01*
X2833416D01*
X2834656Y2849338D01*
X2835431Y2848505D01*
X2835741Y2846838D01*
X2835431Y2845171D01*
X2834501Y2844130D01*
X2833416Y2843505D01*
X2829541D01*
G01X2833416D02*
X2835741Y2837463D01*
G01X2843181Y2849963D02*
X2846901D01*
G01X2845041D02*
Y2837463D01*
G01X2843181D02*
X2846901D01*
G01X2854341Y2849963D02*
Y2837463D01*
X2860541D01*
G01X2866741Y2849963D02*
Y2837463D01*
X2872941D01*
G01X2882241Y2837046D02*
X2881931Y2837255D01*
Y2837671D01*
X2882241Y2837880D01*
X2882551Y2837671D01*
Y2837255D01*
X2882241Y2837046D01*
G01Y2842671D02*
X2881931Y2842880D01*
Y2843296D01*
X2882241Y2843505D01*
X2882551Y2843296D01*
Y2842880D01*
X2882241Y2842671D01*
G01X2908281Y2844130D02*
X2908901Y2844755D01*
X2909366Y2845796D01*
X2909676Y2847255D01*
X2909366Y2848505D01*
X2908746Y2849338D01*
X2907661Y2849963D01*
X2903476D01*
Y2837463D01*
X2908591D01*
X2909676Y2838296D01*
X2910296Y2839546D01*
X2910606Y2841005D01*
X2910296Y2842463D01*
X2909366Y2843713D01*
X2908281Y2844130D01*
X2903476D01*
G01X2919441Y2837463D02*
X2918201Y2837671D01*
X2917116Y2838504D01*
X2916186Y2839755D01*
X2915566Y2841213D01*
X2915256Y2842880D01*
Y2844546D01*
X2915566Y2846213D01*
X2916186Y2847671D01*
X2917116Y2848921D01*
X2918201Y2849755D01*
X2919441Y2849963D01*
X2920681Y2849755D01*
X2921766Y2848921D01*
X2922696Y2847671D01*
X2923316Y2846213D01*
X2923626Y2844546D01*
Y2842880D01*
X2923316Y2841213D01*
X2922696Y2839755D01*
X2921766Y2838504D01*
X2920681Y2837671D01*
X2919441Y2837463D01*
G01X2931841Y2849963D02*
Y2837463D01*
G01X2928276Y2849963D02*
X2935406D01*
G01X2944241D02*
Y2837463D01*
G01X2940676Y2849963D02*
X2947806D01*
G01X2956641Y2837463D02*
X2955401Y2837671D01*
X2954316Y2838504D01*
X2953386Y2839755D01*
X2952766Y2841213D01*
X2952456Y2842880D01*
Y2844546D01*
X2952766Y2846213D01*
X2953386Y2847671D01*
X2954316Y2848921D01*
X2955401Y2849755D01*
X2956641Y2849963D01*
X2957881Y2849755D01*
X2958966Y2848921D01*
X2959896Y2847671D01*
X2960516Y2846213D01*
X2960826Y2844546D01*
Y2842880D01*
X2960516Y2841213D01*
X2959896Y2839755D01*
X2958966Y2838504D01*
X2957881Y2837671D01*
X2956641Y2837463D01*
G01X2965011D02*
Y2849963D01*
X2969041Y2839546D01*
X2973071Y2849963D01*
Y2837463D01*
G01X2993841Y2849963D02*
Y2837463D01*
G01X2991671Y2845796D02*
X2996011D01*
G01X3006241Y2837463D02*
X3005311Y2837671D01*
X3004381Y2838504D01*
X3003761Y2839963D01*
X3003451Y2841630D01*
X3003761Y2843296D01*
X3004381Y2844755D01*
X3005311Y2845588D01*
X3006241Y2845796D01*
X3007171Y2845588D01*
X3008101Y2844755D01*
X3008721Y2843296D01*
X3008876Y2841630D01*
X3008721Y2839963D01*
X3008101Y2838504D01*
X3007171Y2837671D01*
X3006241Y2837463D01*
G01X3031971Y2843713D02*
X3035071D01*
Y2839963D01*
X3034141Y2838713D01*
X3033056Y2837880D01*
X3031506Y2837463D01*
X3029956Y2837880D01*
X3028871Y2838713D01*
X3027941Y2839963D01*
X3027321Y2841421D01*
X3027011Y2843088D01*
Y2844546D01*
X3027321Y2845796D01*
X3027941Y2847255D01*
X3028871Y2848505D01*
X3029801Y2849338D01*
X3031041Y2849963D01*
X3032126D01*
X3033366Y2849546D01*
X3034296Y2848713D01*
G01X3039876Y2837463D02*
Y2849963D01*
X3047006Y2837463D01*
Y2849963D01*
G01X3052431Y2837463D02*
Y2849963D01*
X3055531D01*
X3056771Y2849338D01*
X3057701Y2848505D01*
X3058476Y2847255D01*
X3059096Y2845796D01*
X3059251Y2843713D01*
X3059096Y2841630D01*
X3058476Y2840171D01*
X3057701Y2838921D01*
X3056771Y2838088D01*
X3055531Y2837463D01*
X3052431D01*
G01X3067931D02*
X3068241Y2840171D01*
X3068706Y2842463D01*
X3069326Y2844546D01*
X3070101Y2846838D01*
X3071341Y2849963D01*
X3065141D01*
G01X2792470Y2099483D02*
X2793090Y2100108D01*
X2793555Y2101149D01*
X2793865Y2102608D01*
X2793555Y2103858D01*
X2792935Y2104691D01*
X2791850Y2105316D01*
X2787665D01*
Y2092816D01*
X2792780D01*
X2793865Y2093649D01*
X2794485Y2094899D01*
X2794795Y2096358D01*
X2794485Y2097816D01*
X2793555Y2099066D01*
X2792470Y2099483D01*
X2787665D01*
G01X2799755Y2092816D02*
X2803630Y2105316D01*
X2807505Y2092816D01*
G01X2806110Y2097191D02*
X2801150D01*
G01X2819440Y2104274D02*
X2818510Y2104899D01*
X2817425Y2105316D01*
X2816185D01*
X2814790Y2104691D01*
X2813705Y2103649D01*
X2812930Y2102399D01*
X2812310Y2100316D01*
X2812155Y2098441D01*
X2812465Y2096566D01*
X2812930Y2095316D01*
X2813860Y2094066D01*
X2814945Y2093233D01*
X2816030Y2092816D01*
X2817115D01*
X2818200Y2093233D01*
X2819130Y2093857D01*
X2819905Y2094691D01*
G01X2825020Y2092816D02*
Y2105316D01*
G01X2830910D02*
X2825020Y2097607D01*
G01X2831840Y2092816D02*
X2827655Y2101149D01*
G01X2837420Y2092816D02*
Y2105316D01*
X2840520D01*
X2841760Y2104691D01*
X2842690Y2103858D01*
X2843465Y2102608D01*
X2844085Y2101149D01*
X2844240Y2099066D01*
X2844085Y2096983D01*
X2843465Y2095524D01*
X2842690Y2094274D01*
X2841760Y2093441D01*
X2840520Y2092816D01*
X2837420D01*
G01X2850130D02*
Y2105316D01*
X2854005D01*
X2855245Y2104691D01*
X2856020Y2103858D01*
X2856330Y2102191D01*
X2856020Y2100524D01*
X2855090Y2099483D01*
X2854005Y2098858D01*
X2850130D01*
G01X2854005D02*
X2856330Y2092816D01*
G01X2863770Y2105316D02*
X2867490D01*
G01X2865630D02*
Y2092816D01*
G01X2863770D02*
X2867490D01*
G01X2874930Y2105316D02*
Y2092816D01*
X2881130D01*
G01X2887330Y2105316D02*
Y2092816D01*
X2893530D01*
G01X2902830Y2092399D02*
X2902520Y2092608D01*
Y2093024D01*
X2902830Y2093233D01*
X2903140Y2093024D01*
Y2092608D01*
X2902830Y2092399D01*
G01Y2098024D02*
X2902520Y2098233D01*
Y2098649D01*
X2902830Y2098858D01*
X2903140Y2098649D01*
Y2098233D01*
X2902830Y2098024D01*
G01X2928870Y2099483D02*
X2929490Y2100108D01*
X2929955Y2101149D01*
X2930265Y2102608D01*
X2929955Y2103858D01*
X2929335Y2104691D01*
X2928250Y2105316D01*
X2924065D01*
Y2092816D01*
X2929180D01*
X2930265Y2093649D01*
X2930885Y2094899D01*
X2931195Y2096358D01*
X2930885Y2097816D01*
X2929955Y2099066D01*
X2928870Y2099483D01*
X2924065D01*
G01X2940030Y2092816D02*
X2938790Y2093024D01*
X2937705Y2093857D01*
X2936775Y2095108D01*
X2936155Y2096566D01*
X2935845Y2098233D01*
Y2099899D01*
X2936155Y2101566D01*
X2936775Y2103024D01*
X2937705Y2104274D01*
X2938790Y2105108D01*
X2940030Y2105316D01*
X2941270Y2105108D01*
X2942355Y2104274D01*
X2943285Y2103024D01*
X2943905Y2101566D01*
X2944215Y2099899D01*
Y2098233D01*
X2943905Y2096566D01*
X2943285Y2095108D01*
X2942355Y2093857D01*
X2941270Y2093024D01*
X2940030Y2092816D01*
G01X2952430Y2105316D02*
Y2092816D01*
G01X2948865Y2105316D02*
X2955995D01*
G01X2964830D02*
Y2092816D01*
G01X2961265Y2105316D02*
X2968395D01*
G01X2977230Y2092816D02*
X2975990Y2093024D01*
X2974905Y2093857D01*
X2973975Y2095108D01*
X2973355Y2096566D01*
X2973045Y2098233D01*
Y2099899D01*
X2973355Y2101566D01*
X2973975Y2103024D01*
X2974905Y2104274D01*
X2975990Y2105108D01*
X2977230Y2105316D01*
X2978470Y2105108D01*
X2979555Y2104274D01*
X2980485Y2103024D01*
X2981105Y2101566D01*
X2981415Y2099899D01*
Y2098233D01*
X2981105Y2096566D01*
X2980485Y2095108D01*
X2979555Y2093857D01*
X2978470Y2093024D01*
X2977230Y2092816D01*
G01X2985600D02*
Y2105316D01*
X2989630Y2094899D01*
X2993660Y2105316D01*
Y2092816D01*
G01X3014430Y2105316D02*
Y2092816D01*
G01X3012260Y2101149D02*
X3016600D01*
G01X3026830Y2092816D02*
X3025900Y2093024D01*
X3024970Y2093857D01*
X3024350Y2095316D01*
X3024040Y2096983D01*
X3024350Y2098649D01*
X3024970Y2100108D01*
X3025900Y2100941D01*
X3026830Y2101149D01*
X3027760Y2100941D01*
X3028690Y2100108D01*
X3029310Y2098649D01*
X3029465Y2096983D01*
X3029310Y2095316D01*
X3028690Y2093857D01*
X3027760Y2093024D01*
X3026830Y2092816D01*
G01X3052560Y2099066D02*
X3055660D01*
Y2095316D01*
X3054730Y2094066D01*
X3053645Y2093233D01*
X3052095Y2092816D01*
X3050545Y2093233D01*
X3049460Y2094066D01*
X3048530Y2095316D01*
X3047910Y2096774D01*
X3047600Y2098441D01*
Y2099899D01*
X3047910Y2101149D01*
X3048530Y2102608D01*
X3049460Y2103858D01*
X3050390Y2104691D01*
X3051630Y2105316D01*
X3052715D01*
X3053955Y2104899D01*
X3054885Y2104066D01*
G01X3060465Y2092816D02*
Y2105316D01*
X3067595Y2092816D01*
Y2105316D01*
G01X3073020Y2092816D02*
Y2105316D01*
X3076120D01*
X3077360Y2104691D01*
X3078290Y2103858D01*
X3079065Y2102608D01*
X3079685Y2101149D01*
X3079840Y2099066D01*
X3079685Y2096983D01*
X3079065Y2095524D01*
X3078290Y2094274D01*
X3077360Y2093441D01*
X3076120Y2092816D01*
X3073020D01*
G01X3090690D02*
Y2105316D01*
X3084955Y2096358D01*
X3092705D01*
G01X2794734Y2427151D02*
Y2439651D01*
X2798764Y2429234D01*
X2802794Y2439651D01*
Y2427151D01*
G01X2807599D02*
Y2439651D01*
X2814729Y2427151D01*
Y2439651D01*
G01X2826974Y2438609D02*
X2826044Y2439234D01*
X2824959Y2439651D01*
X2823719D01*
X2822324Y2439026D01*
X2821239Y2437984D01*
X2820464Y2436734D01*
X2819844Y2434651D01*
X2819689Y2432776D01*
X2819999Y2430901D01*
X2820464Y2429651D01*
X2821394Y2428401D01*
X2822479Y2427568D01*
X2823564Y2427151D01*
X2824649D01*
X2825734Y2427568D01*
X2826664Y2428192D01*
X2827439Y2429026D01*
G01X2831314Y2422984D02*
X2840614D01*
G01X2845264Y2439651D02*
Y2427151D01*
X2851464D01*
G01X2856889D02*
X2860764Y2439651D01*
X2864639Y2427151D01*
G01X2863244Y2431526D02*
X2858284D01*
G01X2873164Y2427151D02*
Y2432776D01*
X2870064Y2439651D01*
G01X2876264D02*
X2873164Y2432776D01*
G01X2888664Y2427151D02*
X2882464D01*
Y2439651D01*
X2888664D01*
G01X2886184Y2433609D02*
X2882464D01*
G01X2894864Y2427151D02*
Y2439651D01*
X2898739D01*
X2899979Y2439026D01*
X2900754Y2438193D01*
X2901064Y2436526D01*
X2900754Y2434859D01*
X2899824Y2433818D01*
X2898739Y2433193D01*
X2894864D01*
G01X2898739D02*
X2901064Y2427151D01*
G01X2791566Y2812463D02*
X2795441Y2824963D01*
X2799316Y2812463D01*
G01X2797921Y2816838D02*
X2792961D01*
G01X2804741Y2824963D02*
Y2812463D01*
X2810941D01*
G01X2817141Y2824963D02*
Y2812463D01*
X2823341D01*
G01X2841631Y2824963D02*
Y2816005D01*
X2842251Y2814129D01*
X2843491Y2812880D01*
X2845041Y2812463D01*
X2846591Y2812880D01*
X2847831Y2814129D01*
X2848451Y2816005D01*
Y2824963D01*
G01X2853876Y2812463D02*
Y2824963D01*
X2861006Y2812463D01*
Y2824963D01*
G01X2867981D02*
X2871701D01*
G01X2869841D02*
Y2812463D01*
G01X2867981D02*
X2871701D01*
G01X2882241Y2824963D02*
Y2812463D01*
G01X2878676Y2824963D02*
X2885806D01*
G01X2891386Y2814129D02*
X2892626Y2813088D01*
X2894021Y2812463D01*
X2895261D01*
X2896501Y2813088D01*
X2897431Y2814129D01*
X2897896Y2815588D01*
X2897586Y2817046D01*
X2896811Y2818296D01*
X2895416Y2819130D01*
X2893556Y2819546D01*
X2892471Y2820380D01*
X2892006Y2821838D01*
X2892316Y2823296D01*
X2893091Y2824338D01*
X2894176Y2824963D01*
X2895261D01*
X2896346Y2824546D01*
X2897276Y2823505D01*
G01X2915566Y2812463D02*
X2919441Y2824963D01*
X2923316Y2812463D01*
G01X2921921Y2816838D02*
X2916961D01*
G01X2928741Y2812463D02*
Y2824963D01*
X2932616D01*
X2933856Y2824338D01*
X2934631Y2823505D01*
X2934941Y2821838D01*
X2934631Y2820171D01*
X2933701Y2819130D01*
X2932616Y2818505D01*
X2928741D01*
G01X2932616D02*
X2934941Y2812463D01*
G01X2947341D02*
X2941141D01*
Y2824963D01*
X2947341D01*
G01X2944861Y2818921D02*
X2941141D01*
G01X2967181Y2824963D02*
X2970901D01*
G01X2969041D02*
Y2812463D01*
G01X2967181D02*
X2970901D01*
G01X2977876D02*
Y2824963D01*
X2985006Y2812463D01*
Y2824963D01*
G01X3002211Y2812463D02*
Y2824963D01*
X3006241Y2814546D01*
X3010271Y2824963D01*
Y2812463D01*
G01X3016781Y2824963D02*
X3020501D01*
G01X3018641D02*
Y2812463D01*
G01X3016781D02*
X3020501D01*
G01X3027941Y2824963D02*
Y2812463D01*
X3034141D01*
G01X3040186Y2814129D02*
X3041426Y2813088D01*
X3042821Y2812463D01*
X3044061D01*
X3045301Y2813088D01*
X3046231Y2814129D01*
X3046696Y2815588D01*
X3046386Y2817046D01*
X3045611Y2818296D01*
X3044216Y2819130D01*
X3042356Y2819546D01*
X3041271Y2820380D01*
X3040806Y2821838D01*
X3041116Y2823296D01*
X3041891Y2824338D01*
X3042976Y2824963D01*
X3044061D01*
X3045146Y2824546D01*
X3046076Y2823505D01*
G01X2812155Y2067816D02*
X2816030Y2080316D01*
X2819905Y2067816D01*
G01X2818510Y2072191D02*
X2813550D01*
G01X2825330Y2080316D02*
Y2067816D01*
X2831530D01*
G01X2837730Y2080316D02*
Y2067816D01*
X2843930D01*
G01X2862220Y2080316D02*
Y2071358D01*
X2862840Y2069482D01*
X2864080Y2068233D01*
X2865630Y2067816D01*
X2867180Y2068233D01*
X2868420Y2069482D01*
X2869040Y2071358D01*
Y2080316D01*
G01X2874465Y2067816D02*
Y2080316D01*
X2881595Y2067816D01*
Y2080316D01*
G01X2888570D02*
X2892290D01*
G01X2890430D02*
Y2067816D01*
G01X2888570D02*
X2892290D01*
G01X2902830Y2080316D02*
Y2067816D01*
G01X2899265Y2080316D02*
X2906395D01*
G01X2911975Y2069482D02*
X2913215Y2068441D01*
X2914610Y2067816D01*
X2915850D01*
X2917090Y2068441D01*
X2918020Y2069482D01*
X2918485Y2070941D01*
X2918175Y2072399D01*
X2917400Y2073649D01*
X2916005Y2074483D01*
X2914145Y2074899D01*
X2913060Y2075733D01*
X2912595Y2077191D01*
X2912905Y2078649D01*
X2913680Y2079691D01*
X2914765Y2080316D01*
X2915850D01*
X2916935Y2079899D01*
X2917865Y2078858D01*
G01X2936155Y2067816D02*
X2940030Y2080316D01*
X2943905Y2067816D01*
G01X2942510Y2072191D02*
X2937550D01*
G01X2949330Y2067816D02*
Y2080316D01*
X2953205D01*
X2954445Y2079691D01*
X2955220Y2078858D01*
X2955530Y2077191D01*
X2955220Y2075524D01*
X2954290Y2074483D01*
X2953205Y2073858D01*
X2949330D01*
G01X2953205D02*
X2955530Y2067816D01*
G01X2967930D02*
X2961730D01*
Y2080316D01*
X2967930D01*
G01X2965450Y2074274D02*
X2961730D01*
G01X2987770Y2080316D02*
X2991490D01*
G01X2989630D02*
Y2067816D01*
G01X2987770D02*
X2991490D01*
G01X2998465D02*
Y2080316D01*
X3005595Y2067816D01*
Y2080316D01*
G01X3022800Y2067816D02*
Y2080316D01*
X3026830Y2069899D01*
X3030860Y2080316D01*
Y2067816D01*
G01X3037370Y2080316D02*
X3041090D01*
G01X3039230D02*
Y2067816D01*
G01X3037370D02*
X3041090D01*
G01X3048530Y2080316D02*
Y2067816D01*
X3054730D01*
G01X3060775Y2069482D02*
X3062015Y2068441D01*
X3063410Y2067816D01*
X3064650D01*
X3065890Y2068441D01*
X3066820Y2069482D01*
X3067285Y2070941D01*
X3066975Y2072399D01*
X3066200Y2073649D01*
X3064805Y2074483D01*
X3062945Y2074899D01*
X3061860Y2075733D01*
X3061395Y2077191D01*
X3061705Y2078649D01*
X3062480Y2079691D01*
X3063565Y2080316D01*
X3064650D01*
X3065735Y2079899D01*
X3066665Y2078858D01*
G01X2808461Y2787463D02*
Y2799963D01*
X2812491Y2789546D01*
X2816521Y2799963D01*
Y2787463D01*
G01X2821326D02*
Y2799963D01*
X2828456Y2787463D01*
Y2799963D01*
G01X2840701Y2798921D02*
X2839771Y2799546D01*
X2838686Y2799963D01*
X2837446D01*
X2836051Y2799338D01*
X2834966Y2798296D01*
X2834191Y2797046D01*
X2833571Y2794963D01*
X2833416Y2793088D01*
X2833726Y2791213D01*
X2834191Y2789963D01*
X2835121Y2788713D01*
X2836206Y2787880D01*
X2837291Y2787463D01*
X2838376D01*
X2839461Y2787880D01*
X2840391Y2788504D01*
X2841166Y2789338D01*
G01X2845041Y2783296D02*
X2854341D01*
G01X2858991Y2799963D02*
Y2787463D01*
X2865191D01*
G01X2870616D02*
X2874491Y2799963D01*
X2878366Y2787463D01*
G01X2876971Y2791838D02*
X2872011D01*
G01X2886891Y2787463D02*
Y2793088D01*
X2883791Y2799963D01*
G01X2889991D02*
X2886891Y2793088D01*
G01X2902391Y2787463D02*
X2896191D01*
Y2799963D01*
X2902391D01*
G01X2899911Y2793921D02*
X2896191D01*
G01X2908591Y2787463D02*
Y2799963D01*
X2912466D01*
X2913706Y2799338D01*
X2914481Y2798505D01*
X2914791Y2796838D01*
X2914481Y2795171D01*
X2913551Y2794130D01*
X2912466Y2793505D01*
X2908591D01*
G01X2912466D02*
X2914791Y2787463D01*
G01X2826786Y1385720D02*
X2827406Y1386345D01*
X2827871Y1387386D01*
X2828181Y1388845D01*
X2827871Y1390095D01*
X2827251Y1390928D01*
X2826166Y1391553D01*
X2821981D01*
Y1379053D01*
X2827096D01*
X2828181Y1379886D01*
X2828801Y1381136D01*
X2829111Y1382595D01*
X2828801Y1384053D01*
X2827871Y1385303D01*
X2826786Y1385720D01*
X2821981D01*
G01X2834071Y1379053D02*
X2837946Y1391553D01*
X2841821Y1379053D01*
G01X2840426Y1383428D02*
X2835466D01*
G01X2853756Y1390511D02*
X2852826Y1391136D01*
X2851741Y1391553D01*
X2850501D01*
X2849106Y1390928D01*
X2848021Y1389886D01*
X2847246Y1388636D01*
X2846626Y1386553D01*
X2846471Y1384678D01*
X2846781Y1382803D01*
X2847246Y1381553D01*
X2848176Y1380303D01*
X2849261Y1379470D01*
X2850346Y1379053D01*
X2851431D01*
X2852516Y1379470D01*
X2853446Y1380094D01*
X2854221Y1380928D01*
G01X2859336Y1379053D02*
Y1391553D01*
G01X2865226D02*
X2859336Y1383844D01*
G01X2866156Y1379053D02*
X2861971Y1387386D01*
G01X2871736Y1379053D02*
Y1391553D01*
X2874836D01*
X2876076Y1390928D01*
X2877006Y1390095D01*
X2877781Y1388845D01*
X2878401Y1387386D01*
X2878556Y1385303D01*
X2878401Y1383220D01*
X2877781Y1381761D01*
X2877006Y1380511D01*
X2876076Y1379678D01*
X2874836Y1379053D01*
X2871736D01*
G01X2884446D02*
Y1391553D01*
X2888321D01*
X2889561Y1390928D01*
X2890336Y1390095D01*
X2890646Y1388428D01*
X2890336Y1386761D01*
X2889406Y1385720D01*
X2888321Y1385095D01*
X2884446D01*
G01X2888321D02*
X2890646Y1379053D01*
G01X2898086Y1391553D02*
X2901806D01*
G01X2899946D02*
Y1379053D01*
G01X2898086D02*
X2901806D01*
G01X2909246Y1391553D02*
Y1379053D01*
X2915446D01*
G01X2921646Y1391553D02*
Y1379053D01*
X2927846D01*
G01X2937146Y1378636D02*
X2936836Y1378845D01*
Y1379261D01*
X2937146Y1379470D01*
X2937456Y1379261D01*
Y1378845D01*
X2937146Y1378636D01*
G01Y1384261D02*
X2936836Y1384470D01*
Y1384886D01*
X2937146Y1385095D01*
X2937456Y1384886D01*
Y1384470D01*
X2937146Y1384261D01*
G01X2963186Y1385720D02*
X2963806Y1386345D01*
X2964271Y1387386D01*
X2964581Y1388845D01*
X2964271Y1390095D01*
X2963651Y1390928D01*
X2962566Y1391553D01*
X2958381D01*
Y1379053D01*
X2963496D01*
X2964581Y1379886D01*
X2965201Y1381136D01*
X2965511Y1382595D01*
X2965201Y1384053D01*
X2964271Y1385303D01*
X2963186Y1385720D01*
X2958381D01*
G01X2974346Y1379053D02*
X2973106Y1379261D01*
X2972021Y1380094D01*
X2971091Y1381345D01*
X2970471Y1382803D01*
X2970161Y1384470D01*
Y1386136D01*
X2970471Y1387803D01*
X2971091Y1389261D01*
X2972021Y1390511D01*
X2973106Y1391345D01*
X2974346Y1391553D01*
X2975586Y1391345D01*
X2976671Y1390511D01*
X2977601Y1389261D01*
X2978221Y1387803D01*
X2978531Y1386136D01*
Y1384470D01*
X2978221Y1382803D01*
X2977601Y1381345D01*
X2976671Y1380094D01*
X2975586Y1379261D01*
X2974346Y1379053D01*
G01X2986746Y1391553D02*
Y1379053D01*
G01X2983181Y1391553D02*
X2990311D01*
G01X2999146D02*
Y1379053D01*
G01X2995581Y1391553D02*
X3002711D01*
G01X3011546Y1379053D02*
X3010306Y1379261D01*
X3009221Y1380094D01*
X3008291Y1381345D01*
X3007671Y1382803D01*
X3007361Y1384470D01*
Y1386136D01*
X3007671Y1387803D01*
X3008291Y1389261D01*
X3009221Y1390511D01*
X3010306Y1391345D01*
X3011546Y1391553D01*
X3012786Y1391345D01*
X3013871Y1390511D01*
X3014801Y1389261D01*
X3015421Y1387803D01*
X3015731Y1386136D01*
Y1384470D01*
X3015421Y1382803D01*
X3014801Y1381345D01*
X3013871Y1380094D01*
X3012786Y1379261D01*
X3011546Y1379053D01*
G01X3019916D02*
Y1391553D01*
X3023946Y1381136D01*
X3027976Y1391553D01*
Y1379053D01*
G01X3048746Y1391553D02*
Y1379053D01*
G01X3046576Y1387386D02*
X3050916D01*
G01X3061146Y1379053D02*
X3060216Y1379261D01*
X3059286Y1380094D01*
X3058666Y1381553D01*
X3058356Y1383220D01*
X3058666Y1384886D01*
X3059286Y1386345D01*
X3060216Y1387178D01*
X3061146Y1387386D01*
X3062076Y1387178D01*
X3063006Y1386345D01*
X3063626Y1384886D01*
X3063781Y1383220D01*
X3063626Y1381553D01*
X3063006Y1380094D01*
X3062076Y1379261D01*
X3061146Y1379053D01*
G01X3086876Y1385303D02*
X3089976D01*
Y1381553D01*
X3089046Y1380303D01*
X3087961Y1379470D01*
X3086411Y1379053D01*
X3084861Y1379470D01*
X3083776Y1380303D01*
X3082846Y1381553D01*
X3082226Y1383011D01*
X3081916Y1384678D01*
Y1386136D01*
X3082226Y1387386D01*
X3082846Y1388845D01*
X3083776Y1390095D01*
X3084706Y1390928D01*
X3085946Y1391553D01*
X3087031D01*
X3088271Y1391136D01*
X3089201Y1390303D01*
G01X3094781Y1379053D02*
Y1391553D01*
X3101911Y1379053D01*
Y1391553D01*
G01X3107336Y1379053D02*
Y1391553D01*
X3110436D01*
X3111676Y1390928D01*
X3112606Y1390095D01*
X3113381Y1388845D01*
X3114001Y1387386D01*
X3114156Y1385303D01*
X3114001Y1383220D01*
X3113381Y1381761D01*
X3112606Y1380511D01*
X3111676Y1379678D01*
X3110436Y1379053D01*
X3107336D01*
G01X3119736Y1380928D02*
X3120666Y1379886D01*
X3121751Y1379261D01*
X3123146Y1379053D01*
X3124541Y1379470D01*
X3125626Y1380303D01*
X3126401Y1381761D01*
X3126556Y1383428D01*
X3126246Y1385095D01*
X3125471Y1386136D01*
X3124386Y1386970D01*
X3123301Y1387178D01*
X3122216Y1386970D01*
X3120821Y1386136D01*
X3121286Y1391553D01*
X3125471D01*
G01X2826786Y1735738D02*
X2827406Y1736363D01*
X2827871Y1737404D01*
X2828181Y1738863D01*
X2827871Y1740113D01*
X2827251Y1740946D01*
X2826166Y1741571D01*
X2821981D01*
Y1729071D01*
X2827096D01*
X2828181Y1729904D01*
X2828801Y1731154D01*
X2829111Y1732613D01*
X2828801Y1734071D01*
X2827871Y1735321D01*
X2826786Y1735738D01*
X2821981D01*
G01X2834071Y1729071D02*
X2837946Y1741571D01*
X2841821Y1729071D01*
G01X2840426Y1733446D02*
X2835466D01*
G01X2853756Y1740529D02*
X2852826Y1741154D01*
X2851741Y1741571D01*
X2850501D01*
X2849106Y1740946D01*
X2848021Y1739904D01*
X2847246Y1738654D01*
X2846626Y1736571D01*
X2846471Y1734696D01*
X2846781Y1732821D01*
X2847246Y1731571D01*
X2848176Y1730321D01*
X2849261Y1729488D01*
X2850346Y1729071D01*
X2851431D01*
X2852516Y1729488D01*
X2853446Y1730112D01*
X2854221Y1730946D01*
G01X2859336Y1729071D02*
Y1741571D01*
G01X2865226D02*
X2859336Y1733862D01*
G01X2866156Y1729071D02*
X2861971Y1737404D01*
G01X2871736Y1729071D02*
Y1741571D01*
X2874836D01*
X2876076Y1740946D01*
X2877006Y1740113D01*
X2877781Y1738863D01*
X2878401Y1737404D01*
X2878556Y1735321D01*
X2878401Y1733238D01*
X2877781Y1731779D01*
X2877006Y1730529D01*
X2876076Y1729696D01*
X2874836Y1729071D01*
X2871736D01*
G01X2884446D02*
Y1741571D01*
X2888321D01*
X2889561Y1740946D01*
X2890336Y1740113D01*
X2890646Y1738446D01*
X2890336Y1736779D01*
X2889406Y1735738D01*
X2888321Y1735113D01*
X2884446D01*
G01X2888321D02*
X2890646Y1729071D01*
G01X2898086Y1741571D02*
X2901806D01*
G01X2899946D02*
Y1729071D01*
G01X2898086D02*
X2901806D01*
G01X2909246Y1741571D02*
Y1729071D01*
X2915446D01*
G01X2921646Y1741571D02*
Y1729071D01*
X2927846D01*
G01X2937146Y1728654D02*
X2936836Y1728863D01*
Y1729279D01*
X2937146Y1729488D01*
X2937456Y1729279D01*
Y1728863D01*
X2937146Y1728654D01*
G01Y1734279D02*
X2936836Y1734488D01*
Y1734904D01*
X2937146Y1735113D01*
X2937456Y1734904D01*
Y1734488D01*
X2937146Y1734279D01*
G01X2963186Y1735738D02*
X2963806Y1736363D01*
X2964271Y1737404D01*
X2964581Y1738863D01*
X2964271Y1740113D01*
X2963651Y1740946D01*
X2962566Y1741571D01*
X2958381D01*
Y1729071D01*
X2963496D01*
X2964581Y1729904D01*
X2965201Y1731154D01*
X2965511Y1732613D01*
X2965201Y1734071D01*
X2964271Y1735321D01*
X2963186Y1735738D01*
X2958381D01*
G01X2974346Y1729071D02*
X2973106Y1729279D01*
X2972021Y1730112D01*
X2971091Y1731363D01*
X2970471Y1732821D01*
X2970161Y1734488D01*
Y1736154D01*
X2970471Y1737821D01*
X2971091Y1739279D01*
X2972021Y1740529D01*
X2973106Y1741363D01*
X2974346Y1741571D01*
X2975586Y1741363D01*
X2976671Y1740529D01*
X2977601Y1739279D01*
X2978221Y1737821D01*
X2978531Y1736154D01*
Y1734488D01*
X2978221Y1732821D01*
X2977601Y1731363D01*
X2976671Y1730112D01*
X2975586Y1729279D01*
X2974346Y1729071D01*
G01X2986746Y1741571D02*
Y1729071D01*
G01X2983181Y1741571D02*
X2990311D01*
G01X2999146D02*
Y1729071D01*
G01X2995581Y1741571D02*
X3002711D01*
G01X3011546Y1729071D02*
X3010306Y1729279D01*
X3009221Y1730112D01*
X3008291Y1731363D01*
X3007671Y1732821D01*
X3007361Y1734488D01*
Y1736154D01*
X3007671Y1737821D01*
X3008291Y1739279D01*
X3009221Y1740529D01*
X3010306Y1741363D01*
X3011546Y1741571D01*
X3012786Y1741363D01*
X3013871Y1740529D01*
X3014801Y1739279D01*
X3015421Y1737821D01*
X3015731Y1736154D01*
Y1734488D01*
X3015421Y1732821D01*
X3014801Y1731363D01*
X3013871Y1730112D01*
X3012786Y1729279D01*
X3011546Y1729071D01*
G01X3019916D02*
Y1741571D01*
X3023946Y1731154D01*
X3027976Y1741571D01*
Y1729071D01*
G01X3048746Y1741571D02*
Y1729071D01*
G01X3046576Y1737404D02*
X3050916D01*
G01X3061146Y1729071D02*
X3060216Y1729279D01*
X3059286Y1730112D01*
X3058666Y1731571D01*
X3058356Y1733238D01*
X3058666Y1734904D01*
X3059286Y1736363D01*
X3060216Y1737196D01*
X3061146Y1737404D01*
X3062076Y1737196D01*
X3063006Y1736363D01*
X3063626Y1734904D01*
X3063781Y1733238D01*
X3063626Y1731571D01*
X3063006Y1730112D01*
X3062076Y1729279D01*
X3061146Y1729071D01*
G01X3086876Y1735321D02*
X3089976D01*
Y1731571D01*
X3089046Y1730321D01*
X3087961Y1729488D01*
X3086411Y1729071D01*
X3084861Y1729488D01*
X3083776Y1730321D01*
X3082846Y1731571D01*
X3082226Y1733029D01*
X3081916Y1734696D01*
Y1736154D01*
X3082226Y1737404D01*
X3082846Y1738863D01*
X3083776Y1740113D01*
X3084706Y1740946D01*
X3085946Y1741571D01*
X3087031D01*
X3088271Y1741154D01*
X3089201Y1740321D01*
G01X3094781Y1729071D02*
Y1741571D01*
X3101911Y1729071D01*
Y1741571D01*
G01X3107336Y1729071D02*
Y1741571D01*
X3110436D01*
X3111676Y1740946D01*
X3112606Y1740113D01*
X3113381Y1738863D01*
X3114001Y1737404D01*
X3114156Y1735321D01*
X3114001Y1733238D01*
X3113381Y1731779D01*
X3112606Y1730529D01*
X3111676Y1729696D01*
X3110436Y1729071D01*
X3107336D01*
G01X3120201Y1739488D02*
X3121131Y1740737D01*
X3122216Y1741363D01*
X3123456Y1741571D01*
X3125006Y1741154D01*
X3126091Y1740113D01*
X3126401Y1738863D01*
X3126246Y1737612D01*
X3125626Y1736571D01*
X3122526Y1734488D01*
X3121131Y1733029D01*
X3120201Y1730946D01*
X3119891Y1729071D01*
X3126401D01*
G01X2829050Y2042816D02*
Y2055316D01*
X2833080Y2044899D01*
X2837110Y2055316D01*
Y2042816D01*
G01X2841915D02*
Y2055316D01*
X2849045Y2042816D01*
Y2055316D01*
G01X2861290Y2054274D02*
X2860360Y2054899D01*
X2859275Y2055316D01*
X2858035D01*
X2856640Y2054691D01*
X2855555Y2053649D01*
X2854780Y2052399D01*
X2854160Y2050316D01*
X2854005Y2048441D01*
X2854315Y2046566D01*
X2854780Y2045316D01*
X2855710Y2044066D01*
X2856795Y2043233D01*
X2857880Y2042816D01*
X2858965D01*
X2860050Y2043233D01*
X2860980Y2043857D01*
X2861755Y2044691D01*
G01X2865630Y2038649D02*
X2874930D01*
G01X2879580Y2055316D02*
Y2042816D01*
X2885780D01*
G01X2891205D02*
X2895080Y2055316D01*
X2898955Y2042816D01*
G01X2897560Y2047191D02*
X2892600D01*
G01X2907480Y2042816D02*
Y2048441D01*
X2904380Y2055316D01*
G01X2910580D02*
X2907480Y2048441D01*
G01X2922980Y2042816D02*
X2916780D01*
Y2055316D01*
X2922980D01*
G01X2920500Y2049274D02*
X2916780D01*
G01X2929180Y2042816D02*
Y2055316D01*
X2933055D01*
X2934295Y2054691D01*
X2935070Y2053858D01*
X2935380Y2052191D01*
X2935070Y2050524D01*
X2934140Y2049483D01*
X2933055Y2048858D01*
X2929180D01*
G01X2933055D02*
X2935380Y2042816D01*
G01X2834104Y2364651D02*
X2837824D01*
G01X2835964D02*
Y2352151D01*
G01X2834104D02*
X2837824D01*
G01X2844799D02*
Y2364651D01*
X2851929Y2352151D01*
Y2364651D01*
G01X2857354Y2354026D02*
X2858284Y2352984D01*
X2859369Y2352359D01*
X2860764Y2352151D01*
X2862159Y2352568D01*
X2863244Y2353401D01*
X2864019Y2354859D01*
X2864174Y2356526D01*
X2863864Y2358193D01*
X2863089Y2359234D01*
X2862004Y2360068D01*
X2860919Y2360276D01*
X2859834Y2360068D01*
X2858439Y2359234D01*
X2858904Y2364651D01*
X2863089D01*
G01X2834104Y2389651D02*
X2837824D01*
G01X2835964D02*
Y2377151D01*
G01X2834104D02*
X2837824D01*
G01X2844799D02*
Y2389651D01*
X2851929Y2377151D01*
Y2389651D01*
G01X2857354Y2379026D02*
X2858284Y2377984D01*
X2859369Y2377359D01*
X2860764Y2377151D01*
X2862159Y2377568D01*
X2863244Y2378401D01*
X2864019Y2379859D01*
X2864174Y2381526D01*
X2863864Y2383193D01*
X2863089Y2384234D01*
X2862004Y2385068D01*
X2860919Y2385276D01*
X2859834Y2385068D01*
X2858439Y2384234D01*
X2858904Y2389651D01*
X2863089D01*
G01X2834104Y2414651D02*
X2837824D01*
G01X2835964D02*
Y2402151D01*
G01X2834104D02*
X2837824D01*
G01X2844799D02*
Y2414651D01*
X2851929Y2402151D01*
Y2414651D01*
G01X2857354Y2404026D02*
X2858284Y2402984D01*
X2859369Y2402359D01*
X2860764Y2402151D01*
X2862159Y2402568D01*
X2863244Y2403401D01*
X2864019Y2404859D01*
X2864174Y2406526D01*
X2863864Y2408193D01*
X2863089Y2409234D01*
X2862004Y2410068D01*
X2860919Y2410276D01*
X2859834Y2410068D01*
X2858439Y2409234D01*
X2858904Y2414651D01*
X2863089D01*
G01X2847831Y2724963D02*
X2851551D01*
G01X2849691D02*
Y2712463D01*
G01X2847831D02*
X2851551D01*
G01X2858526D02*
Y2724963D01*
X2865656Y2712463D01*
Y2724963D01*
G01X2871546Y2717671D02*
X2872631Y2719130D01*
X2873561Y2719963D01*
X2874801Y2720380D01*
X2875886Y2719963D01*
X2876661Y2719130D01*
X2877281Y2717880D01*
X2877436Y2716421D01*
X2877281Y2715171D01*
X2876661Y2713921D01*
X2875731Y2712880D01*
X2874646Y2712463D01*
X2873406Y2712880D01*
X2872321Y2714129D01*
X2871701Y2716005D01*
X2871546Y2718088D01*
X2871856Y2720796D01*
X2872321Y2722255D01*
X2873096Y2723713D01*
X2874181Y2724755D01*
X2875266Y2724963D01*
X2876351Y2724546D01*
X2877126Y2723505D01*
G01X2847831Y2749963D02*
X2851551D01*
G01X2849691D02*
Y2737463D01*
G01X2847831D02*
X2851551D01*
G01X2858526D02*
Y2749963D01*
X2865656Y2737463D01*
Y2749963D01*
G01X2871546Y2742671D02*
X2872631Y2744130D01*
X2873561Y2744963D01*
X2874801Y2745380D01*
X2875886Y2744963D01*
X2876661Y2744130D01*
X2877281Y2742880D01*
X2877436Y2741421D01*
X2877281Y2740171D01*
X2876661Y2738921D01*
X2875731Y2737880D01*
X2874646Y2737463D01*
X2873406Y2737880D01*
X2872321Y2739129D01*
X2871701Y2741005D01*
X2871546Y2743088D01*
X2871856Y2745796D01*
X2872321Y2747255D01*
X2873096Y2748713D01*
X2874181Y2749755D01*
X2875266Y2749963D01*
X2876351Y2749546D01*
X2877126Y2748505D01*
G01X2847831Y2774963D02*
X2851551D01*
G01X2849691D02*
Y2762463D01*
G01X2847831D02*
X2851551D01*
G01X2858526D02*
Y2774963D01*
X2865656Y2762463D01*
Y2774963D01*
G01X2871546Y2767671D02*
X2872631Y2769130D01*
X2873561Y2769963D01*
X2874801Y2770380D01*
X2875886Y2769963D01*
X2876661Y2769130D01*
X2877281Y2767880D01*
X2877436Y2766421D01*
X2877281Y2765171D01*
X2876661Y2763921D01*
X2875731Y2762880D01*
X2874646Y2762463D01*
X2873406Y2762880D01*
X2872321Y2764129D01*
X2871701Y2766005D01*
X2871546Y2768088D01*
X2871856Y2770796D01*
X2872321Y2772255D01*
X2873096Y2773713D01*
X2874181Y2774755D01*
X2875266Y2774963D01*
X2876351Y2774546D01*
X2877126Y2773505D01*
G01X2853523Y987938D02*
Y1000438D01*
X2859413D01*
G01X2857243Y994396D02*
X2853523D01*
G01X2867008Y1000438D02*
X2870728D01*
G01X2868868D02*
Y987938D01*
G01X2867008D02*
X2870728D01*
G01X2877703D02*
Y1000438D01*
X2884833Y987938D01*
Y1000438D01*
G01X2891808D02*
X2895528D01*
G01X2893668D02*
Y987938D01*
G01X2891808D02*
X2895528D01*
G01X2902813Y989604D02*
X2904053Y988563D01*
X2905448Y987938D01*
X2906688D01*
X2907928Y988563D01*
X2908858Y989604D01*
X2909323Y991063D01*
X2909013Y992521D01*
X2908238Y993771D01*
X2906843Y994605D01*
X2904983Y995021D01*
X2903898Y995855D01*
X2903433Y997313D01*
X2903743Y998771D01*
X2904518Y999813D01*
X2905603Y1000438D01*
X2906688D01*
X2907773Y1000021D01*
X2908703Y998980D01*
G01X2915213Y987938D02*
Y1000438D01*
G01X2921723D02*
Y987938D01*
G01Y994188D02*
X2915213D01*
G01X2933968Y987938D02*
X2927768D01*
Y1000438D01*
X2933968D01*
G01X2931488Y994396D02*
X2927768D01*
G01X2939858Y987938D02*
Y1000438D01*
X2942958D01*
X2944198Y999813D01*
X2945128Y998980D01*
X2945903Y997730D01*
X2946523Y996271D01*
X2946678Y994188D01*
X2946523Y992105D01*
X2945903Y990646D01*
X2945128Y989396D01*
X2944198Y988563D01*
X2942958Y987938D01*
X2939858D01*
G01X2951018Y983771D02*
X2960318D01*
G01X2964813Y989604D02*
X2966053Y988563D01*
X2967448Y987938D01*
X2968688D01*
X2969928Y988563D01*
X2970858Y989604D01*
X2971323Y991063D01*
X2971013Y992521D01*
X2970238Y993771D01*
X2968843Y994605D01*
X2966983Y995021D01*
X2965898Y995855D01*
X2965433Y997313D01*
X2965743Y998771D01*
X2966518Y999813D01*
X2967603Y1000438D01*
X2968688D01*
X2969773Y1000021D01*
X2970703Y998980D01*
G01X2978608Y1000438D02*
X2982328D01*
G01X2980468D02*
Y987938D01*
G01X2978608D02*
X2982328D01*
G01X2989923Y1000438D02*
X2995813D01*
X2989923Y987938D01*
X2995813D01*
G01X3008368D02*
X3002168D01*
Y1000438D01*
X3008368D01*
G01X3005888Y994396D02*
X3002168D01*
G01X2846471Y1354053D02*
X2850346Y1366553D01*
X2854221Y1354053D01*
G01X2852826Y1358428D02*
X2847866D01*
G01X2859646Y1366553D02*
Y1354053D01*
X2865846D01*
G01X2872046Y1366553D02*
Y1354053D01*
X2878246D01*
G01X2896536Y1366553D02*
Y1357595D01*
X2897156Y1355719D01*
X2898396Y1354470D01*
X2899946Y1354053D01*
X2901496Y1354470D01*
X2902736Y1355719D01*
X2903356Y1357595D01*
Y1366553D01*
G01X2908781Y1354053D02*
Y1366553D01*
X2915911Y1354053D01*
Y1366553D01*
G01X2922886D02*
X2926606D01*
G01X2924746D02*
Y1354053D01*
G01X2922886D02*
X2926606D01*
G01X2937146Y1366553D02*
Y1354053D01*
G01X2933581Y1366553D02*
X2940711D01*
G01X2946291Y1355719D02*
X2947531Y1354678D01*
X2948926Y1354053D01*
X2950166D01*
X2951406Y1354678D01*
X2952336Y1355719D01*
X2952801Y1357178D01*
X2952491Y1358636D01*
X2951716Y1359886D01*
X2950321Y1360720D01*
X2948461Y1361136D01*
X2947376Y1361970D01*
X2946911Y1363428D01*
X2947221Y1364886D01*
X2947996Y1365928D01*
X2949081Y1366553D01*
X2950166D01*
X2951251Y1366136D01*
X2952181Y1365095D01*
G01X2970471Y1354053D02*
X2974346Y1366553D01*
X2978221Y1354053D01*
G01X2976826Y1358428D02*
X2971866D01*
G01X2983646Y1354053D02*
Y1366553D01*
X2987521D01*
X2988761Y1365928D01*
X2989536Y1365095D01*
X2989846Y1363428D01*
X2989536Y1361761D01*
X2988606Y1360720D01*
X2987521Y1360095D01*
X2983646D01*
G01X2987521D02*
X2989846Y1354053D01*
G01X3002246D02*
X2996046D01*
Y1366553D01*
X3002246D01*
G01X2999766Y1360511D02*
X2996046D01*
G01X3022086Y1366553D02*
X3025806D01*
G01X3023946D02*
Y1354053D01*
G01X3022086D02*
X3025806D01*
G01X3032781D02*
Y1366553D01*
X3039911Y1354053D01*
Y1366553D01*
G01X3057116Y1354053D02*
Y1366553D01*
X3061146Y1356136D01*
X3065176Y1366553D01*
Y1354053D01*
G01X3071686Y1366553D02*
X3075406D01*
G01X3073546D02*
Y1354053D01*
G01X3071686D02*
X3075406D01*
G01X3082846Y1366553D02*
Y1354053D01*
X3089046D01*
G01X3095091Y1355719D02*
X3096331Y1354678D01*
X3097726Y1354053D01*
X3098966D01*
X3100206Y1354678D01*
X3101136Y1355719D01*
X3101601Y1357178D01*
X3101291Y1358636D01*
X3100516Y1359886D01*
X3099121Y1360720D01*
X3097261Y1361136D01*
X3096176Y1361970D01*
X3095711Y1363428D01*
X3096021Y1364886D01*
X3096796Y1365928D01*
X3097881Y1366553D01*
X3098966D01*
X3100051Y1366136D01*
X3100981Y1365095D01*
G01X2846471Y1704071D02*
X2850346Y1716571D01*
X2854221Y1704071D01*
G01X2852826Y1708446D02*
X2847866D01*
G01X2859646Y1716571D02*
Y1704071D01*
X2865846D01*
G01X2872046Y1716571D02*
Y1704071D01*
X2878246D01*
G01X2896536Y1716571D02*
Y1707613D01*
X2897156Y1705737D01*
X2898396Y1704488D01*
X2899946Y1704071D01*
X2901496Y1704488D01*
X2902736Y1705737D01*
X2903356Y1707613D01*
Y1716571D01*
G01X2908781Y1704071D02*
Y1716571D01*
X2915911Y1704071D01*
Y1716571D01*
G01X2922886D02*
X2926606D01*
G01X2924746D02*
Y1704071D01*
G01X2922886D02*
X2926606D01*
G01X2937146Y1716571D02*
Y1704071D01*
G01X2933581Y1716571D02*
X2940711D01*
G01X2946291Y1705737D02*
X2947531Y1704696D01*
X2948926Y1704071D01*
X2950166D01*
X2951406Y1704696D01*
X2952336Y1705737D01*
X2952801Y1707196D01*
X2952491Y1708654D01*
X2951716Y1709904D01*
X2950321Y1710738D01*
X2948461Y1711154D01*
X2947376Y1711988D01*
X2946911Y1713446D01*
X2947221Y1714904D01*
X2947996Y1715946D01*
X2949081Y1716571D01*
X2950166D01*
X2951251Y1716154D01*
X2952181Y1715113D01*
G01X2970471Y1704071D02*
X2974346Y1716571D01*
X2978221Y1704071D01*
G01X2976826Y1708446D02*
X2971866D01*
G01X2983646Y1704071D02*
Y1716571D01*
X2987521D01*
X2988761Y1715946D01*
X2989536Y1715113D01*
X2989846Y1713446D01*
X2989536Y1711779D01*
X2988606Y1710738D01*
X2987521Y1710113D01*
X2983646D01*
G01X2987521D02*
X2989846Y1704071D01*
G01X3002246D02*
X2996046D01*
Y1716571D01*
X3002246D01*
G01X2999766Y1710529D02*
X2996046D01*
G01X3022086Y1716571D02*
X3025806D01*
G01X3023946D02*
Y1704071D01*
G01X3022086D02*
X3025806D01*
G01X3032781D02*
Y1716571D01*
X3039911Y1704071D01*
Y1716571D01*
G01X3057116Y1704071D02*
Y1716571D01*
X3061146Y1706154D01*
X3065176Y1716571D01*
Y1704071D01*
G01X3071686Y1716571D02*
X3075406D01*
G01X3073546D02*
Y1704071D01*
G01X3071686D02*
X3075406D01*
G01X3082846Y1716571D02*
Y1704071D01*
X3089046D01*
G01X3095091Y1705737D02*
X3096331Y1704696D01*
X3097726Y1704071D01*
X3098966D01*
X3100206Y1704696D01*
X3101136Y1705737D01*
X3101601Y1707196D01*
X3101291Y1708654D01*
X3100516Y1709904D01*
X3099121Y1710738D01*
X3097261Y1711154D01*
X3096176Y1711988D01*
X3095711Y1713446D01*
X3096021Y1714904D01*
X3096796Y1715946D01*
X3097881Y1716571D01*
X3098966D01*
X3100051Y1716154D01*
X3100981Y1715113D01*
G01X2878633Y-34179D02*
X2879718Y-35220D01*
X2880958Y-35637D01*
X2882198Y-35220D01*
X2883283Y-33971D01*
X2884058Y-32095D01*
X2884368Y-30220D01*
Y-27929D01*
X2884058Y-26054D01*
X2883283Y-24387D01*
X2882353Y-23554D01*
X2881268Y-23137D01*
X2880028Y-23554D01*
X2879098Y-24387D01*
X2878478Y-25637D01*
X2878168Y-27304D01*
X2878478Y-28762D01*
X2879253Y-30220D01*
X2880183Y-31054D01*
X2881268Y-31262D01*
X2882508Y-30846D01*
X2883438Y-29804D01*
X2884368Y-27929D01*
G01X2893358Y-35637D02*
X2893668Y-32929D01*
X2894133Y-30637D01*
X2894753Y-28554D01*
X2895528Y-26262D01*
X2896768Y-23137D01*
X2890568D01*
G01X2906068Y-36054D02*
X2905758Y-35845D01*
Y-35429D01*
X2906068Y-35220D01*
X2906378Y-35429D01*
Y-35845D01*
X2906068Y-36054D01*
G01X2918468Y-23137D02*
X2917228Y-23554D01*
X2916298Y-24595D01*
X2915678Y-25845D01*
X2915213Y-27512D01*
X2915058Y-29387D01*
X2915213Y-31262D01*
X2915678Y-32929D01*
X2916298Y-34179D01*
X2917228Y-35220D01*
X2918468Y-35637D01*
X2919708Y-35220D01*
X2920638Y-34179D01*
X2921258Y-32929D01*
X2921723Y-31262D01*
X2921878Y-29387D01*
X2921723Y-27512D01*
X2921258Y-25845D01*
X2920638Y-24595D01*
X2919708Y-23554D01*
X2918468Y-23137D01*
G01X2928543Y-27304D02*
X2933193Y-35637D01*
G01Y-27304D02*
X2928543Y-35637D01*
G01X2945128D02*
Y-23137D01*
X2939393Y-32095D01*
X2947143D01*
G01X2957528Y-35637D02*
Y-23137D01*
X2951793Y-32095D01*
X2959543D01*
G01X2968068Y-36054D02*
X2967758Y-35845D01*
Y-35429D01*
X2968068Y-35220D01*
X2968378Y-35429D01*
Y-35845D01*
X2968068Y-36054D01*
G01X2980468Y-23137D02*
X2979228Y-23554D01*
X2978298Y-24595D01*
X2977678Y-25845D01*
X2977213Y-27512D01*
X2977058Y-29387D01*
X2977213Y-31262D01*
X2977678Y-32929D01*
X2978298Y-34179D01*
X2979228Y-35220D01*
X2980468Y-35637D01*
X2981708Y-35220D01*
X2982638Y-34179D01*
X2983258Y-32929D01*
X2983723Y-31262D01*
X2983878Y-29387D01*
X2983723Y-27512D01*
X2983258Y-25845D01*
X2982638Y-24595D01*
X2981708Y-23554D01*
X2980468Y-23137D01*
G01X2878633Y-1029D02*
X2879718Y-2070D01*
X2880958Y-2487D01*
X2882198Y-2070D01*
X2883283Y-821D01*
X2884058Y1055D01*
X2884368Y2930D01*
Y5221D01*
X2884058Y7096D01*
X2883283Y8763D01*
X2882353Y9596D01*
X2881268Y10013D01*
X2880028Y9596D01*
X2879098Y8763D01*
X2878478Y7513D01*
X2878168Y5846D01*
X2878478Y4388D01*
X2879253Y2930D01*
X2880183Y2096D01*
X2881268Y1888D01*
X2882508Y2304D01*
X2883438Y3346D01*
X2884368Y5221D01*
G01X2893358Y-2487D02*
X2893668Y221D01*
X2894133Y2513D01*
X2894753Y4596D01*
X2895528Y6888D01*
X2896768Y10013D01*
X2890568D01*
G01X2906068Y-2904D02*
X2905758Y-2695D01*
Y-2279D01*
X2906068Y-2070D01*
X2906378Y-2279D01*
Y-2695D01*
X2906068Y-2904D01*
G01X2918468Y10013D02*
X2917228Y9596D01*
X2916298Y8555D01*
X2915678Y7305D01*
X2915213Y5638D01*
X2915058Y3763D01*
X2915213Y1888D01*
X2915678Y221D01*
X2916298Y-1029D01*
X2917228Y-2070D01*
X2918468Y-2487D01*
X2919708Y-2070D01*
X2920638Y-1029D01*
X2921258Y221D01*
X2921723Y1888D01*
X2921878Y3763D01*
X2921723Y5638D01*
X2921258Y7305D01*
X2920638Y8555D01*
X2919708Y9596D01*
X2918468Y10013D01*
G01X2928543Y5846D02*
X2933193Y-2487D01*
G01Y5846D02*
X2928543Y-2487D01*
G01X2945128D02*
Y10013D01*
X2939393Y1055D01*
X2947143D01*
G01X2957528Y-2487D02*
Y10013D01*
X2951793Y1055D01*
X2959543D01*
G01X2968068Y-2904D02*
X2967758Y-2695D01*
Y-2279D01*
X2968068Y-2070D01*
X2968378Y-2279D01*
Y-2695D01*
X2968068Y-2904D01*
G01X2980468Y10013D02*
X2979228Y9596D01*
X2978298Y8555D01*
X2977678Y7305D01*
X2977213Y5638D01*
X2977058Y3763D01*
X2977213Y1888D01*
X2977678Y221D01*
X2978298Y-1029D01*
X2979228Y-2070D01*
X2980468Y-2487D01*
X2981708Y-2070D01*
X2982638Y-1029D01*
X2983258Y221D01*
X2983723Y1888D01*
X2983878Y3763D01*
X2983723Y5638D01*
X2983258Y7305D01*
X2982638Y8555D01*
X2981708Y9596D01*
X2980468Y10013D01*
G01X2878323Y35871D02*
X2879408Y37330D01*
X2880338Y38163D01*
X2881578Y38580D01*
X2882663Y38163D01*
X2883438Y37330D01*
X2884058Y36080D01*
X2884213Y34621D01*
X2884058Y33371D01*
X2883438Y32121D01*
X2882508Y31080D01*
X2881423Y30663D01*
X2880183Y31080D01*
X2879098Y32329D01*
X2878478Y34205D01*
X2878323Y36288D01*
X2878633Y38996D01*
X2879098Y40455D01*
X2879873Y41913D01*
X2880958Y42955D01*
X2882043Y43163D01*
X2883128Y42746D01*
X2883903Y41705D01*
G01X2890258Y33163D02*
X2891188Y31704D01*
X2892428Y30871D01*
X2893823Y30663D01*
X2895063Y30871D01*
X2896303Y31913D01*
X2897078Y33163D01*
X2897233Y34413D01*
X2896923Y35871D01*
X2895838Y36913D01*
X2894753Y37330D01*
X2893358D01*
G01X2894753D02*
X2895683Y37955D01*
X2896458Y38996D01*
X2896768Y40246D01*
X2896458Y41496D01*
X2895683Y42538D01*
X2894288Y43163D01*
X2892893Y42955D01*
X2891498Y42121D01*
G01X2906068Y30246D02*
X2905758Y30455D01*
Y30871D01*
X2906068Y31080D01*
X2906378Y30871D01*
Y30455D01*
X2906068Y30246D01*
G01X2918468Y43163D02*
X2917228Y42746D01*
X2916298Y41705D01*
X2915678Y40455D01*
X2915213Y38788D01*
X2915058Y36913D01*
X2915213Y35038D01*
X2915678Y33371D01*
X2916298Y32121D01*
X2917228Y31080D01*
X2918468Y30663D01*
X2919708Y31080D01*
X2920638Y32121D01*
X2921258Y33371D01*
X2921723Y35038D01*
X2921878Y36913D01*
X2921723Y38788D01*
X2921258Y40455D01*
X2920638Y41705D01*
X2919708Y42746D01*
X2918468Y43163D01*
G01X2928543Y38996D02*
X2933193Y30663D01*
G01Y38996D02*
X2928543Y30663D01*
G01X2940323Y41080D02*
X2941253Y42329D01*
X2942338Y42955D01*
X2943578Y43163D01*
X2945128Y42746D01*
X2946213Y41705D01*
X2946523Y40455D01*
X2946368Y39204D01*
X2945748Y38163D01*
X2942648Y36080D01*
X2941253Y34621D01*
X2940323Y32538D01*
X2940013Y30663D01*
X2946523D01*
G01X2955668Y43163D02*
X2954428Y42746D01*
X2953498Y41705D01*
X2952878Y40455D01*
X2952413Y38788D01*
X2952258Y36913D01*
X2952413Y35038D01*
X2952878Y33371D01*
X2953498Y32121D01*
X2954428Y31080D01*
X2955668Y30663D01*
X2956908Y31080D01*
X2957838Y32121D01*
X2958458Y33371D01*
X2958923Y35038D01*
X2959078Y36913D01*
X2958923Y38788D01*
X2958458Y40455D01*
X2957838Y41705D01*
X2956908Y42746D01*
X2955668Y43163D01*
G01X2968068Y30246D02*
X2967758Y30455D01*
Y30871D01*
X2968068Y31080D01*
X2968378Y30871D01*
Y30455D01*
X2968068Y30246D01*
G01X2980468Y43163D02*
X2979228Y42746D01*
X2978298Y41705D01*
X2977678Y40455D01*
X2977213Y38788D01*
X2977058Y36913D01*
X2977213Y35038D01*
X2977678Y33371D01*
X2978298Y32121D01*
X2979228Y31080D01*
X2980468Y30663D01*
X2981708Y31080D01*
X2982638Y32121D01*
X2983258Y33371D01*
X2983723Y35038D01*
X2983878Y36913D01*
X2983723Y38788D01*
X2983258Y40455D01*
X2982638Y41705D01*
X2981708Y42746D01*
X2980468Y43163D01*
G01X2883128Y63813D02*
Y76313D01*
X2877393Y67355D01*
X2885143D01*
G01X2893668Y63813D02*
X2894753Y64021D01*
X2895993Y64646D01*
X2896768Y65688D01*
X2897078Y67146D01*
X2896768Y68604D01*
X2895838Y69855D01*
X2894443Y70480D01*
X2892893D01*
X2891963Y70896D01*
X2891188Y71938D01*
X2890878Y73396D01*
X2891343Y74855D01*
X2892428Y75896D01*
X2893668Y76313D01*
X2894908Y75896D01*
X2895993Y74855D01*
X2896458Y73396D01*
X2896148Y71938D01*
X2895373Y70896D01*
X2894443Y70480D01*
X2892893D01*
X2891498Y69855D01*
X2890568Y68604D01*
X2890258Y67146D01*
X2890568Y65688D01*
X2891343Y64646D01*
X2892583Y64021D01*
X2893668Y63813D01*
G01X2906068Y63396D02*
X2905758Y63605D01*
Y64021D01*
X2906068Y64230D01*
X2906378Y64021D01*
Y63605D01*
X2906068Y63396D01*
G01X2918468Y76313D02*
X2917228Y75896D01*
X2916298Y74855D01*
X2915678Y73605D01*
X2915213Y71938D01*
X2915058Y70063D01*
X2915213Y68188D01*
X2915678Y66521D01*
X2916298Y65271D01*
X2917228Y64230D01*
X2918468Y63813D01*
X2919708Y64230D01*
X2920638Y65271D01*
X2921258Y66521D01*
X2921723Y68188D01*
X2921878Y70063D01*
X2921723Y71938D01*
X2921258Y73605D01*
X2920638Y74855D01*
X2919708Y75896D01*
X2918468Y76313D01*
G01X2928543Y72146D02*
X2933193Y63813D01*
G01Y72146D02*
X2928543Y63813D01*
G01X2940323Y74230D02*
X2941253Y75479D01*
X2942338Y76105D01*
X2943578Y76313D01*
X2945128Y75896D01*
X2946213Y74855D01*
X2946523Y73605D01*
X2946368Y72354D01*
X2945748Y71313D01*
X2942648Y69230D01*
X2941253Y67771D01*
X2940323Y65688D01*
X2940013Y63813D01*
X2946523D01*
G01X2955668Y76313D02*
X2954428Y75896D01*
X2953498Y74855D01*
X2952878Y73605D01*
X2952413Y71938D01*
X2952258Y70063D01*
X2952413Y68188D01*
X2952878Y66521D01*
X2953498Y65271D01*
X2954428Y64230D01*
X2955668Y63813D01*
X2956908Y64230D01*
X2957838Y65271D01*
X2958458Y66521D01*
X2958923Y68188D01*
X2959078Y70063D01*
X2958923Y71938D01*
X2958458Y73605D01*
X2957838Y74855D01*
X2956908Y75896D01*
X2955668Y76313D01*
G01X2968068Y63396D02*
X2967758Y63605D01*
Y64021D01*
X2968068Y64230D01*
X2968378Y64021D01*
Y63605D01*
X2968068Y63396D01*
G01X2980468Y76313D02*
X2979228Y75896D01*
X2978298Y74855D01*
X2977678Y73605D01*
X2977213Y71938D01*
X2977058Y70063D01*
X2977213Y68188D01*
X2977678Y66521D01*
X2978298Y65271D01*
X2979228Y64230D01*
X2980468Y63813D01*
X2981708Y64230D01*
X2982638Y65271D01*
X2983258Y66521D01*
X2983723Y68188D01*
X2983878Y70063D01*
X2983723Y71938D01*
X2983258Y73605D01*
X2982638Y74855D01*
X2981708Y75896D01*
X2980468Y76313D01*
G01X2863366Y1329053D02*
Y1341553D01*
X2867396Y1331136D01*
X2871426Y1341553D01*
Y1329053D01*
G01X2876231D02*
Y1341553D01*
X2883361Y1329053D01*
Y1341553D01*
G01X2895606Y1340511D02*
X2894676Y1341136D01*
X2893591Y1341553D01*
X2892351D01*
X2890956Y1340928D01*
X2889871Y1339886D01*
X2889096Y1338636D01*
X2888476Y1336553D01*
X2888321Y1334678D01*
X2888631Y1332803D01*
X2889096Y1331553D01*
X2890026Y1330303D01*
X2891111Y1329470D01*
X2892196Y1329053D01*
X2893281D01*
X2894366Y1329470D01*
X2895296Y1330094D01*
X2896071Y1330928D01*
G01X2899946Y1324886D02*
X2909246D01*
G01X2913896Y1341553D02*
Y1329053D01*
X2920096D01*
G01X2925521D02*
X2929396Y1341553D01*
X2933271Y1329053D01*
G01X2931876Y1333428D02*
X2926916D01*
G01X2941796Y1329053D02*
Y1334678D01*
X2938696Y1341553D01*
G01X2944896D02*
X2941796Y1334678D01*
G01X2957296Y1329053D02*
X2951096D01*
Y1341553D01*
X2957296D01*
G01X2954816Y1335511D02*
X2951096D01*
G01X2963496Y1329053D02*
Y1341553D01*
X2967371D01*
X2968611Y1340928D01*
X2969386Y1340095D01*
X2969696Y1338428D01*
X2969386Y1336761D01*
X2968456Y1335720D01*
X2967371Y1335095D01*
X2963496D01*
G01X2967371D02*
X2969696Y1329053D01*
G01X2863366Y1679071D02*
Y1691571D01*
X2867396Y1681154D01*
X2871426Y1691571D01*
Y1679071D01*
G01X2876231D02*
Y1691571D01*
X2883361Y1679071D01*
Y1691571D01*
G01X2895606Y1690529D02*
X2894676Y1691154D01*
X2893591Y1691571D01*
X2892351D01*
X2890956Y1690946D01*
X2889871Y1689904D01*
X2889096Y1688654D01*
X2888476Y1686571D01*
X2888321Y1684696D01*
X2888631Y1682821D01*
X2889096Y1681571D01*
X2890026Y1680321D01*
X2891111Y1679488D01*
X2892196Y1679071D01*
X2893281D01*
X2894366Y1679488D01*
X2895296Y1680112D01*
X2896071Y1680946D01*
G01X2899946Y1674904D02*
X2909246D01*
G01X2913896Y1691571D02*
Y1679071D01*
X2920096D01*
G01X2925521D02*
X2929396Y1691571D01*
X2933271Y1679071D01*
G01X2931876Y1683446D02*
X2926916D01*
G01X2941796Y1679071D02*
Y1684696D01*
X2938696Y1691571D01*
G01X2944896D02*
X2941796Y1684696D01*
G01X2957296Y1679071D02*
X2951096D01*
Y1691571D01*
X2957296D01*
G01X2954816Y1685529D02*
X2951096D01*
G01X2963496Y1679071D02*
Y1691571D01*
X2967371D01*
X2968611Y1690946D01*
X2969386Y1690113D01*
X2969696Y1688446D01*
X2969386Y1686779D01*
X2968456Y1685738D01*
X2967371Y1685113D01*
X2963496D01*
G01X2967371D02*
X2969696Y1679071D01*
G01X2868420Y1980316D02*
X2872140D01*
G01X2870280D02*
Y1967816D01*
G01X2868420D02*
X2872140D01*
G01X2879115D02*
Y1980316D01*
X2886245Y1967816D01*
Y1980316D01*
G01X2891670Y1970316D02*
X2892600Y1968857D01*
X2893840Y1968024D01*
X2895235Y1967816D01*
X2896475Y1968024D01*
X2897715Y1969066D01*
X2898490Y1970316D01*
X2898645Y1971566D01*
X2898335Y1973024D01*
X2897250Y1974066D01*
X2896165Y1974483D01*
X2894770D01*
G01X2896165D02*
X2897095Y1975108D01*
X2897870Y1976149D01*
X2898180Y1977399D01*
X2897870Y1978649D01*
X2897095Y1979691D01*
X2895700Y1980316D01*
X2894305Y1980108D01*
X2892910Y1979274D01*
G01X2868420Y2005316D02*
X2872140D01*
G01X2870280D02*
Y1992816D01*
G01X2868420D02*
X2872140D01*
G01X2879115D02*
Y2005316D01*
X2886245Y1992816D01*
Y2005316D01*
G01X2891670Y1995316D02*
X2892600Y1993857D01*
X2893840Y1993024D01*
X2895235Y1992816D01*
X2896475Y1993024D01*
X2897715Y1994066D01*
X2898490Y1995316D01*
X2898645Y1996566D01*
X2898335Y1998024D01*
X2897250Y1999066D01*
X2896165Y1999483D01*
X2894770D01*
G01X2896165D02*
X2897095Y2000108D01*
X2897870Y2001149D01*
X2898180Y2002399D01*
X2897870Y2003649D01*
X2897095Y2004691D01*
X2895700Y2005316D01*
X2894305Y2005108D01*
X2892910Y2004274D01*
G01X2868420Y2030316D02*
X2872140D01*
G01X2870280D02*
Y2017816D01*
G01X2868420D02*
X2872140D01*
G01X2879115D02*
Y2030316D01*
X2886245Y2017816D01*
Y2030316D01*
G01X2891670Y2020316D02*
X2892600Y2018857D01*
X2893840Y2018024D01*
X2895235Y2017816D01*
X2896475Y2018024D01*
X2897715Y2019066D01*
X2898490Y2020316D01*
X2898645Y2021566D01*
X2898335Y2023024D01*
X2897250Y2024066D01*
X2896165Y2024483D01*
X2894770D01*
G01X2896165D02*
X2897095Y2025108D01*
X2897870Y2026149D01*
X2898180Y2027399D01*
X2897870Y2028649D01*
X2897095Y2029691D01*
X2895700Y2030316D01*
X2894305Y2030108D01*
X2892910Y2029274D01*
G01X2906068Y96963D02*
Y109463D01*
X2904208Y106963D01*
G01Y96963D02*
X2907928D01*
G01X2918158D02*
X2918468Y99671D01*
X2918933Y101963D01*
X2919553Y104046D01*
X2920328Y106338D01*
X2921568Y109463D01*
X2915368D01*
G01X2930868Y96963D02*
X2931953Y97171D01*
X2933193Y97796D01*
X2933968Y98838D01*
X2934278Y100296D01*
X2933968Y101754D01*
X2933038Y103005D01*
X2931643Y103630D01*
X2930093D01*
X2929163Y104046D01*
X2928388Y105088D01*
X2928078Y106546D01*
X2928543Y108005D01*
X2929628Y109046D01*
X2930868Y109463D01*
X2932108Y109046D01*
X2933193Y108005D01*
X2933658Y106546D01*
X2933348Y105088D01*
X2932573Y104046D01*
X2931643Y103630D01*
X2930093D01*
X2928698Y103005D01*
X2927768Y101754D01*
X2927458Y100296D01*
X2927768Y98838D01*
X2928543Y97796D01*
X2929783Y97171D01*
X2930868Y96963D01*
G01X2943268Y96546D02*
X2942958Y96755D01*
Y97171D01*
X2943268Y97380D01*
X2943578Y97171D01*
Y96755D01*
X2943268Y96546D01*
G01X2955668Y109463D02*
X2954428Y109046D01*
X2953498Y108005D01*
X2952878Y106755D01*
X2952413Y105088D01*
X2952258Y103213D01*
X2952413Y101338D01*
X2952878Y99671D01*
X2953498Y98421D01*
X2954428Y97380D01*
X2955668Y96963D01*
X2956908Y97380D01*
X2957838Y98421D01*
X2958458Y99671D01*
X2958923Y101338D01*
X2959078Y103213D01*
X2958923Y105088D01*
X2958458Y106755D01*
X2957838Y108005D01*
X2956908Y109046D01*
X2955668Y109463D01*
G01X2906068Y130113D02*
Y142613D01*
X2904208Y140113D01*
G01Y130113D02*
X2907928D01*
G01X2915058Y132613D02*
X2915988Y131154D01*
X2917228Y130321D01*
X2918623Y130113D01*
X2919863Y130321D01*
X2921103Y131363D01*
X2921878Y132613D01*
X2922033Y133863D01*
X2921723Y135321D01*
X2920638Y136363D01*
X2919553Y136780D01*
X2918158D01*
G01X2919553D02*
X2920483Y137405D01*
X2921258Y138446D01*
X2921568Y139696D01*
X2921258Y140946D01*
X2920483Y141988D01*
X2919088Y142613D01*
X2917693Y142405D01*
X2916298Y141571D01*
G01X2932728Y130113D02*
Y142613D01*
X2926993Y133655D01*
X2934743D01*
G01X2943268Y129696D02*
X2942958Y129905D01*
Y130321D01*
X2943268Y130530D01*
X2943578Y130321D01*
Y129905D01*
X2943268Y129696D01*
G01X2955668Y142613D02*
X2954428Y142196D01*
X2953498Y141155D01*
X2952878Y139905D01*
X2952413Y138238D01*
X2952258Y136363D01*
X2952413Y134488D01*
X2952878Y132821D01*
X2953498Y131571D01*
X2954428Y130530D01*
X2955668Y130113D01*
X2956908Y130530D01*
X2957838Y131571D01*
X2958458Y132821D01*
X2958923Y134488D01*
X2959078Y136363D01*
X2958923Y138238D01*
X2958458Y139905D01*
X2957838Y141155D01*
X2956908Y142196D01*
X2955668Y142613D01*
G01X2906068Y163263D02*
Y175763D01*
X2904208Y173263D01*
G01Y163263D02*
X2907928D01*
G01X2915523Y173680D02*
X2916453Y174929D01*
X2917538Y175555D01*
X2918778Y175763D01*
X2920328Y175346D01*
X2921413Y174305D01*
X2921723Y173055D01*
X2921568Y171804D01*
X2920948Y170763D01*
X2917848Y168680D01*
X2916453Y167221D01*
X2915523Y165138D01*
X2915213Y163263D01*
X2921723D01*
G01X2927458Y165138D02*
X2928388Y164096D01*
X2929473Y163471D01*
X2930868Y163263D01*
X2932263Y163680D01*
X2933348Y164513D01*
X2934123Y165971D01*
X2934278Y167638D01*
X2933968Y169305D01*
X2933193Y170346D01*
X2932108Y171180D01*
X2931023Y171388D01*
X2929938Y171180D01*
X2928543Y170346D01*
X2929008Y175763D01*
X2933193D01*
G01X2943268Y162846D02*
X2942958Y163055D01*
Y163471D01*
X2943268Y163680D01*
X2943578Y163471D01*
Y163055D01*
X2943268Y162846D01*
G01X2955668Y175763D02*
X2954428Y175346D01*
X2953498Y174305D01*
X2952878Y173055D01*
X2952413Y171388D01*
X2952258Y169513D01*
X2952413Y167638D01*
X2952878Y165971D01*
X2953498Y164721D01*
X2954428Y163680D01*
X2955668Y163263D01*
X2956908Y163680D01*
X2957838Y164721D01*
X2958458Y165971D01*
X2958923Y167638D01*
X2959078Y169513D01*
X2958923Y171388D01*
X2958458Y173055D01*
X2957838Y174305D01*
X2956908Y175346D01*
X2955668Y175763D01*
G01X2906068Y196413D02*
Y208913D01*
X2904208Y206413D01*
G01Y196413D02*
X2907928D01*
G01X2915523Y206830D02*
X2916453Y208079D01*
X2917538Y208705D01*
X2918778Y208913D01*
X2920328Y208496D01*
X2921413Y207455D01*
X2921723Y206205D01*
X2921568Y204954D01*
X2920948Y203913D01*
X2917848Y201830D01*
X2916453Y200371D01*
X2915523Y198288D01*
X2915213Y196413D01*
X2921723D01*
G01X2927458Y198288D02*
X2928388Y197246D01*
X2929473Y196621D01*
X2930868Y196413D01*
X2932263Y196830D01*
X2933348Y197663D01*
X2934123Y199121D01*
X2934278Y200788D01*
X2933968Y202455D01*
X2933193Y203496D01*
X2932108Y204330D01*
X2931023Y204538D01*
X2929938Y204330D01*
X2928543Y203496D01*
X2929008Y208913D01*
X2933193D01*
G01X2943268Y195996D02*
X2942958Y196205D01*
Y196621D01*
X2943268Y196830D01*
X2943578Y196621D01*
Y196205D01*
X2943268Y195996D01*
G01X2955668Y208913D02*
X2954428Y208496D01*
X2953498Y207455D01*
X2952878Y206205D01*
X2952413Y204538D01*
X2952258Y202663D01*
X2952413Y200788D01*
X2952878Y199121D01*
X2953498Y197871D01*
X2954428Y196830D01*
X2955668Y196413D01*
X2956908Y196830D01*
X2957838Y197871D01*
X2958458Y199121D01*
X2958923Y200788D01*
X2959078Y202663D01*
X2958923Y204538D01*
X2958458Y206205D01*
X2957838Y207455D01*
X2956908Y208496D01*
X2955668Y208913D01*
G01X2906068Y229563D02*
Y242063D01*
X2904208Y239563D01*
G01Y229563D02*
X2907928D01*
G01X2915523Y239980D02*
X2916453Y241229D01*
X2917538Y241855D01*
X2918778Y242063D01*
X2920328Y241646D01*
X2921413Y240605D01*
X2921723Y239355D01*
X2921568Y238104D01*
X2920948Y237063D01*
X2917848Y234980D01*
X2916453Y233521D01*
X2915523Y231438D01*
X2915213Y229563D01*
X2921723D01*
G01X2927923Y239980D02*
X2928853Y241229D01*
X2929938Y241855D01*
X2931178Y242063D01*
X2932728Y241646D01*
X2933813Y240605D01*
X2934123Y239355D01*
X2933968Y238104D01*
X2933348Y237063D01*
X2930248Y234980D01*
X2928853Y233521D01*
X2927923Y231438D01*
X2927613Y229563D01*
X2934123D01*
G01X2943268Y229146D02*
X2942958Y229355D01*
Y229771D01*
X2943268Y229980D01*
X2943578Y229771D01*
Y229355D01*
X2943268Y229146D01*
G01X2955668Y242063D02*
X2954428Y241646D01*
X2953498Y240605D01*
X2952878Y239355D01*
X2952413Y237688D01*
X2952258Y235813D01*
X2952413Y233938D01*
X2952878Y232271D01*
X2953498Y231021D01*
X2954428Y229980D01*
X2955668Y229563D01*
X2956908Y229980D01*
X2957838Y231021D01*
X2958458Y232271D01*
X2958923Y233938D01*
X2959078Y235813D01*
X2958923Y237688D01*
X2958458Y239355D01*
X2957838Y240605D01*
X2956908Y241646D01*
X2955668Y242063D01*
G01X2908858Y264588D02*
X2909788Y263546D01*
X2910873Y262921D01*
X2912268Y262713D01*
X2913663Y263130D01*
X2914748Y263963D01*
X2915523Y265421D01*
X2915678Y267088D01*
X2915368Y268755D01*
X2914593Y269796D01*
X2913508Y270630D01*
X2912423Y270838D01*
X2911338Y270630D01*
X2909943Y269796D01*
X2910408Y275213D01*
X2914593D01*
G01X2921723Y273130D02*
X2922653Y274379D01*
X2923738Y275005D01*
X2924978Y275213D01*
X2926528Y274796D01*
X2927613Y273755D01*
X2927923Y272505D01*
X2927768Y271254D01*
X2927148Y270213D01*
X2924048Y268130D01*
X2922653Y266671D01*
X2921723Y264588D01*
X2921413Y262713D01*
X2927923D01*
G01X2937068Y262296D02*
X2936758Y262505D01*
Y262921D01*
X2937068Y263130D01*
X2937378Y262921D01*
Y262505D01*
X2937068Y262296D01*
G01X2949468Y275213D02*
X2948228Y274796D01*
X2947298Y273755D01*
X2946678Y272505D01*
X2946213Y270838D01*
X2946058Y268963D01*
X2946213Y267088D01*
X2946678Y265421D01*
X2947298Y264171D01*
X2948228Y263130D01*
X2949468Y262713D01*
X2950708Y263130D01*
X2951638Y264171D01*
X2952258Y265421D01*
X2952723Y267088D01*
X2952878Y268963D01*
X2952723Y270838D01*
X2952258Y272505D01*
X2951638Y273755D01*
X2950708Y274796D01*
X2949468Y275213D01*
G01X2914128Y295863D02*
Y308363D01*
X2908393Y299405D01*
X2916143D01*
G01X2926528Y295863D02*
Y308363D01*
X2920793Y299405D01*
X2928543D01*
G01X2937068Y295446D02*
X2936758Y295655D01*
Y296071D01*
X2937068Y296280D01*
X2937378Y296071D01*
Y295655D01*
X2937068Y295446D01*
G01X2949468Y308363D02*
X2948228Y307946D01*
X2947298Y306905D01*
X2946678Y305655D01*
X2946213Y303988D01*
X2946058Y302113D01*
X2946213Y300238D01*
X2946678Y298571D01*
X2947298Y297321D01*
X2948228Y296280D01*
X2949468Y295863D01*
X2950708Y296280D01*
X2951638Y297321D01*
X2952258Y298571D01*
X2952723Y300238D01*
X2952878Y302113D01*
X2952723Y303988D01*
X2952258Y305655D01*
X2951638Y306905D01*
X2950708Y307946D01*
X2949468Y308363D01*
G01X2914128Y329013D02*
Y341513D01*
X2908393Y332555D01*
X2916143D01*
G01X2926528Y329013D02*
Y341513D01*
X2920793Y332555D01*
X2928543D01*
G01X2937068Y328596D02*
X2936758Y328805D01*
Y329221D01*
X2937068Y329430D01*
X2937378Y329221D01*
Y328805D01*
X2937068Y328596D01*
G01X2949468Y341513D02*
X2948228Y341096D01*
X2947298Y340055D01*
X2946678Y338805D01*
X2946213Y337138D01*
X2946058Y335263D01*
X2946213Y333388D01*
X2946678Y331721D01*
X2947298Y330471D01*
X2948228Y329430D01*
X2949468Y329013D01*
X2950708Y329430D01*
X2951638Y330471D01*
X2952258Y331721D01*
X2952723Y333388D01*
X2952878Y335263D01*
X2952723Y337138D01*
X2952258Y338805D01*
X2951638Y340055D01*
X2950708Y341096D01*
X2949468Y341513D01*
G01X2914128Y362163D02*
Y374663D01*
X2908393Y365705D01*
X2916143D01*
G01X2924668Y362163D02*
Y374663D01*
X2922808Y372163D01*
G01Y362163D02*
X2926528D01*
G01X2937068Y361746D02*
X2936758Y361955D01*
Y362371D01*
X2937068Y362580D01*
X2937378Y362371D01*
Y361955D01*
X2937068Y361746D01*
G01X2949468Y374663D02*
X2948228Y374246D01*
X2947298Y373205D01*
X2946678Y371955D01*
X2946213Y370288D01*
X2946058Y368413D01*
X2946213Y366538D01*
X2946678Y364871D01*
X2947298Y363621D01*
X2948228Y362580D01*
X2949468Y362163D01*
X2950708Y362580D01*
X2951638Y363621D01*
X2952258Y364871D01*
X2952723Y366538D01*
X2952878Y368413D01*
X2952723Y370288D01*
X2952258Y371955D01*
X2951638Y373205D01*
X2950708Y374246D01*
X2949468Y374663D01*
G01X2908858Y397813D02*
X2909788Y396354D01*
X2911028Y395521D01*
X2912423Y395313D01*
X2913663Y395521D01*
X2914903Y396563D01*
X2915678Y397813D01*
X2915833Y399063D01*
X2915523Y400521D01*
X2914438Y401563D01*
X2913353Y401980D01*
X2911958D01*
G01X2913353D02*
X2914283Y402605D01*
X2915058Y403646D01*
X2915368Y404896D01*
X2915058Y406146D01*
X2914283Y407188D01*
X2912888Y407813D01*
X2911493Y407605D01*
X2910098Y406771D01*
G01X2924668Y407813D02*
X2923428Y407396D01*
X2922498Y406355D01*
X2921878Y405105D01*
X2921413Y403438D01*
X2921258Y401563D01*
X2921413Y399688D01*
X2921878Y398021D01*
X2922498Y396771D01*
X2923428Y395730D01*
X2924668Y395313D01*
X2925908Y395730D01*
X2926838Y396771D01*
X2927458Y398021D01*
X2927923Y399688D01*
X2928078Y401563D01*
X2927923Y403438D01*
X2927458Y405105D01*
X2926838Y406355D01*
X2925908Y407396D01*
X2924668Y407813D01*
G01X2937068Y394896D02*
X2936758Y395105D01*
Y395521D01*
X2937068Y395730D01*
X2937378Y395521D01*
Y395105D01*
X2937068Y394896D01*
G01X2949468Y407813D02*
X2948228Y407396D01*
X2947298Y406355D01*
X2946678Y405105D01*
X2946213Y403438D01*
X2946058Y401563D01*
X2946213Y399688D01*
X2946678Y398021D01*
X2947298Y396771D01*
X2948228Y395730D01*
X2949468Y395313D01*
X2950708Y395730D01*
X2951638Y396771D01*
X2952258Y398021D01*
X2952723Y399688D01*
X2952878Y401563D01*
X2952723Y403438D01*
X2952258Y405105D01*
X2951638Y406355D01*
X2950708Y407396D01*
X2949468Y407813D01*
G01X2903123Y438880D02*
X2904053Y440129D01*
X2905138Y440755D01*
X2906378Y440963D01*
X2907928Y440546D01*
X2909013Y439505D01*
X2909323Y438255D01*
X2909168Y437004D01*
X2908548Y435963D01*
X2905448Y433880D01*
X2904053Y432421D01*
X2903123Y430338D01*
X2902813Y428463D01*
X2909323D01*
G01X2915523Y438880D02*
X2916453Y440129D01*
X2917538Y440755D01*
X2918778Y440963D01*
X2920328Y440546D01*
X2921413Y439505D01*
X2921723Y438255D01*
X2921568Y437004D01*
X2920948Y435963D01*
X2917848Y433880D01*
X2916453Y432421D01*
X2915523Y430338D01*
X2915213Y428463D01*
X2921723D01*
G01X2930868D02*
Y440963D01*
X2929008Y438463D01*
G01Y428463D02*
X2932728D01*
G01X2943268Y428046D02*
X2942958Y428255D01*
Y428671D01*
X2943268Y428880D01*
X2943578Y428671D01*
Y428255D01*
X2943268Y428046D01*
G01X2955668Y440963D02*
X2954428Y440546D01*
X2953498Y439505D01*
X2952878Y438255D01*
X2952413Y436588D01*
X2952258Y434713D01*
X2952413Y432838D01*
X2952878Y431171D01*
X2953498Y429921D01*
X2954428Y428880D01*
X2955668Y428463D01*
X2956908Y428880D01*
X2957838Y429921D01*
X2958458Y431171D01*
X2958923Y432838D01*
X2959078Y434713D01*
X2958923Y436588D01*
X2958458Y438255D01*
X2957838Y439505D01*
X2956908Y440546D01*
X2955668Y440963D01*
G01X2906068Y461613D02*
Y474113D01*
X2904208Y471613D01*
G01Y461613D02*
X2907928D01*
G01X2915523Y466821D02*
X2916608Y468280D01*
X2917538Y469113D01*
X2918778Y469530D01*
X2919863Y469113D01*
X2920638Y468280D01*
X2921258Y467030D01*
X2921413Y465571D01*
X2921258Y464321D01*
X2920638Y463071D01*
X2919708Y462030D01*
X2918623Y461613D01*
X2917383Y462030D01*
X2916298Y463279D01*
X2915678Y465155D01*
X2915523Y467238D01*
X2915833Y469946D01*
X2916298Y471405D01*
X2917073Y472863D01*
X2918158Y473905D01*
X2919243Y474113D01*
X2920328Y473696D01*
X2921103Y472655D01*
G01X2927923Y466821D02*
X2929008Y468280D01*
X2929938Y469113D01*
X2931178Y469530D01*
X2932263Y469113D01*
X2933038Y468280D01*
X2933658Y467030D01*
X2933813Y465571D01*
X2933658Y464321D01*
X2933038Y463071D01*
X2932108Y462030D01*
X2931023Y461613D01*
X2929783Y462030D01*
X2928698Y463279D01*
X2928078Y465155D01*
X2927923Y467238D01*
X2928233Y469946D01*
X2928698Y471405D01*
X2929473Y472863D01*
X2930558Y473905D01*
X2931643Y474113D01*
X2932728Y473696D01*
X2933503Y472655D01*
G01X2943268Y461196D02*
X2942958Y461405D01*
Y461821D01*
X2943268Y462030D01*
X2943578Y461821D01*
Y461405D01*
X2943268Y461196D01*
G01X2955668Y474113D02*
X2954428Y473696D01*
X2953498Y472655D01*
X2952878Y471405D01*
X2952413Y469738D01*
X2952258Y467863D01*
X2952413Y465988D01*
X2952878Y464321D01*
X2953498Y463071D01*
X2954428Y462030D01*
X2955668Y461613D01*
X2956908Y462030D01*
X2957838Y463071D01*
X2958458Y464321D01*
X2958923Y465988D01*
X2959078Y467863D01*
X2958923Y469738D01*
X2958458Y471405D01*
X2957838Y472655D01*
X2956908Y473696D01*
X2955668Y474113D01*
G01X2906068Y494763D02*
Y507263D01*
X2904208Y504763D01*
G01Y494763D02*
X2907928D01*
G01X2915523Y505180D02*
X2916453Y506429D01*
X2917538Y507055D01*
X2918778Y507263D01*
X2920328Y506846D01*
X2921413Y505805D01*
X2921723Y504555D01*
X2921568Y503304D01*
X2920948Y502263D01*
X2917848Y500180D01*
X2916453Y498721D01*
X2915523Y496638D01*
X2915213Y494763D01*
X2921723D01*
G01X2927923Y499971D02*
X2929008Y501430D01*
X2929938Y502263D01*
X2931178Y502680D01*
X2932263Y502263D01*
X2933038Y501430D01*
X2933658Y500180D01*
X2933813Y498721D01*
X2933658Y497471D01*
X2933038Y496221D01*
X2932108Y495180D01*
X2931023Y494763D01*
X2929783Y495180D01*
X2928698Y496429D01*
X2928078Y498305D01*
X2927923Y500388D01*
X2928233Y503096D01*
X2928698Y504555D01*
X2929473Y506013D01*
X2930558Y507055D01*
X2931643Y507263D01*
X2932728Y506846D01*
X2933503Y505805D01*
G01X2943268Y494346D02*
X2942958Y494555D01*
Y494971D01*
X2943268Y495180D01*
X2943578Y494971D01*
Y494555D01*
X2943268Y494346D01*
G01X2955668Y507263D02*
X2954428Y506846D01*
X2953498Y505805D01*
X2952878Y504555D01*
X2952413Y502888D01*
X2952258Y501013D01*
X2952413Y499138D01*
X2952878Y497471D01*
X2953498Y496221D01*
X2954428Y495180D01*
X2955668Y494763D01*
X2956908Y495180D01*
X2957838Y496221D01*
X2958458Y497471D01*
X2958923Y499138D01*
X2959078Y501013D01*
X2958923Y502888D01*
X2958458Y504555D01*
X2957838Y505805D01*
X2956908Y506846D01*
X2955668Y507263D01*
G01X2911958Y527913D02*
X2912268Y530621D01*
X2912733Y532913D01*
X2913353Y534996D01*
X2914128Y537288D01*
X2915368Y540413D01*
X2909168D01*
G01X2922033Y529371D02*
X2923118Y528330D01*
X2924358Y527913D01*
X2925598Y528330D01*
X2926683Y529579D01*
X2927458Y531455D01*
X2927768Y533330D01*
Y535621D01*
X2927458Y537496D01*
X2926683Y539163D01*
X2925753Y539996D01*
X2924668Y540413D01*
X2923428Y539996D01*
X2922498Y539163D01*
X2921878Y537913D01*
X2921568Y536246D01*
X2921878Y534788D01*
X2922653Y533330D01*
X2923583Y532496D01*
X2924668Y532288D01*
X2925908Y532704D01*
X2926838Y533746D01*
X2927768Y535621D01*
G01X2937068Y527496D02*
X2936758Y527705D01*
Y528121D01*
X2937068Y528330D01*
X2937378Y528121D01*
Y527705D01*
X2937068Y527496D01*
G01X2949468Y540413D02*
X2948228Y539996D01*
X2947298Y538955D01*
X2946678Y537705D01*
X2946213Y536038D01*
X2946058Y534163D01*
X2946213Y532288D01*
X2946678Y530621D01*
X2947298Y529371D01*
X2948228Y528330D01*
X2949468Y527913D01*
X2950708Y528330D01*
X2951638Y529371D01*
X2952258Y530621D01*
X2952723Y532288D01*
X2952878Y534163D01*
X2952723Y536038D01*
X2952258Y537705D01*
X2951638Y538955D01*
X2950708Y539996D01*
X2949468Y540413D01*
G01X2909323Y566271D02*
X2910408Y567730D01*
X2911338Y568563D01*
X2912578Y568980D01*
X2913663Y568563D01*
X2914438Y567730D01*
X2915058Y566480D01*
X2915213Y565021D01*
X2915058Y563771D01*
X2914438Y562521D01*
X2913508Y561480D01*
X2912423Y561063D01*
X2911183Y561480D01*
X2910098Y562729D01*
X2909478Y564605D01*
X2909323Y566688D01*
X2909633Y569396D01*
X2910098Y570855D01*
X2910873Y572313D01*
X2911958Y573355D01*
X2913043Y573563D01*
X2914128Y573146D01*
X2914903Y572105D01*
G01X2924358Y561063D02*
X2924668Y563771D01*
X2925133Y566063D01*
X2925753Y568146D01*
X2926528Y570438D01*
X2927768Y573563D01*
X2921568D01*
G01X2937068Y560646D02*
X2936758Y560855D01*
Y561271D01*
X2937068Y561480D01*
X2937378Y561271D01*
Y560855D01*
X2937068Y560646D01*
G01X2949468Y573563D02*
X2948228Y573146D01*
X2947298Y572105D01*
X2946678Y570855D01*
X2946213Y569188D01*
X2946058Y567313D01*
X2946213Y565438D01*
X2946678Y563771D01*
X2947298Y562521D01*
X2948228Y561480D01*
X2949468Y561063D01*
X2950708Y561480D01*
X2951638Y562521D01*
X2952258Y563771D01*
X2952723Y565438D01*
X2952878Y567313D01*
X2952723Y569188D01*
X2952258Y570855D01*
X2951638Y572105D01*
X2950708Y573146D01*
X2949468Y573563D01*
G01X2914128Y594213D02*
Y606713D01*
X2908393Y597755D01*
X2916143D01*
G01X2926528Y594213D02*
Y606713D01*
X2920793Y597755D01*
X2928543D01*
G01X2937068Y593796D02*
X2936758Y594005D01*
Y594421D01*
X2937068Y594630D01*
X2937378Y594421D01*
Y594005D01*
X2937068Y593796D01*
G01X2949468Y606713D02*
X2948228Y606296D01*
X2947298Y605255D01*
X2946678Y604005D01*
X2946213Y602338D01*
X2946058Y600463D01*
X2946213Y598588D01*
X2946678Y596921D01*
X2947298Y595671D01*
X2948228Y594630D01*
X2949468Y594213D01*
X2950708Y594630D01*
X2951638Y595671D01*
X2952258Y596921D01*
X2952723Y598588D01*
X2952878Y600463D01*
X2952723Y602338D01*
X2952258Y604005D01*
X2951638Y605255D01*
X2950708Y606296D01*
X2949468Y606713D01*
G01X2914128Y627363D02*
Y639863D01*
X2908393Y630905D01*
X2916143D01*
G01X2924668Y627363D02*
Y639863D01*
X2922808Y637363D01*
G01Y627363D02*
X2926528D01*
G01X2937068Y626946D02*
X2936758Y627155D01*
Y627571D01*
X2937068Y627780D01*
X2937378Y627571D01*
Y627155D01*
X2937068Y626946D01*
G01X2949468Y639863D02*
X2948228Y639446D01*
X2947298Y638405D01*
X2946678Y637155D01*
X2946213Y635488D01*
X2946058Y633613D01*
X2946213Y631738D01*
X2946678Y630071D01*
X2947298Y628821D01*
X2948228Y627780D01*
X2949468Y627363D01*
X2950708Y627780D01*
X2951638Y628821D01*
X2952258Y630071D01*
X2952723Y631738D01*
X2952878Y633613D01*
X2952723Y635488D01*
X2952258Y637155D01*
X2951638Y638405D01*
X2950708Y639446D01*
X2949468Y639863D01*
G01X2902658Y663013D02*
X2903588Y661554D01*
X2904828Y660721D01*
X2906223Y660513D01*
X2907463Y660721D01*
X2908703Y661763D01*
X2909478Y663013D01*
X2909633Y664263D01*
X2909323Y665721D01*
X2908238Y666763D01*
X2907153Y667180D01*
X2905758D01*
G01X2907153D02*
X2908083Y667805D01*
X2908858Y668846D01*
X2909168Y670096D01*
X2908858Y671346D01*
X2908083Y672388D01*
X2906688Y673013D01*
X2905293Y672805D01*
X2903898Y671971D01*
G01X2915833Y661971D02*
X2916918Y660930D01*
X2918158Y660513D01*
X2919398Y660930D01*
X2920483Y662179D01*
X2921258Y664055D01*
X2921568Y665930D01*
Y668221D01*
X2921258Y670096D01*
X2920483Y671763D01*
X2919553Y672596D01*
X2918468Y673013D01*
X2917228Y672596D01*
X2916298Y671763D01*
X2915678Y670513D01*
X2915368Y668846D01*
X2915678Y667388D01*
X2916453Y665930D01*
X2917383Y665096D01*
X2918468Y664888D01*
X2919708Y665304D01*
X2920638Y666346D01*
X2921568Y668221D01*
G01X2930868Y660096D02*
X2930558Y660305D01*
Y660721D01*
X2930868Y660930D01*
X2931178Y660721D01*
Y660305D01*
X2930868Y660096D01*
G01X2940633Y661971D02*
X2941718Y660930D01*
X2942958Y660513D01*
X2944198Y660930D01*
X2945283Y662179D01*
X2946058Y664055D01*
X2946368Y665930D01*
Y668221D01*
X2946058Y670096D01*
X2945283Y671763D01*
X2944353Y672596D01*
X2943268Y673013D01*
X2942028Y672596D01*
X2941098Y671763D01*
X2940478Y670513D01*
X2940168Y668846D01*
X2940478Y667388D01*
X2941253Y665930D01*
X2942183Y665096D01*
X2943268Y664888D01*
X2944508Y665304D01*
X2945438Y666346D01*
X2946368Y668221D01*
G01X2953033Y661971D02*
X2954118Y660930D01*
X2955358Y660513D01*
X2956598Y660930D01*
X2957683Y662179D01*
X2958458Y664055D01*
X2958768Y665930D01*
Y668221D01*
X2958458Y670096D01*
X2957683Y671763D01*
X2956753Y672596D01*
X2955668Y673013D01*
X2954428Y672596D01*
X2953498Y671763D01*
X2952878Y670513D01*
X2952568Y668846D01*
X2952878Y667388D01*
X2953653Y665930D01*
X2954583Y665096D01*
X2955668Y664888D01*
X2956908Y665304D01*
X2957838Y666346D01*
X2958768Y668221D01*
G01X2908858Y696163D02*
X2909788Y694704D01*
X2911028Y693871D01*
X2912423Y693663D01*
X2913663Y693871D01*
X2914903Y694913D01*
X2915678Y696163D01*
X2915833Y697413D01*
X2915523Y698871D01*
X2914438Y699913D01*
X2913353Y700330D01*
X2911958D01*
G01X2913353D02*
X2914283Y700955D01*
X2915058Y701996D01*
X2915368Y703246D01*
X2915058Y704496D01*
X2914283Y705538D01*
X2912888Y706163D01*
X2911493Y705955D01*
X2910098Y705121D01*
G01X2921723Y704080D02*
X2922653Y705329D01*
X2923738Y705955D01*
X2924978Y706163D01*
X2926528Y705746D01*
X2927613Y704705D01*
X2927923Y703455D01*
X2927768Y702204D01*
X2927148Y701163D01*
X2924048Y699080D01*
X2922653Y697621D01*
X2921723Y695538D01*
X2921413Y693663D01*
X2927923D01*
G01X2937068Y693246D02*
X2936758Y693455D01*
Y693871D01*
X2937068Y694080D01*
X2937378Y693871D01*
Y693455D01*
X2937068Y693246D01*
G01X2949468Y706163D02*
X2948228Y705746D01*
X2947298Y704705D01*
X2946678Y703455D01*
X2946213Y701788D01*
X2946058Y699913D01*
X2946213Y698038D01*
X2946678Y696371D01*
X2947298Y695121D01*
X2948228Y694080D01*
X2949468Y693663D01*
X2950708Y694080D01*
X2951638Y695121D01*
X2952258Y696371D01*
X2952723Y698038D01*
X2952878Y699913D01*
X2952723Y701788D01*
X2952258Y703455D01*
X2951638Y704705D01*
X2950708Y705746D01*
X2949468Y706163D01*
G01X2909323Y737230D02*
X2910253Y738479D01*
X2911338Y739105D01*
X2912578Y739313D01*
X2914128Y738896D01*
X2915213Y737855D01*
X2915523Y736605D01*
X2915368Y735354D01*
X2914748Y734313D01*
X2911648Y732230D01*
X2910253Y730771D01*
X2909323Y728688D01*
X2909013Y726813D01*
X2915523D01*
G01X2921723Y737230D02*
X2922653Y738479D01*
X2923738Y739105D01*
X2924978Y739313D01*
X2926528Y738896D01*
X2927613Y737855D01*
X2927923Y736605D01*
X2927768Y735354D01*
X2927148Y734313D01*
X2924048Y732230D01*
X2922653Y730771D01*
X2921723Y728688D01*
X2921413Y726813D01*
X2927923D01*
G01X2937068Y726396D02*
X2936758Y726605D01*
Y727021D01*
X2937068Y727230D01*
X2937378Y727021D01*
Y726605D01*
X2937068Y726396D01*
G01X2949468Y739313D02*
X2948228Y738896D01*
X2947298Y737855D01*
X2946678Y736605D01*
X2946213Y734938D01*
X2946058Y733063D01*
X2946213Y731188D01*
X2946678Y729521D01*
X2947298Y728271D01*
X2948228Y727230D01*
X2949468Y726813D01*
X2950708Y727230D01*
X2951638Y728271D01*
X2952258Y729521D01*
X2952723Y731188D01*
X2952878Y733063D01*
X2952723Y734938D01*
X2952258Y736605D01*
X2951638Y737855D01*
X2950708Y738896D01*
X2949468Y739313D01*
G01X2906068Y759963D02*
Y772463D01*
X2904208Y769963D01*
G01Y759963D02*
X2907928D01*
G01X2915833Y761421D02*
X2916918Y760380D01*
X2918158Y759963D01*
X2919398Y760380D01*
X2920483Y761629D01*
X2921258Y763505D01*
X2921568Y765380D01*
Y767671D01*
X2921258Y769546D01*
X2920483Y771213D01*
X2919553Y772046D01*
X2918468Y772463D01*
X2917228Y772046D01*
X2916298Y771213D01*
X2915678Y769963D01*
X2915368Y768296D01*
X2915678Y766838D01*
X2916453Y765380D01*
X2917383Y764546D01*
X2918468Y764338D01*
X2919708Y764754D01*
X2920638Y765796D01*
X2921568Y767671D01*
G01X2930868Y759546D02*
X2930558Y759755D01*
Y760171D01*
X2930868Y760380D01*
X2931178Y760171D01*
Y759755D01*
X2930868Y759546D01*
G01X2940323Y765171D02*
X2941408Y766630D01*
X2942338Y767463D01*
X2943578Y767880D01*
X2944663Y767463D01*
X2945438Y766630D01*
X2946058Y765380D01*
X2946213Y763921D01*
X2946058Y762671D01*
X2945438Y761421D01*
X2944508Y760380D01*
X2943423Y759963D01*
X2942183Y760380D01*
X2941098Y761629D01*
X2940478Y763505D01*
X2940323Y765588D01*
X2940633Y768296D01*
X2941098Y769755D01*
X2941873Y771213D01*
X2942958Y772255D01*
X2944043Y772463D01*
X2945128Y772046D01*
X2945903Y771005D01*
G01X2955668Y759963D02*
X2956753Y760171D01*
X2957993Y760796D01*
X2958768Y761838D01*
X2959078Y763296D01*
X2958768Y764754D01*
X2957838Y766005D01*
X2956443Y766630D01*
X2954893D01*
X2953963Y767046D01*
X2953188Y768088D01*
X2952878Y769546D01*
X2953343Y771005D01*
X2954428Y772046D01*
X2955668Y772463D01*
X2956908Y772046D01*
X2957993Y771005D01*
X2958458Y769546D01*
X2958148Y768088D01*
X2957373Y767046D01*
X2956443Y766630D01*
X2954893D01*
X2953498Y766005D01*
X2952568Y764754D01*
X2952258Y763296D01*
X2952568Y761838D01*
X2953343Y760796D01*
X2954583Y760171D01*
X2955668Y759963D01*
G01X2912268Y793113D02*
Y805613D01*
X2910408Y803113D01*
G01Y793113D02*
X2914128D01*
G01X2921723Y803530D02*
X2922653Y804779D01*
X2923738Y805405D01*
X2924978Y805613D01*
X2926528Y805196D01*
X2927613Y804155D01*
X2927923Y802905D01*
X2927768Y801654D01*
X2927148Y800613D01*
X2924048Y798530D01*
X2922653Y797071D01*
X2921723Y794988D01*
X2921413Y793113D01*
X2927923D01*
G01X2937068Y792696D02*
X2936758Y792905D01*
Y793321D01*
X2937068Y793530D01*
X2937378Y793321D01*
Y792905D01*
X2937068Y792696D01*
G01X2946523Y803530D02*
X2947453Y804779D01*
X2948538Y805405D01*
X2949778Y805613D01*
X2951328Y805196D01*
X2952413Y804155D01*
X2952723Y802905D01*
X2952568Y801654D01*
X2951948Y800613D01*
X2948848Y798530D01*
X2947453Y797071D01*
X2946523Y794988D01*
X2946213Y793113D01*
X2952723D01*
G01X2912268Y826263D02*
Y838763D01*
X2910408Y836263D01*
G01Y826263D02*
X2914128D01*
G01X2924668Y838763D02*
X2923428Y838346D01*
X2922498Y837305D01*
X2921878Y836055D01*
X2921413Y834388D01*
X2921258Y832513D01*
X2921413Y830638D01*
X2921878Y828971D01*
X2922498Y827721D01*
X2923428Y826680D01*
X2924668Y826263D01*
X2925908Y826680D01*
X2926838Y827721D01*
X2927458Y828971D01*
X2927923Y830638D01*
X2928078Y832513D01*
X2927923Y834388D01*
X2927458Y836055D01*
X2926838Y837305D01*
X2925908Y838346D01*
X2924668Y838763D01*
G01X2937068Y825846D02*
X2936758Y826055D01*
Y826471D01*
X2937068Y826680D01*
X2937378Y826471D01*
Y826055D01*
X2937068Y825846D01*
G01X2949468Y838763D02*
X2948228Y838346D01*
X2947298Y837305D01*
X2946678Y836055D01*
X2946213Y834388D01*
X2946058Y832513D01*
X2946213Y830638D01*
X2946678Y828971D01*
X2947298Y827721D01*
X2948228Y826680D01*
X2949468Y826263D01*
X2950708Y826680D01*
X2951638Y827721D01*
X2952258Y828971D01*
X2952723Y830638D01*
X2952878Y832513D01*
X2952723Y834388D01*
X2952258Y836055D01*
X2951638Y837305D01*
X2950708Y838346D01*
X2949468Y838763D01*
G01X2912268Y859413D02*
Y871913D01*
X2910408Y869413D01*
G01Y859413D02*
X2914128D01*
G01X2924668Y871913D02*
X2923428Y871496D01*
X2922498Y870455D01*
X2921878Y869205D01*
X2921413Y867538D01*
X2921258Y865663D01*
X2921413Y863788D01*
X2921878Y862121D01*
X2922498Y860871D01*
X2923428Y859830D01*
X2924668Y859413D01*
X2925908Y859830D01*
X2926838Y860871D01*
X2927458Y862121D01*
X2927923Y863788D01*
X2928078Y865663D01*
X2927923Y867538D01*
X2927458Y869205D01*
X2926838Y870455D01*
X2925908Y871496D01*
X2924668Y871913D01*
G01X2937068Y858996D02*
X2936758Y859205D01*
Y859621D01*
X2937068Y859830D01*
X2937378Y859621D01*
Y859205D01*
X2937068Y858996D01*
G01X2949468Y871913D02*
X2948228Y871496D01*
X2947298Y870455D01*
X2946678Y869205D01*
X2946213Y867538D01*
X2946058Y865663D01*
X2946213Y863788D01*
X2946678Y862121D01*
X2947298Y860871D01*
X2948228Y859830D01*
X2949468Y859413D01*
X2950708Y859830D01*
X2951638Y860871D01*
X2952258Y862121D01*
X2952723Y863788D01*
X2952878Y865663D01*
X2952723Y867538D01*
X2952258Y869205D01*
X2951638Y870455D01*
X2950708Y871496D01*
X2949468Y871913D01*
G01X2909633Y894021D02*
X2910718Y892980D01*
X2911958Y892563D01*
X2913198Y892980D01*
X2914283Y894229D01*
X2915058Y896105D01*
X2915368Y897980D01*
Y900271D01*
X2915058Y902146D01*
X2914283Y903813D01*
X2913353Y904646D01*
X2912268Y905063D01*
X2911028Y904646D01*
X2910098Y903813D01*
X2909478Y902563D01*
X2909168Y900896D01*
X2909478Y899438D01*
X2910253Y897980D01*
X2911183Y897146D01*
X2912268Y896938D01*
X2913508Y897354D01*
X2914438Y898396D01*
X2915368Y900271D01*
G01X2924668Y892146D02*
X2924358Y892355D01*
Y892771D01*
X2924668Y892980D01*
X2924978Y892771D01*
Y892355D01*
X2924668Y892146D01*
G01X2937068Y892563D02*
X2938153Y892771D01*
X2939393Y893396D01*
X2940168Y894438D01*
X2940478Y895896D01*
X2940168Y897354D01*
X2939238Y898605D01*
X2937843Y899230D01*
X2936293D01*
X2935363Y899646D01*
X2934588Y900688D01*
X2934278Y902146D01*
X2934743Y903605D01*
X2935828Y904646D01*
X2937068Y905063D01*
X2938308Y904646D01*
X2939393Y903605D01*
X2939858Y902146D01*
X2939548Y900688D01*
X2938773Y899646D01*
X2937843Y899230D01*
X2936293D01*
X2934898Y898605D01*
X2933968Y897354D01*
X2933658Y895896D01*
X2933968Y894438D01*
X2934743Y893396D01*
X2935983Y892771D01*
X2937068Y892563D01*
G01X2951328D02*
Y905063D01*
X2945593Y896105D01*
X2953343D01*
G01X2902736Y1266553D02*
X2906456D01*
G01X2904596D02*
Y1254053D01*
G01X2902736D02*
X2906456D01*
G01X2913431D02*
Y1266553D01*
X2920561Y1254053D01*
Y1266553D01*
G01X2931256Y1254053D02*
Y1266553D01*
X2925521Y1257595D01*
X2933271D01*
G01X2902736Y1291553D02*
X2906456D01*
G01X2904596D02*
Y1279053D01*
G01X2902736D02*
X2906456D01*
G01X2913431D02*
Y1291553D01*
X2920561Y1279053D01*
Y1291553D01*
G01X2931256Y1279053D02*
Y1291553D01*
X2925521Y1282595D01*
X2933271D01*
G01X2902736Y1316553D02*
X2906456D01*
G01X2904596D02*
Y1304053D01*
G01X2902736D02*
X2906456D01*
G01X2913431D02*
Y1316553D01*
X2920561Y1304053D01*
Y1316553D01*
G01X2931256Y1304053D02*
Y1316553D01*
X2925521Y1307595D01*
X2933271D01*
G01X2902736Y1616571D02*
X2906456D01*
G01X2904596D02*
Y1604071D01*
G01X2902736D02*
X2906456D01*
G01X2913431D02*
Y1616571D01*
X2920561Y1604071D01*
Y1616571D01*
G01X2929396Y1604071D02*
Y1616571D01*
X2927536Y1614071D01*
G01Y1604071D02*
X2931256D01*
G01X2902736Y1641571D02*
X2906456D01*
G01X2904596D02*
Y1629071D01*
G01X2902736D02*
X2906456D01*
G01X2913431D02*
Y1641571D01*
X2920561Y1629071D01*
Y1641571D01*
G01X2929396Y1629071D02*
Y1641571D01*
X2927536Y1639071D01*
G01Y1629071D02*
X2931256D01*
G01X2902736Y1666571D02*
X2906456D01*
G01X2904596D02*
Y1654071D01*
G01X2902736D02*
X2906456D01*
G01X2913431D02*
Y1666571D01*
X2920561Y1654071D01*
Y1666571D01*
G01X2929396Y1654071D02*
Y1666571D01*
X2927536Y1664071D01*
G01Y1654071D02*
X2931256D01*
G01X2918468Y925713D02*
X2919553Y925921D01*
X2920793Y926546D01*
X2921568Y927588D01*
X2921878Y929046D01*
X2921568Y930504D01*
X2920638Y931755D01*
X2919243Y932380D01*
X2917693D01*
X2916763Y932796D01*
X2915988Y933838D01*
X2915678Y935296D01*
X2916143Y936755D01*
X2917228Y937796D01*
X2918468Y938213D01*
X2919708Y937796D01*
X2920793Y936755D01*
X2921258Y935296D01*
X2920948Y933838D01*
X2920173Y932796D01*
X2919243Y932380D01*
X2917693D01*
X2916298Y931755D01*
X2915368Y930504D01*
X2915058Y929046D01*
X2915368Y927588D01*
X2916143Y926546D01*
X2917383Y925921D01*
X2918468Y925713D01*
G01X2930868Y925296D02*
X2930558Y925505D01*
Y925921D01*
X2930868Y926130D01*
X2931178Y925921D01*
Y925505D01*
X2930868Y925296D01*
G01X2943268Y938213D02*
X2942028Y937796D01*
X2941098Y936755D01*
X2940478Y935505D01*
X2940013Y933838D01*
X2939858Y931963D01*
X2940013Y930088D01*
X2940478Y928421D01*
X2941098Y927171D01*
X2942028Y926130D01*
X2943268Y925713D01*
X2944508Y926130D01*
X2945438Y927171D01*
X2946058Y928421D01*
X2946523Y930088D01*
X2946678Y931963D01*
X2946523Y933838D01*
X2946058Y935505D01*
X2945438Y936755D01*
X2944508Y937796D01*
X2943268Y938213D01*
G01X2918468Y958863D02*
X2919553Y959071D01*
X2920793Y959696D01*
X2921568Y960738D01*
X2921878Y962196D01*
X2921568Y963654D01*
X2920638Y964905D01*
X2919243Y965530D01*
X2917693D01*
X2916763Y965946D01*
X2915988Y966988D01*
X2915678Y968446D01*
X2916143Y969905D01*
X2917228Y970946D01*
X2918468Y971363D01*
X2919708Y970946D01*
X2920793Y969905D01*
X2921258Y968446D01*
X2920948Y966988D01*
X2920173Y965946D01*
X2919243Y965530D01*
X2917693D01*
X2916298Y964905D01*
X2915368Y963654D01*
X2915058Y962196D01*
X2915368Y960738D01*
X2916143Y959696D01*
X2917383Y959071D01*
X2918468Y958863D01*
G01X2930868Y958446D02*
X2930558Y958655D01*
Y959071D01*
X2930868Y959280D01*
X2931178Y959071D01*
Y958655D01*
X2930868Y958446D01*
G01X2943268Y971363D02*
X2942028Y970946D01*
X2941098Y969905D01*
X2940478Y968655D01*
X2940013Y966988D01*
X2939858Y965113D01*
X2940013Y963238D01*
X2940478Y961571D01*
X2941098Y960321D01*
X2942028Y959280D01*
X2943268Y958863D01*
X2944508Y959280D01*
X2945438Y960321D01*
X2946058Y961571D01*
X2946523Y963238D01*
X2946678Y965113D01*
X2946523Y966988D01*
X2946058Y968655D01*
X2945438Y969905D01*
X2944508Y970946D01*
X2943268Y971363D01*
G01X2959034Y2427151D02*
Y2439651D01*
X2963064Y2429234D01*
X2967094Y2439651D01*
Y2427151D01*
G01X2971589D02*
X2975464Y2439651D01*
X2979339Y2427151D01*
G01X2977944Y2431526D02*
X2972984D01*
G01X2984609Y2427151D02*
X2991119Y2439651D01*
G01X2984609D02*
X2991119Y2427151D01*
G01X2995614Y2422984D02*
X3004914D01*
G01X3009254Y2427151D02*
Y2439651D01*
X3012354D01*
X3013594Y2439026D01*
X3014524Y2438193D01*
X3015299Y2436943D01*
X3015919Y2435484D01*
X3016074Y2433401D01*
X3015919Y2431318D01*
X3015299Y2429859D01*
X3014524Y2428609D01*
X3013594Y2427776D01*
X3012354Y2427151D01*
X3009254D01*
G01X3028164D02*
X3021964D01*
Y2439651D01*
X3028164D01*
G01X3025684Y2433609D02*
X3021964D01*
G01X3034364Y2427151D02*
Y2439651D01*
X3038084D01*
X3039324Y2439026D01*
X3040254Y2437568D01*
X3040564Y2435901D01*
X3040254Y2434234D01*
X3039479Y2432984D01*
X3038084Y2432359D01*
X3034364D01*
G01X3049864Y2439651D02*
Y2427151D01*
G01X3046299Y2439651D02*
X3053429D01*
G01X3059009Y2427151D02*
Y2439651D01*
G01X3065519D02*
Y2427151D01*
G01Y2433401D02*
X3059009D01*
G01X2972761Y2787463D02*
Y2799963D01*
X2976791Y2789546D01*
X2980821Y2799963D01*
Y2787463D01*
G01X2985316D02*
X2989191Y2799963D01*
X2993066Y2787463D01*
G01X2991671Y2791838D02*
X2986711D01*
G01X2998336Y2787463D02*
X3004846Y2799963D01*
G01X2998336D02*
X3004846Y2787463D01*
G01X3009341Y2783296D02*
X3018641D01*
G01X3022981Y2787463D02*
Y2799963D01*
X3026081D01*
X3027321Y2799338D01*
X3028251Y2798505D01*
X3029026Y2797255D01*
X3029646Y2795796D01*
X3029801Y2793713D01*
X3029646Y2791630D01*
X3029026Y2790171D01*
X3028251Y2788921D01*
X3027321Y2788088D01*
X3026081Y2787463D01*
X3022981D01*
G01X3041891D02*
X3035691D01*
Y2799963D01*
X3041891D01*
G01X3039411Y2793921D02*
X3035691D01*
G01X3048091Y2787463D02*
Y2799963D01*
X3051811D01*
X3053051Y2799338D01*
X3053981Y2797880D01*
X3054291Y2796213D01*
X3053981Y2794546D01*
X3053206Y2793296D01*
X3051811Y2792671D01*
X3048091D01*
G01X3063591Y2799963D02*
Y2787463D01*
G01X3060026Y2799963D02*
X3067156D01*
G01X3072736Y2787463D02*
Y2799963D01*
G01X3079246D02*
Y2787463D01*
G01Y2793713D02*
X3072736D01*
G01X2984919Y2362568D02*
X2985849Y2363817D01*
X2986934Y2364443D01*
X2988174Y2364651D01*
X2989724Y2364234D01*
X2990809Y2363193D01*
X2991119Y2361943D01*
X2990964Y2360692D01*
X2990344Y2359651D01*
X2987244Y2357568D01*
X2985849Y2356109D01*
X2984919Y2354026D01*
X2984609Y2352151D01*
X2991119D01*
G01X2996854Y2354026D02*
X2997784Y2352984D01*
X2998869Y2352359D01*
X3000264Y2352151D01*
X3001659Y2352568D01*
X3002744Y2353401D01*
X3003519Y2354859D01*
X3003674Y2356526D01*
X3003364Y2358193D01*
X3002589Y2359234D01*
X3001504Y2360068D01*
X3000419Y2360276D01*
X2999334Y2360068D01*
X2997939Y2359234D01*
X2998404Y2364651D01*
X3002589D01*
G01X3012664Y2351734D02*
X3012354Y2351943D01*
Y2352359D01*
X3012664Y2352568D01*
X3012974Y2352359D01*
Y2351943D01*
X3012664Y2351734D01*
G01X3025064Y2352151D02*
X3026149Y2352359D01*
X3027389Y2352984D01*
X3028164Y2354026D01*
X3028474Y2355484D01*
X3028164Y2356942D01*
X3027234Y2358193D01*
X3025839Y2358818D01*
X3024289D01*
X3023359Y2359234D01*
X3022584Y2360276D01*
X3022274Y2361734D01*
X3022739Y2363193D01*
X3023824Y2364234D01*
X3025064Y2364651D01*
X3026304Y2364234D01*
X3027389Y2363193D01*
X3027854Y2361734D01*
X3027544Y2360276D01*
X3026769Y2359234D01*
X3025839Y2358818D01*
X3024289D01*
X3022894Y2358193D01*
X3021964Y2356942D01*
X3021654Y2355484D01*
X3021964Y2354026D01*
X3022739Y2352984D01*
X3023979Y2352359D01*
X3025064Y2352151D01*
G01X3034054Y2354026D02*
X3034984Y2352984D01*
X3036069Y2352359D01*
X3037464Y2352151D01*
X3038859Y2352568D01*
X3039944Y2353401D01*
X3040719Y2354859D01*
X3040874Y2356526D01*
X3040564Y2358193D01*
X3039789Y2359234D01*
X3038704Y2360068D01*
X3037619Y2360276D01*
X3036534Y2360068D01*
X3035139Y2359234D01*
X3035604Y2364651D01*
X3039789D01*
G01X2984919Y2387568D02*
X2985849Y2388817D01*
X2986934Y2389443D01*
X2988174Y2389651D01*
X2989724Y2389234D01*
X2990809Y2388193D01*
X2991119Y2386943D01*
X2990964Y2385692D01*
X2990344Y2384651D01*
X2987244Y2382568D01*
X2985849Y2381109D01*
X2984919Y2379026D01*
X2984609Y2377151D01*
X2991119D01*
G01X2996854Y2379026D02*
X2997784Y2377984D01*
X2998869Y2377359D01*
X3000264Y2377151D01*
X3001659Y2377568D01*
X3002744Y2378401D01*
X3003519Y2379859D01*
X3003674Y2381526D01*
X3003364Y2383193D01*
X3002589Y2384234D01*
X3001504Y2385068D01*
X3000419Y2385276D01*
X2999334Y2385068D01*
X2997939Y2384234D01*
X2998404Y2389651D01*
X3002589D01*
G01X3012664Y2376734D02*
X3012354Y2376943D01*
Y2377359D01*
X3012664Y2377568D01*
X3012974Y2377359D01*
Y2376943D01*
X3012664Y2376734D01*
G01X3025064Y2377151D02*
X3026149Y2377359D01*
X3027389Y2377984D01*
X3028164Y2379026D01*
X3028474Y2380484D01*
X3028164Y2381942D01*
X3027234Y2383193D01*
X3025839Y2383818D01*
X3024289D01*
X3023359Y2384234D01*
X3022584Y2385276D01*
X3022274Y2386734D01*
X3022739Y2388193D01*
X3023824Y2389234D01*
X3025064Y2389651D01*
X3026304Y2389234D01*
X3027389Y2388193D01*
X3027854Y2386734D01*
X3027544Y2385276D01*
X3026769Y2384234D01*
X3025839Y2383818D01*
X3024289D01*
X3022894Y2383193D01*
X3021964Y2381942D01*
X3021654Y2380484D01*
X3021964Y2379026D01*
X3022739Y2377984D01*
X3023979Y2377359D01*
X3025064Y2377151D01*
G01X3034054Y2379026D02*
X3034984Y2377984D01*
X3036069Y2377359D01*
X3037464Y2377151D01*
X3038859Y2377568D01*
X3039944Y2378401D01*
X3040719Y2379859D01*
X3040874Y2381526D01*
X3040564Y2383193D01*
X3039789Y2384234D01*
X3038704Y2385068D01*
X3037619Y2385276D01*
X3036534Y2385068D01*
X3035139Y2384234D01*
X3035604Y2389651D01*
X3039789D01*
G01X2984919Y2412568D02*
X2985849Y2413817D01*
X2986934Y2414443D01*
X2988174Y2414651D01*
X2989724Y2414234D01*
X2990809Y2413193D01*
X2991119Y2411943D01*
X2990964Y2410692D01*
X2990344Y2409651D01*
X2987244Y2407568D01*
X2985849Y2406109D01*
X2984919Y2404026D01*
X2984609Y2402151D01*
X2991119D01*
G01X2996854Y2404026D02*
X2997784Y2402984D01*
X2998869Y2402359D01*
X3000264Y2402151D01*
X3001659Y2402568D01*
X3002744Y2403401D01*
X3003519Y2404859D01*
X3003674Y2406526D01*
X3003364Y2408193D01*
X3002589Y2409234D01*
X3001504Y2410068D01*
X3000419Y2410276D01*
X2999334Y2410068D01*
X2997939Y2409234D01*
X2998404Y2414651D01*
X3002589D01*
G01X3012664Y2401734D02*
X3012354Y2401943D01*
Y2402359D01*
X3012664Y2402568D01*
X3012974Y2402359D01*
Y2401943D01*
X3012664Y2401734D01*
G01X3025064Y2402151D02*
X3026149Y2402359D01*
X3027389Y2402984D01*
X3028164Y2404026D01*
X3028474Y2405484D01*
X3028164Y2406942D01*
X3027234Y2408193D01*
X3025839Y2408818D01*
X3024289D01*
X3023359Y2409234D01*
X3022584Y2410276D01*
X3022274Y2411734D01*
X3022739Y2413193D01*
X3023824Y2414234D01*
X3025064Y2414651D01*
X3026304Y2414234D01*
X3027389Y2413193D01*
X3027854Y2411734D01*
X3027544Y2410276D01*
X3026769Y2409234D01*
X3025839Y2408818D01*
X3024289D01*
X3022894Y2408193D01*
X3021964Y2406942D01*
X3021654Y2405484D01*
X3021964Y2404026D01*
X3022739Y2402984D01*
X3023979Y2402359D01*
X3025064Y2402151D01*
G01X3034054Y2404026D02*
X3034984Y2402984D01*
X3036069Y2402359D01*
X3037464Y2402151D01*
X3038859Y2402568D01*
X3039944Y2403401D01*
X3040719Y2404859D01*
X3040874Y2406526D01*
X3040564Y2408193D01*
X3039789Y2409234D01*
X3038704Y2410068D01*
X3037619Y2410276D01*
X3036534Y2410068D01*
X3035139Y2409234D01*
X3035604Y2414651D01*
X3039789D01*
G01X2993350Y2042816D02*
Y2055316D01*
X2997380Y2044899D01*
X3001410Y2055316D01*
Y2042816D01*
G01X3005905D02*
X3009780Y2055316D01*
X3013655Y2042816D01*
G01X3012260Y2047191D02*
X3007300D01*
G01X3018925Y2042816D02*
X3025435Y2055316D01*
G01X3018925D02*
X3025435Y2042816D01*
G01X3029930Y2038649D02*
X3039230D01*
G01X3043570Y2042816D02*
Y2055316D01*
X3046670D01*
X3047910Y2054691D01*
X3048840Y2053858D01*
X3049615Y2052608D01*
X3050235Y2051149D01*
X3050390Y2049066D01*
X3050235Y2046983D01*
X3049615Y2045524D01*
X3048840Y2044274D01*
X3047910Y2043441D01*
X3046670Y2042816D01*
X3043570D01*
G01X3062480D02*
X3056280D01*
Y2055316D01*
X3062480D01*
G01X3060000Y2049274D02*
X3056280D01*
G01X3068680Y2042816D02*
Y2055316D01*
X3072400D01*
X3073640Y2054691D01*
X3074570Y2053233D01*
X3074880Y2051566D01*
X3074570Y2049899D01*
X3073795Y2048649D01*
X3072400Y2048024D01*
X3068680D01*
G01X3084180Y2055316D02*
Y2042816D01*
G01X3080615Y2055316D02*
X3087745D01*
G01X3093325Y2042816D02*
Y2055316D01*
G01X3099835D02*
Y2042816D01*
G01Y2049066D02*
X3093325D01*
G01X3005156Y2713921D02*
X3006241Y2712880D01*
X3007481Y2712463D01*
X3008721Y2712880D01*
X3009806Y2714129D01*
X3010581Y2716005D01*
X3010891Y2717880D01*
Y2720171D01*
X3010581Y2722046D01*
X3009806Y2723713D01*
X3008876Y2724546D01*
X3007791Y2724963D01*
X3006551Y2724546D01*
X3005621Y2723713D01*
X3005001Y2722463D01*
X3004691Y2720796D01*
X3005001Y2719338D01*
X3005776Y2717880D01*
X3006706Y2717046D01*
X3007791Y2716838D01*
X3009031Y2717254D01*
X3009961Y2718296D01*
X3010891Y2720171D01*
G01X3020191Y2712046D02*
X3019881Y2712255D01*
Y2712671D01*
X3020191Y2712880D01*
X3020501Y2712671D01*
Y2712255D01*
X3020191Y2712046D01*
G01X3029956Y2713921D02*
X3031041Y2712880D01*
X3032281Y2712463D01*
X3033521Y2712880D01*
X3034606Y2714129D01*
X3035381Y2716005D01*
X3035691Y2717880D01*
Y2720171D01*
X3035381Y2722046D01*
X3034606Y2723713D01*
X3033676Y2724546D01*
X3032591Y2724963D01*
X3031351Y2724546D01*
X3030421Y2723713D01*
X3029801Y2722463D01*
X3029491Y2720796D01*
X3029801Y2719338D01*
X3030576Y2717880D01*
X3031506Y2717046D01*
X3032591Y2716838D01*
X3033831Y2717254D01*
X3034761Y2718296D01*
X3035691Y2720171D01*
G01X3041581Y2714338D02*
X3042511Y2713296D01*
X3043596Y2712671D01*
X3044991Y2712463D01*
X3046386Y2712880D01*
X3047471Y2713713D01*
X3048246Y2715171D01*
X3048401Y2716838D01*
X3048091Y2718505D01*
X3047316Y2719546D01*
X3046231Y2720380D01*
X3045146Y2720588D01*
X3044061Y2720380D01*
X3042666Y2719546D01*
X3043131Y2724963D01*
X3047316D01*
G01X3005156Y2738921D02*
X3006241Y2737880D01*
X3007481Y2737463D01*
X3008721Y2737880D01*
X3009806Y2739129D01*
X3010581Y2741005D01*
X3010891Y2742880D01*
Y2745171D01*
X3010581Y2747046D01*
X3009806Y2748713D01*
X3008876Y2749546D01*
X3007791Y2749963D01*
X3006551Y2749546D01*
X3005621Y2748713D01*
X3005001Y2747463D01*
X3004691Y2745796D01*
X3005001Y2744338D01*
X3005776Y2742880D01*
X3006706Y2742046D01*
X3007791Y2741838D01*
X3009031Y2742254D01*
X3009961Y2743296D01*
X3010891Y2745171D01*
G01X3020191Y2737046D02*
X3019881Y2737255D01*
Y2737671D01*
X3020191Y2737880D01*
X3020501Y2737671D01*
Y2737255D01*
X3020191Y2737046D01*
G01X3029956Y2738921D02*
X3031041Y2737880D01*
X3032281Y2737463D01*
X3033521Y2737880D01*
X3034606Y2739129D01*
X3035381Y2741005D01*
X3035691Y2742880D01*
Y2745171D01*
X3035381Y2747046D01*
X3034606Y2748713D01*
X3033676Y2749546D01*
X3032591Y2749963D01*
X3031351Y2749546D01*
X3030421Y2748713D01*
X3029801Y2747463D01*
X3029491Y2745796D01*
X3029801Y2744338D01*
X3030576Y2742880D01*
X3031506Y2742046D01*
X3032591Y2741838D01*
X3033831Y2742254D01*
X3034761Y2743296D01*
X3035691Y2745171D01*
G01X3041581Y2739338D02*
X3042511Y2738296D01*
X3043596Y2737671D01*
X3044991Y2737463D01*
X3046386Y2737880D01*
X3047471Y2738713D01*
X3048246Y2740171D01*
X3048401Y2741838D01*
X3048091Y2743505D01*
X3047316Y2744546D01*
X3046231Y2745380D01*
X3045146Y2745588D01*
X3044061Y2745380D01*
X3042666Y2744546D01*
X3043131Y2749963D01*
X3047316D01*
G01X3005156Y2763921D02*
X3006241Y2762880D01*
X3007481Y2762463D01*
X3008721Y2762880D01*
X3009806Y2764129D01*
X3010581Y2766005D01*
X3010891Y2767880D01*
Y2770171D01*
X3010581Y2772046D01*
X3009806Y2773713D01*
X3008876Y2774546D01*
X3007791Y2774963D01*
X3006551Y2774546D01*
X3005621Y2773713D01*
X3005001Y2772463D01*
X3004691Y2770796D01*
X3005001Y2769338D01*
X3005776Y2767880D01*
X3006706Y2767046D01*
X3007791Y2766838D01*
X3009031Y2767254D01*
X3009961Y2768296D01*
X3010891Y2770171D01*
G01X3020191Y2762046D02*
X3019881Y2762255D01*
Y2762671D01*
X3020191Y2762880D01*
X3020501Y2762671D01*
Y2762255D01*
X3020191Y2762046D01*
G01X3029956Y2763921D02*
X3031041Y2762880D01*
X3032281Y2762463D01*
X3033521Y2762880D01*
X3034606Y2764129D01*
X3035381Y2766005D01*
X3035691Y2767880D01*
Y2770171D01*
X3035381Y2772046D01*
X3034606Y2773713D01*
X3033676Y2774546D01*
X3032591Y2774963D01*
X3031351Y2774546D01*
X3030421Y2773713D01*
X3029801Y2772463D01*
X3029491Y2770796D01*
X3029801Y2769338D01*
X3030576Y2767880D01*
X3031506Y2767046D01*
X3032591Y2766838D01*
X3033831Y2767254D01*
X3034761Y2768296D01*
X3035691Y2770171D01*
G01X3041581Y2764338D02*
X3042511Y2763296D01*
X3043596Y2762671D01*
X3044991Y2762463D01*
X3046386Y2762880D01*
X3047471Y2763713D01*
X3048246Y2765171D01*
X3048401Y2766838D01*
X3048091Y2768505D01*
X3047316Y2769546D01*
X3046231Y2770380D01*
X3045146Y2770588D01*
X3044061Y2770380D01*
X3042666Y2769546D01*
X3043131Y2774963D01*
X3047316D01*
G01X3018770Y1969691D02*
X3019700Y1968649D01*
X3020785Y1968024D01*
X3022180Y1967816D01*
X3023575Y1968233D01*
X3024660Y1969066D01*
X3025435Y1970524D01*
X3025590Y1972191D01*
X3025280Y1973858D01*
X3024505Y1974899D01*
X3023420Y1975733D01*
X3022335Y1975941D01*
X3021250Y1975733D01*
X3019855Y1974899D01*
X3020320Y1980316D01*
X3024505D01*
G01X3031170Y1969691D02*
X3032100Y1968649D01*
X3033185Y1968024D01*
X3034580Y1967816D01*
X3035975Y1968233D01*
X3037060Y1969066D01*
X3037835Y1970524D01*
X3037990Y1972191D01*
X3037680Y1973858D01*
X3036905Y1974899D01*
X3035820Y1975733D01*
X3034735Y1975941D01*
X3033650Y1975733D01*
X3032255Y1974899D01*
X3032720Y1980316D01*
X3036905D01*
G01X3046980Y1967399D02*
X3046670Y1967608D01*
Y1968024D01*
X3046980Y1968233D01*
X3047290Y1968024D01*
Y1967608D01*
X3046980Y1967399D01*
G01X3059380Y1980316D02*
X3058140Y1979899D01*
X3057210Y1978858D01*
X3056590Y1977608D01*
X3056125Y1975941D01*
X3055970Y1974066D01*
X3056125Y1972191D01*
X3056590Y1970524D01*
X3057210Y1969274D01*
X3058140Y1968233D01*
X3059380Y1967816D01*
X3060620Y1968233D01*
X3061550Y1969274D01*
X3062170Y1970524D01*
X3062635Y1972191D01*
X3062790Y1974066D01*
X3062635Y1975941D01*
X3062170Y1977608D01*
X3061550Y1978858D01*
X3060620Y1979899D01*
X3059380Y1980316D01*
G01X3068370Y1969691D02*
X3069300Y1968649D01*
X3070385Y1968024D01*
X3071780Y1967816D01*
X3073175Y1968233D01*
X3074260Y1969066D01*
X3075035Y1970524D01*
X3075190Y1972191D01*
X3074880Y1973858D01*
X3074105Y1974899D01*
X3073020Y1975733D01*
X3071935Y1975941D01*
X3070850Y1975733D01*
X3069455Y1974899D01*
X3069920Y1980316D01*
X3074105D01*
G01X3018770Y1994691D02*
X3019700Y1993649D01*
X3020785Y1993024D01*
X3022180Y1992816D01*
X3023575Y1993233D01*
X3024660Y1994066D01*
X3025435Y1995524D01*
X3025590Y1997191D01*
X3025280Y1998858D01*
X3024505Y1999899D01*
X3023420Y2000733D01*
X3022335Y2000941D01*
X3021250Y2000733D01*
X3019855Y1999899D01*
X3020320Y2005316D01*
X3024505D01*
G01X3031170Y1994691D02*
X3032100Y1993649D01*
X3033185Y1993024D01*
X3034580Y1992816D01*
X3035975Y1993233D01*
X3037060Y1994066D01*
X3037835Y1995524D01*
X3037990Y1997191D01*
X3037680Y1998858D01*
X3036905Y1999899D01*
X3035820Y2000733D01*
X3034735Y2000941D01*
X3033650Y2000733D01*
X3032255Y1999899D01*
X3032720Y2005316D01*
X3036905D01*
G01X3046980Y1992399D02*
X3046670Y1992608D01*
Y1993024D01*
X3046980Y1993233D01*
X3047290Y1993024D01*
Y1992608D01*
X3046980Y1992399D01*
G01X3059380Y2005316D02*
X3058140Y2004899D01*
X3057210Y2003858D01*
X3056590Y2002608D01*
X3056125Y2000941D01*
X3055970Y1999066D01*
X3056125Y1997191D01*
X3056590Y1995524D01*
X3057210Y1994274D01*
X3058140Y1993233D01*
X3059380Y1992816D01*
X3060620Y1993233D01*
X3061550Y1994274D01*
X3062170Y1995524D01*
X3062635Y1997191D01*
X3062790Y1999066D01*
X3062635Y2000941D01*
X3062170Y2002608D01*
X3061550Y2003858D01*
X3060620Y2004899D01*
X3059380Y2005316D01*
G01X3068370Y1994691D02*
X3069300Y1993649D01*
X3070385Y1993024D01*
X3071780Y1992816D01*
X3073175Y1993233D01*
X3074260Y1994066D01*
X3075035Y1995524D01*
X3075190Y1997191D01*
X3074880Y1998858D01*
X3074105Y1999899D01*
X3073020Y2000733D01*
X3071935Y2000941D01*
X3070850Y2000733D01*
X3069455Y1999899D01*
X3069920Y2005316D01*
X3074105D01*
G01X3018770Y2019691D02*
X3019700Y2018649D01*
X3020785Y2018024D01*
X3022180Y2017816D01*
X3023575Y2018233D01*
X3024660Y2019066D01*
X3025435Y2020524D01*
X3025590Y2022191D01*
X3025280Y2023858D01*
X3024505Y2024899D01*
X3023420Y2025733D01*
X3022335Y2025941D01*
X3021250Y2025733D01*
X3019855Y2024899D01*
X3020320Y2030316D01*
X3024505D01*
G01X3031170Y2019691D02*
X3032100Y2018649D01*
X3033185Y2018024D01*
X3034580Y2017816D01*
X3035975Y2018233D01*
X3037060Y2019066D01*
X3037835Y2020524D01*
X3037990Y2022191D01*
X3037680Y2023858D01*
X3036905Y2024899D01*
X3035820Y2025733D01*
X3034735Y2025941D01*
X3033650Y2025733D01*
X3032255Y2024899D01*
X3032720Y2030316D01*
X3036905D01*
G01X3046980Y2017399D02*
X3046670Y2017608D01*
Y2018024D01*
X3046980Y2018233D01*
X3047290Y2018024D01*
Y2017608D01*
X3046980Y2017399D01*
G01X3059380Y2030316D02*
X3058140Y2029899D01*
X3057210Y2028858D01*
X3056590Y2027608D01*
X3056125Y2025941D01*
X3055970Y2024066D01*
X3056125Y2022191D01*
X3056590Y2020524D01*
X3057210Y2019274D01*
X3058140Y2018233D01*
X3059380Y2017816D01*
X3060620Y2018233D01*
X3061550Y2019274D01*
X3062170Y2020524D01*
X3062635Y2022191D01*
X3062790Y2024066D01*
X3062635Y2025941D01*
X3062170Y2027608D01*
X3061550Y2028858D01*
X3060620Y2029899D01*
X3059380Y2030316D01*
G01X3068370Y2019691D02*
X3069300Y2018649D01*
X3070385Y2018024D01*
X3071780Y2017816D01*
X3073175Y2018233D01*
X3074260Y2019066D01*
X3075035Y2020524D01*
X3075190Y2022191D01*
X3074880Y2023858D01*
X3074105Y2024899D01*
X3073020Y2025733D01*
X3071935Y2025941D01*
X3070850Y2025733D01*
X3069455Y2024899D01*
X3069920Y2030316D01*
X3074105D01*
G01X3027666Y1329053D02*
Y1341553D01*
X3031696Y1331136D01*
X3035726Y1341553D01*
Y1329053D01*
G01X3040221D02*
X3044096Y1341553D01*
X3047971Y1329053D01*
G01X3046576Y1333428D02*
X3041616D01*
G01X3053241Y1329053D02*
X3059751Y1341553D01*
G01X3053241D02*
X3059751Y1329053D01*
G01X3064246Y1324886D02*
X3073546D01*
G01X3077886Y1329053D02*
Y1341553D01*
X3080986D01*
X3082226Y1340928D01*
X3083156Y1340095D01*
X3083931Y1338845D01*
X3084551Y1337386D01*
X3084706Y1335303D01*
X3084551Y1333220D01*
X3083931Y1331761D01*
X3083156Y1330511D01*
X3082226Y1329678D01*
X3080986Y1329053D01*
X3077886D01*
G01X3096796D02*
X3090596D01*
Y1341553D01*
X3096796D01*
G01X3094316Y1335511D02*
X3090596D01*
G01X3102996Y1329053D02*
Y1341553D01*
X3106716D01*
X3107956Y1340928D01*
X3108886Y1339470D01*
X3109196Y1337803D01*
X3108886Y1336136D01*
X3108111Y1334886D01*
X3106716Y1334261D01*
X3102996D01*
G01X3118496Y1341553D02*
Y1329053D01*
G01X3114931Y1341553D02*
X3122061D01*
G01X3127641Y1329053D02*
Y1341553D01*
G01X3134151D02*
Y1329053D01*
G01Y1335303D02*
X3127641D01*
G01X3027666Y1679071D02*
Y1691571D01*
X3031696Y1681154D01*
X3035726Y1691571D01*
Y1679071D01*
G01X3040221D02*
X3044096Y1691571D01*
X3047971Y1679071D01*
G01X3046576Y1683446D02*
X3041616D01*
G01X3053241Y1679071D02*
X3059751Y1691571D01*
G01X3053241D02*
X3059751Y1679071D01*
G01X3064246Y1674904D02*
X3073546D01*
G01X3077886Y1679071D02*
Y1691571D01*
X3080986D01*
X3082226Y1690946D01*
X3083156Y1690113D01*
X3083931Y1688863D01*
X3084551Y1687404D01*
X3084706Y1685321D01*
X3084551Y1683238D01*
X3083931Y1681779D01*
X3083156Y1680529D01*
X3082226Y1679696D01*
X3080986Y1679071D01*
X3077886D01*
G01X3096796D02*
X3090596D01*
Y1691571D01*
X3096796D01*
G01X3094316Y1685529D02*
X3090596D01*
G01X3102996Y1679071D02*
Y1691571D01*
X3106716D01*
X3107956Y1690946D01*
X3108886Y1689488D01*
X3109196Y1687821D01*
X3108886Y1686154D01*
X3108111Y1684904D01*
X3106716Y1684279D01*
X3102996D01*
G01X3118496Y1691571D02*
Y1679071D01*
G01X3114931Y1691571D02*
X3122061D01*
G01X3127641Y1679071D02*
Y1691571D01*
G01X3134151D02*
Y1679071D01*
G01Y1685321D02*
X3127641D01*
G01X3048668Y987938D02*
Y1000438D01*
X3052543D01*
X3053783Y999813D01*
X3054558Y998980D01*
X3054868Y997313D01*
X3054558Y995646D01*
X3053628Y994605D01*
X3052543Y993980D01*
X3048668D01*
G01X3052543D02*
X3054868Y987938D01*
G01X3064168D02*
X3062928Y988146D01*
X3061843Y988979D01*
X3060913Y990230D01*
X3060293Y991688D01*
X3059983Y993355D01*
Y995021D01*
X3060293Y996688D01*
X3060913Y998146D01*
X3061843Y999396D01*
X3062928Y1000230D01*
X3064168Y1000438D01*
X3065408Y1000230D01*
X3066493Y999396D01*
X3067423Y998146D01*
X3068043Y996688D01*
X3068353Y995021D01*
Y993355D01*
X3068043Y991688D01*
X3067423Y990230D01*
X3066493Y988979D01*
X3065408Y988146D01*
X3064168Y987938D01*
G01X3076568Y1000438D02*
Y987938D01*
G01X3073003Y1000438D02*
X3080133D01*
G01X3085093Y987938D02*
X3088968Y1000438D01*
X3092843Y987938D01*
G01X3091448Y992313D02*
X3086488D01*
G01X3101368Y1000438D02*
Y987938D01*
G01X3097803Y1000438D02*
X3104933D01*
G01X3111908D02*
X3115628D01*
G01X3113768D02*
Y987938D01*
G01X3111908D02*
X3115628D01*
G01X3126168D02*
X3124928Y988146D01*
X3123843Y988979D01*
X3122913Y990230D01*
X3122293Y991688D01*
X3121983Y993355D01*
Y995021D01*
X3122293Y996688D01*
X3122913Y998146D01*
X3123843Y999396D01*
X3124928Y1000230D01*
X3126168Y1000438D01*
X3127408Y1000230D01*
X3128493Y999396D01*
X3129423Y998146D01*
X3130043Y996688D01*
X3130353Y995021D01*
Y993355D01*
X3130043Y991688D01*
X3129423Y990230D01*
X3128493Y988979D01*
X3127408Y988146D01*
X3126168Y987938D01*
G01X3135003D02*
Y1000438D01*
X3142133Y987938D01*
Y1000438D01*
G01X3058356Y1254053D02*
Y1266553D01*
X3052621Y1257595D01*
X3060371D01*
G01X3068896Y1266553D02*
X3067656Y1266136D01*
X3066726Y1265095D01*
X3066106Y1263845D01*
X3065641Y1262178D01*
X3065486Y1260303D01*
X3065641Y1258428D01*
X3066106Y1256761D01*
X3066726Y1255511D01*
X3067656Y1254470D01*
X3068896Y1254053D01*
X3070136Y1254470D01*
X3071066Y1255511D01*
X3071686Y1256761D01*
X3072151Y1258428D01*
X3072306Y1260303D01*
X3072151Y1262178D01*
X3071686Y1263845D01*
X3071066Y1265095D01*
X3070136Y1266136D01*
X3068896Y1266553D01*
G01X3081296Y1253636D02*
X3080986Y1253845D01*
Y1254261D01*
X3081296Y1254470D01*
X3081606Y1254261D01*
Y1253845D01*
X3081296Y1253636D01*
G01X3095556Y1254053D02*
Y1266553D01*
X3089821Y1257595D01*
X3097571D01*
G01X3102686Y1255928D02*
X3103616Y1254886D01*
X3104701Y1254261D01*
X3106096Y1254053D01*
X3107491Y1254470D01*
X3108576Y1255303D01*
X3109351Y1256761D01*
X3109506Y1258428D01*
X3109196Y1260095D01*
X3108421Y1261136D01*
X3107336Y1261970D01*
X3106251Y1262178D01*
X3105166Y1261970D01*
X3103771Y1261136D01*
X3104236Y1266553D01*
X3108421D01*
G01X3058356Y1279053D02*
Y1291553D01*
X3052621Y1282595D01*
X3060371D01*
G01X3068896Y1291553D02*
X3067656Y1291136D01*
X3066726Y1290095D01*
X3066106Y1288845D01*
X3065641Y1287178D01*
X3065486Y1285303D01*
X3065641Y1283428D01*
X3066106Y1281761D01*
X3066726Y1280511D01*
X3067656Y1279470D01*
X3068896Y1279053D01*
X3070136Y1279470D01*
X3071066Y1280511D01*
X3071686Y1281761D01*
X3072151Y1283428D01*
X3072306Y1285303D01*
X3072151Y1287178D01*
X3071686Y1288845D01*
X3071066Y1290095D01*
X3070136Y1291136D01*
X3068896Y1291553D01*
G01X3081296Y1278636D02*
X3080986Y1278845D01*
Y1279261D01*
X3081296Y1279470D01*
X3081606Y1279261D01*
Y1278845D01*
X3081296Y1278636D01*
G01X3095556Y1279053D02*
Y1291553D01*
X3089821Y1282595D01*
X3097571D01*
G01X3102686Y1280928D02*
X3103616Y1279886D01*
X3104701Y1279261D01*
X3106096Y1279053D01*
X3107491Y1279470D01*
X3108576Y1280303D01*
X3109351Y1281761D01*
X3109506Y1283428D01*
X3109196Y1285095D01*
X3108421Y1286136D01*
X3107336Y1286970D01*
X3106251Y1287178D01*
X3105166Y1286970D01*
X3103771Y1286136D01*
X3104236Y1291553D01*
X3108421D01*
G01X3058356Y1304053D02*
Y1316553D01*
X3052621Y1307595D01*
X3060371D01*
G01X3068896Y1316553D02*
X3067656Y1316136D01*
X3066726Y1315095D01*
X3066106Y1313845D01*
X3065641Y1312178D01*
X3065486Y1310303D01*
X3065641Y1308428D01*
X3066106Y1306761D01*
X3066726Y1305511D01*
X3067656Y1304470D01*
X3068896Y1304053D01*
X3070136Y1304470D01*
X3071066Y1305511D01*
X3071686Y1306761D01*
X3072151Y1308428D01*
X3072306Y1310303D01*
X3072151Y1312178D01*
X3071686Y1313845D01*
X3071066Y1315095D01*
X3070136Y1316136D01*
X3068896Y1316553D01*
G01X3081296Y1303636D02*
X3080986Y1303845D01*
Y1304261D01*
X3081296Y1304470D01*
X3081606Y1304261D01*
Y1303845D01*
X3081296Y1303636D01*
G01X3095556Y1304053D02*
Y1316553D01*
X3089821Y1307595D01*
X3097571D01*
G01X3102686Y1305928D02*
X3103616Y1304886D01*
X3104701Y1304261D01*
X3106096Y1304053D01*
X3107491Y1304470D01*
X3108576Y1305303D01*
X3109351Y1306761D01*
X3109506Y1308428D01*
X3109196Y1310095D01*
X3108421Y1311136D01*
X3107336Y1311970D01*
X3106251Y1312178D01*
X3105166Y1311970D01*
X3103771Y1311136D01*
X3104236Y1316553D01*
X3108421D01*
G01X3056496Y1604071D02*
X3057581Y1604279D01*
X3058821Y1604904D01*
X3059596Y1605946D01*
X3059906Y1607404D01*
X3059596Y1608862D01*
X3058666Y1610113D01*
X3057271Y1610738D01*
X3055721D01*
X3054791Y1611154D01*
X3054016Y1612196D01*
X3053706Y1613654D01*
X3054171Y1615113D01*
X3055256Y1616154D01*
X3056496Y1616571D01*
X3057736Y1616154D01*
X3058821Y1615113D01*
X3059286Y1613654D01*
X3058976Y1612196D01*
X3058201Y1611154D01*
X3057271Y1610738D01*
X3055721D01*
X3054326Y1610113D01*
X3053396Y1608862D01*
X3053086Y1607404D01*
X3053396Y1605946D01*
X3054171Y1604904D01*
X3055411Y1604279D01*
X3056496Y1604071D01*
G01X3070756D02*
Y1616571D01*
X3065021Y1607613D01*
X3072771D01*
G01X3081296Y1603654D02*
X3080986Y1603863D01*
Y1604279D01*
X3081296Y1604488D01*
X3081606Y1604279D01*
Y1603863D01*
X3081296Y1603654D01*
G01X3093696Y1616571D02*
X3092456Y1616154D01*
X3091526Y1615113D01*
X3090906Y1613863D01*
X3090441Y1612196D01*
X3090286Y1610321D01*
X3090441Y1608446D01*
X3090906Y1606779D01*
X3091526Y1605529D01*
X3092456Y1604488D01*
X3093696Y1604071D01*
X3094936Y1604488D01*
X3095866Y1605529D01*
X3096486Y1606779D01*
X3096951Y1608446D01*
X3097106Y1610321D01*
X3096951Y1612196D01*
X3096486Y1613863D01*
X3095866Y1615113D01*
X3094936Y1616154D01*
X3093696Y1616571D01*
G01X3102686Y1605946D02*
X3103616Y1604904D01*
X3104701Y1604279D01*
X3106096Y1604071D01*
X3107491Y1604488D01*
X3108576Y1605321D01*
X3109351Y1606779D01*
X3109506Y1608446D01*
X3109196Y1610113D01*
X3108421Y1611154D01*
X3107336Y1611988D01*
X3106251Y1612196D01*
X3105166Y1611988D01*
X3103771Y1611154D01*
X3104236Y1616571D01*
X3108421D01*
G01X3056496Y1629071D02*
X3057581Y1629279D01*
X3058821Y1629904D01*
X3059596Y1630946D01*
X3059906Y1632404D01*
X3059596Y1633862D01*
X3058666Y1635113D01*
X3057271Y1635738D01*
X3055721D01*
X3054791Y1636154D01*
X3054016Y1637196D01*
X3053706Y1638654D01*
X3054171Y1640113D01*
X3055256Y1641154D01*
X3056496Y1641571D01*
X3057736Y1641154D01*
X3058821Y1640113D01*
X3059286Y1638654D01*
X3058976Y1637196D01*
X3058201Y1636154D01*
X3057271Y1635738D01*
X3055721D01*
X3054326Y1635113D01*
X3053396Y1633862D01*
X3053086Y1632404D01*
X3053396Y1630946D01*
X3054171Y1629904D01*
X3055411Y1629279D01*
X3056496Y1629071D01*
G01X3070756D02*
Y1641571D01*
X3065021Y1632613D01*
X3072771D01*
G01X3081296Y1628654D02*
X3080986Y1628863D01*
Y1629279D01*
X3081296Y1629488D01*
X3081606Y1629279D01*
Y1628863D01*
X3081296Y1628654D01*
G01X3093696Y1641571D02*
X3092456Y1641154D01*
X3091526Y1640113D01*
X3090906Y1638863D01*
X3090441Y1637196D01*
X3090286Y1635321D01*
X3090441Y1633446D01*
X3090906Y1631779D01*
X3091526Y1630529D01*
X3092456Y1629488D01*
X3093696Y1629071D01*
X3094936Y1629488D01*
X3095866Y1630529D01*
X3096486Y1631779D01*
X3096951Y1633446D01*
X3097106Y1635321D01*
X3096951Y1637196D01*
X3096486Y1638863D01*
X3095866Y1640113D01*
X3094936Y1641154D01*
X3093696Y1641571D01*
G01X3102686Y1630946D02*
X3103616Y1629904D01*
X3104701Y1629279D01*
X3106096Y1629071D01*
X3107491Y1629488D01*
X3108576Y1630321D01*
X3109351Y1631779D01*
X3109506Y1633446D01*
X3109196Y1635113D01*
X3108421Y1636154D01*
X3107336Y1636988D01*
X3106251Y1637196D01*
X3105166Y1636988D01*
X3103771Y1636154D01*
X3104236Y1641571D01*
X3108421D01*
G01X3056496Y1654071D02*
X3057581Y1654279D01*
X3058821Y1654904D01*
X3059596Y1655946D01*
X3059906Y1657404D01*
X3059596Y1658862D01*
X3058666Y1660113D01*
X3057271Y1660738D01*
X3055721D01*
X3054791Y1661154D01*
X3054016Y1662196D01*
X3053706Y1663654D01*
X3054171Y1665113D01*
X3055256Y1666154D01*
X3056496Y1666571D01*
X3057736Y1666154D01*
X3058821Y1665113D01*
X3059286Y1663654D01*
X3058976Y1662196D01*
X3058201Y1661154D01*
X3057271Y1660738D01*
X3055721D01*
X3054326Y1660113D01*
X3053396Y1658862D01*
X3053086Y1657404D01*
X3053396Y1655946D01*
X3054171Y1654904D01*
X3055411Y1654279D01*
X3056496Y1654071D01*
G01X3070756D02*
Y1666571D01*
X3065021Y1657613D01*
X3072771D01*
G01X3081296Y1653654D02*
X3080986Y1653863D01*
Y1654279D01*
X3081296Y1654488D01*
X3081606Y1654279D01*
Y1653863D01*
X3081296Y1653654D01*
G01X3093696Y1666571D02*
X3092456Y1666154D01*
X3091526Y1665113D01*
X3090906Y1663863D01*
X3090441Y1662196D01*
X3090286Y1660321D01*
X3090441Y1658446D01*
X3090906Y1656779D01*
X3091526Y1655529D01*
X3092456Y1654488D01*
X3093696Y1654071D01*
X3094936Y1654488D01*
X3095866Y1655529D01*
X3096486Y1656779D01*
X3096951Y1658446D01*
X3097106Y1660321D01*
X3096951Y1662196D01*
X3096486Y1663863D01*
X3095866Y1665113D01*
X3094936Y1666154D01*
X3093696Y1666571D01*
G01X3102686Y1655946D02*
X3103616Y1654904D01*
X3104701Y1654279D01*
X3106096Y1654071D01*
X3107491Y1654488D01*
X3108576Y1655321D01*
X3109351Y1656779D01*
X3109506Y1658446D01*
X3109196Y1660113D01*
X3108421Y1661154D01*
X3107336Y1661988D01*
X3106251Y1662196D01*
X3105166Y1661988D01*
X3103771Y1661154D01*
X3104236Y1666571D01*
X3108421D01*
G01X3070368Y-23137D02*
X3069128Y-23554D01*
X3068198Y-24595D01*
X3067578Y-25845D01*
X3067113Y-27512D01*
X3066958Y-29387D01*
X3067113Y-31262D01*
X3067578Y-32929D01*
X3068198Y-34179D01*
X3069128Y-35220D01*
X3070368Y-35637D01*
X3071608Y-35220D01*
X3072538Y-34179D01*
X3073158Y-32929D01*
X3073623Y-31262D01*
X3073778Y-29387D01*
X3073623Y-27512D01*
X3073158Y-25845D01*
X3072538Y-24595D01*
X3071608Y-23554D01*
X3070368Y-23137D01*
G01X3082768Y-36054D02*
X3082458Y-35845D01*
Y-35429D01*
X3082768Y-35220D01*
X3083078Y-35429D01*
Y-35845D01*
X3082768Y-36054D01*
G01X3095168Y-23137D02*
X3093928Y-23554D01*
X3092998Y-24595D01*
X3092378Y-25845D01*
X3091913Y-27512D01*
X3091758Y-29387D01*
X3091913Y-31262D01*
X3092378Y-32929D01*
X3092998Y-34179D01*
X3093928Y-35220D01*
X3095168Y-35637D01*
X3096408Y-35220D01*
X3097338Y-34179D01*
X3097958Y-32929D01*
X3098423Y-31262D01*
X3098578Y-29387D01*
X3098423Y-27512D01*
X3097958Y-25845D01*
X3097338Y-24595D01*
X3096408Y-23554D01*
X3095168Y-23137D01*
G01X3107568D02*
X3106328Y-23554D01*
X3105398Y-24595D01*
X3104778Y-25845D01*
X3104313Y-27512D01*
X3104158Y-29387D01*
X3104313Y-31262D01*
X3104778Y-32929D01*
X3105398Y-34179D01*
X3106328Y-35220D01*
X3107568Y-35637D01*
X3108808Y-35220D01*
X3109738Y-34179D01*
X3110358Y-32929D01*
X3110823Y-31262D01*
X3110978Y-29387D01*
X3110823Y-27512D01*
X3110358Y-25845D01*
X3109738Y-24595D01*
X3108808Y-23554D01*
X3107568Y-23137D01*
G01X3119968D02*
X3118728Y-23554D01*
X3117798Y-24595D01*
X3117178Y-25845D01*
X3116713Y-27512D01*
X3116558Y-29387D01*
X3116713Y-31262D01*
X3117178Y-32929D01*
X3117798Y-34179D01*
X3118728Y-35220D01*
X3119968Y-35637D01*
X3121208Y-35220D01*
X3122138Y-34179D01*
X3122758Y-32929D01*
X3123223Y-31262D01*
X3123378Y-29387D01*
X3123223Y-27512D01*
X3122758Y-25845D01*
X3122138Y-24595D01*
X3121208Y-23554D01*
X3119968Y-23137D01*
G01X3070368Y10013D02*
X3069128Y9596D01*
X3068198Y8555D01*
X3067578Y7305D01*
X3067113Y5638D01*
X3066958Y3763D01*
X3067113Y1888D01*
X3067578Y221D01*
X3068198Y-1029D01*
X3069128Y-2070D01*
X3070368Y-2487D01*
X3071608Y-2070D01*
X3072538Y-1029D01*
X3073158Y221D01*
X3073623Y1888D01*
X3073778Y3763D01*
X3073623Y5638D01*
X3073158Y7305D01*
X3072538Y8555D01*
X3071608Y9596D01*
X3070368Y10013D01*
G01X3082768Y-2904D02*
X3082458Y-2695D01*
Y-2279D01*
X3082768Y-2070D01*
X3083078Y-2279D01*
Y-2695D01*
X3082768Y-2904D01*
G01X3095168Y10013D02*
X3093928Y9596D01*
X3092998Y8555D01*
X3092378Y7305D01*
X3091913Y5638D01*
X3091758Y3763D01*
X3091913Y1888D01*
X3092378Y221D01*
X3092998Y-1029D01*
X3093928Y-2070D01*
X3095168Y-2487D01*
X3096408Y-2070D01*
X3097338Y-1029D01*
X3097958Y221D01*
X3098423Y1888D01*
X3098578Y3763D01*
X3098423Y5638D01*
X3097958Y7305D01*
X3097338Y8555D01*
X3096408Y9596D01*
X3095168Y10013D01*
G01X3107568D02*
X3106328Y9596D01*
X3105398Y8555D01*
X3104778Y7305D01*
X3104313Y5638D01*
X3104158Y3763D01*
X3104313Y1888D01*
X3104778Y221D01*
X3105398Y-1029D01*
X3106328Y-2070D01*
X3107568Y-2487D01*
X3108808Y-2070D01*
X3109738Y-1029D01*
X3110358Y221D01*
X3110823Y1888D01*
X3110978Y3763D01*
X3110823Y5638D01*
X3110358Y7305D01*
X3109738Y8555D01*
X3108808Y9596D01*
X3107568Y10013D01*
G01X3119968D02*
X3118728Y9596D01*
X3117798Y8555D01*
X3117178Y7305D01*
X3116713Y5638D01*
X3116558Y3763D01*
X3116713Y1888D01*
X3117178Y221D01*
X3117798Y-1029D01*
X3118728Y-2070D01*
X3119968Y-2487D01*
X3121208Y-2070D01*
X3122138Y-1029D01*
X3122758Y221D01*
X3123223Y1888D01*
X3123378Y3763D01*
X3123223Y5638D01*
X3122758Y7305D01*
X3122138Y8555D01*
X3121208Y9596D01*
X3119968Y10013D01*
G01X3061533Y32121D02*
X3062618Y31080D01*
X3063858Y30663D01*
X3065098Y31080D01*
X3066183Y32329D01*
X3066958Y34205D01*
X3067268Y36080D01*
Y38371D01*
X3066958Y40246D01*
X3066183Y41913D01*
X3065253Y42746D01*
X3064168Y43163D01*
X3062928Y42746D01*
X3061998Y41913D01*
X3061378Y40663D01*
X3061068Y38996D01*
X3061378Y37538D01*
X3062153Y36080D01*
X3063083Y35246D01*
X3064168Y35038D01*
X3065408Y35454D01*
X3066338Y36496D01*
X3067268Y38371D01*
G01X3076568Y43163D02*
X3075328Y42746D01*
X3074398Y41705D01*
X3073778Y40455D01*
X3073313Y38788D01*
X3073158Y36913D01*
X3073313Y35038D01*
X3073778Y33371D01*
X3074398Y32121D01*
X3075328Y31080D01*
X3076568Y30663D01*
X3077808Y31080D01*
X3078738Y32121D01*
X3079358Y33371D01*
X3079823Y35038D01*
X3079978Y36913D01*
X3079823Y38788D01*
X3079358Y40455D01*
X3078738Y41705D01*
X3077808Y42746D01*
X3076568Y43163D01*
G01X3088968Y30246D02*
X3088658Y30455D01*
Y30871D01*
X3088968Y31080D01*
X3089278Y30871D01*
Y30455D01*
X3088968Y30246D01*
G01X3101368Y43163D02*
X3100128Y42746D01*
X3099198Y41705D01*
X3098578Y40455D01*
X3098113Y38788D01*
X3097958Y36913D01*
X3098113Y35038D01*
X3098578Y33371D01*
X3099198Y32121D01*
X3100128Y31080D01*
X3101368Y30663D01*
X3102608Y31080D01*
X3103538Y32121D01*
X3104158Y33371D01*
X3104623Y35038D01*
X3104778Y36913D01*
X3104623Y38788D01*
X3104158Y40455D01*
X3103538Y41705D01*
X3102608Y42746D01*
X3101368Y43163D01*
G01X3113768D02*
X3112528Y42746D01*
X3111598Y41705D01*
X3110978Y40455D01*
X3110513Y38788D01*
X3110358Y36913D01*
X3110513Y35038D01*
X3110978Y33371D01*
X3111598Y32121D01*
X3112528Y31080D01*
X3113768Y30663D01*
X3115008Y31080D01*
X3115938Y32121D01*
X3116558Y33371D01*
X3117023Y35038D01*
X3117178Y36913D01*
X3117023Y38788D01*
X3116558Y40455D01*
X3115938Y41705D01*
X3115008Y42746D01*
X3113768Y43163D01*
G01X3126168D02*
X3124928Y42746D01*
X3123998Y41705D01*
X3123378Y40455D01*
X3122913Y38788D01*
X3122758Y36913D01*
X3122913Y35038D01*
X3123378Y33371D01*
X3123998Y32121D01*
X3124928Y31080D01*
X3126168Y30663D01*
X3127408Y31080D01*
X3128338Y32121D01*
X3128958Y33371D01*
X3129423Y35038D01*
X3129578Y36913D01*
X3129423Y38788D01*
X3128958Y40455D01*
X3128338Y41705D01*
X3127408Y42746D01*
X3126168Y43163D01*
G01X3061533Y65271D02*
X3062618Y64230D01*
X3063858Y63813D01*
X3065098Y64230D01*
X3066183Y65479D01*
X3066958Y67355D01*
X3067268Y69230D01*
Y71521D01*
X3066958Y73396D01*
X3066183Y75063D01*
X3065253Y75896D01*
X3064168Y76313D01*
X3062928Y75896D01*
X3061998Y75063D01*
X3061378Y73813D01*
X3061068Y72146D01*
X3061378Y70688D01*
X3062153Y69230D01*
X3063083Y68396D01*
X3064168Y68188D01*
X3065408Y68604D01*
X3066338Y69646D01*
X3067268Y71521D01*
G01X3076568Y76313D02*
X3075328Y75896D01*
X3074398Y74855D01*
X3073778Y73605D01*
X3073313Y71938D01*
X3073158Y70063D01*
X3073313Y68188D01*
X3073778Y66521D01*
X3074398Y65271D01*
X3075328Y64230D01*
X3076568Y63813D01*
X3077808Y64230D01*
X3078738Y65271D01*
X3079358Y66521D01*
X3079823Y68188D01*
X3079978Y70063D01*
X3079823Y71938D01*
X3079358Y73605D01*
X3078738Y74855D01*
X3077808Y75896D01*
X3076568Y76313D01*
G01X3088968Y63396D02*
X3088658Y63605D01*
Y64021D01*
X3088968Y64230D01*
X3089278Y64021D01*
Y63605D01*
X3088968Y63396D01*
G01X3101368Y76313D02*
X3100128Y75896D01*
X3099198Y74855D01*
X3098578Y73605D01*
X3098113Y71938D01*
X3097958Y70063D01*
X3098113Y68188D01*
X3098578Y66521D01*
X3099198Y65271D01*
X3100128Y64230D01*
X3101368Y63813D01*
X3102608Y64230D01*
X3103538Y65271D01*
X3104158Y66521D01*
X3104623Y68188D01*
X3104778Y70063D01*
X3104623Y71938D01*
X3104158Y73605D01*
X3103538Y74855D01*
X3102608Y75896D01*
X3101368Y76313D01*
G01X3113768D02*
X3112528Y75896D01*
X3111598Y74855D01*
X3110978Y73605D01*
X3110513Y71938D01*
X3110358Y70063D01*
X3110513Y68188D01*
X3110978Y66521D01*
X3111598Y65271D01*
X3112528Y64230D01*
X3113768Y63813D01*
X3115008Y64230D01*
X3115938Y65271D01*
X3116558Y66521D01*
X3117023Y68188D01*
X3117178Y70063D01*
X3117023Y71938D01*
X3116558Y73605D01*
X3115938Y74855D01*
X3115008Y75896D01*
X3113768Y76313D01*
G01X3126168D02*
X3124928Y75896D01*
X3123998Y74855D01*
X3123378Y73605D01*
X3122913Y71938D01*
X3122758Y70063D01*
X3122913Y68188D01*
X3123378Y66521D01*
X3123998Y65271D01*
X3124928Y64230D01*
X3126168Y63813D01*
X3127408Y64230D01*
X3128338Y65271D01*
X3128958Y66521D01*
X3129423Y68188D01*
X3129578Y70063D01*
X3129423Y71938D01*
X3128958Y73605D01*
X3128338Y74855D01*
X3127408Y75896D01*
X3126168Y76313D01*
G01X3093153Y101130D02*
X3097183D01*
G01X3093153Y134280D02*
X3097183D01*
G01X3093153Y167430D02*
X3097183D01*
G01X3093153Y200580D02*
X3097183D01*
G01X3093153Y233730D02*
X3097183D01*
G01X3093153Y266880D02*
X3097183D01*
G01X3093153Y300030D02*
X3097183D01*
G01X3093153Y333180D02*
X3097183D01*
G01X3093153Y366330D02*
X3097183D01*
G01X3093153Y399480D02*
X3097183D01*
G01X3093153Y432630D02*
X3097183D01*
G01X3093153Y465780D02*
X3097183D01*
G01X3093153Y498930D02*
X3097183D01*
G01X3093153Y532080D02*
X3097183D01*
G01X3093153Y565230D02*
X3097183D01*
G01X3093153Y598380D02*
X3097183D01*
G01X3093153Y631530D02*
X3097183D01*
G01X3093153Y664680D02*
X3097183D01*
G01X3093153Y697830D02*
X3097183D01*
G01X3093153Y730980D02*
X3097183D01*
G01X3093153Y764130D02*
X3097183D01*
G01X3093153Y797280D02*
X3097183D01*
G01X3093153Y830430D02*
X3097183D01*
G01X3093153Y863580D02*
X3097183D01*
G01X3093153Y896730D02*
X3097183D01*
G01X3093153Y929880D02*
X3097183D01*
G01X3093153Y963030D02*
X3097183D01*
G01X3094858Y1037938D02*
Y1050438D01*
X3097958D01*
X3099198Y1049813D01*
X3100128Y1048980D01*
X3100903Y1047730D01*
X3101523Y1046271D01*
X3101678Y1044188D01*
X3101523Y1042105D01*
X3100903Y1040646D01*
X3100128Y1039396D01*
X3099198Y1038563D01*
X3097958Y1037938D01*
X3094858D01*
G01X3107568D02*
Y1050438D01*
X3111443D01*
X3112683Y1049813D01*
X3113458Y1048980D01*
X3113768Y1047313D01*
X3113458Y1045646D01*
X3112528Y1044605D01*
X3111443Y1043980D01*
X3107568D01*
G01X3111443D02*
X3113768Y1037938D01*
G01X3121208Y1050438D02*
X3124928D01*
G01X3123068D02*
Y1037938D01*
G01X3121208D02*
X3124928D01*
G01X3132368Y1050438D02*
Y1037938D01*
X3138568D01*
G01X3144768Y1050438D02*
Y1037938D01*
X3150968D01*
G01X3176078Y1049396D02*
X3175148Y1050021D01*
X3174063Y1050438D01*
X3172823D01*
X3171428Y1049813D01*
X3170343Y1048771D01*
X3169568Y1047521D01*
X3168948Y1045438D01*
X3168793Y1043563D01*
X3169103Y1041688D01*
X3169568Y1040438D01*
X3170498Y1039188D01*
X3171583Y1038355D01*
X3172668Y1037938D01*
X3173753D01*
X3174838Y1038355D01*
X3175768Y1038979D01*
X3176543Y1039813D01*
G01X3181813Y1037938D02*
Y1050438D01*
G01X3188323D02*
Y1037938D01*
G01Y1044188D02*
X3181813D01*
G01X3193593Y1037938D02*
X3197468Y1050438D01*
X3201343Y1037938D01*
G01X3199948Y1042313D02*
X3194988D01*
G01X3206768Y1037938D02*
Y1050438D01*
X3210643D01*
X3211883Y1049813D01*
X3212658Y1048980D01*
X3212968Y1047313D01*
X3212658Y1045646D01*
X3211728Y1044605D01*
X3210643Y1043980D01*
X3206768D01*
G01X3210643D02*
X3212968Y1037938D01*
G01X3222268Y1050438D02*
Y1037938D01*
G01X3218703Y1050438D02*
X3225833D01*
G01X3234668Y1037521D02*
X3234358Y1037730D01*
Y1038146D01*
X3234668Y1038355D01*
X3234978Y1038146D01*
Y1037730D01*
X3234668Y1037521D01*
G01Y1043146D02*
X3234358Y1043355D01*
Y1043771D01*
X3234668Y1043980D01*
X3234978Y1043771D01*
Y1043355D01*
X3234668Y1043146D01*
G01X3259468Y1050438D02*
Y1037938D01*
G01X3255903Y1050438D02*
X3263033D01*
G01X3271868Y1037938D02*
X3270628Y1038146D01*
X3269543Y1038979D01*
X3268613Y1040230D01*
X3267993Y1041688D01*
X3267683Y1043355D01*
Y1045021D01*
X3267993Y1046688D01*
X3268613Y1048146D01*
X3269543Y1049396D01*
X3270628Y1050230D01*
X3271868Y1050438D01*
X3273108Y1050230D01*
X3274193Y1049396D01*
X3275123Y1048146D01*
X3275743Y1046688D01*
X3276053Y1045021D01*
Y1043355D01*
X3275743Y1041688D01*
X3275123Y1040230D01*
X3274193Y1038979D01*
X3273108Y1038146D01*
X3271868Y1037938D01*
G01X3281168D02*
Y1050438D01*
X3284888D01*
X3286128Y1049813D01*
X3287058Y1048355D01*
X3287368Y1046688D01*
X3287058Y1045021D01*
X3286283Y1043771D01*
X3284888Y1043146D01*
X3281168D01*
G01X3309068Y1050438D02*
Y1037938D01*
G01X3306898Y1046271D02*
X3311238D01*
G01X3321468Y1037938D02*
X3320538Y1038146D01*
X3319608Y1038979D01*
X3318988Y1040438D01*
X3318678Y1042105D01*
X3318988Y1043771D01*
X3319608Y1045230D01*
X3320538Y1046063D01*
X3321468Y1046271D01*
X3322398Y1046063D01*
X3323328Y1045230D01*
X3323948Y1043771D01*
X3324103Y1042105D01*
X3323948Y1040438D01*
X3323328Y1038979D01*
X3322398Y1038146D01*
X3321468Y1037938D01*
G01X3347508Y1044605D02*
X3348128Y1045230D01*
X3348593Y1046271D01*
X3348903Y1047730D01*
X3348593Y1048980D01*
X3347973Y1049813D01*
X3346888Y1050438D01*
X3342703D01*
Y1037938D01*
X3347818D01*
X3348903Y1038771D01*
X3349523Y1040021D01*
X3349833Y1041480D01*
X3349523Y1042938D01*
X3348593Y1044188D01*
X3347508Y1044605D01*
X3342703D01*
G01X3358668Y1037938D02*
X3357428Y1038146D01*
X3356343Y1038979D01*
X3355413Y1040230D01*
X3354793Y1041688D01*
X3354483Y1043355D01*
Y1045021D01*
X3354793Y1046688D01*
X3355413Y1048146D01*
X3356343Y1049396D01*
X3357428Y1050230D01*
X3358668Y1050438D01*
X3359908Y1050230D01*
X3360993Y1049396D01*
X3361923Y1048146D01*
X3362543Y1046688D01*
X3362853Y1045021D01*
Y1043355D01*
X3362543Y1041688D01*
X3361923Y1040230D01*
X3360993Y1038979D01*
X3359908Y1038146D01*
X3358668Y1037938D01*
G01X3371068Y1050438D02*
Y1037938D01*
G01X3367503Y1050438D02*
X3374633D01*
G01X3383468D02*
Y1037938D01*
G01X3379903Y1050438D02*
X3387033D01*
G01X3395868Y1037938D02*
X3394628Y1038146D01*
X3393543Y1038979D01*
X3392613Y1040230D01*
X3391993Y1041688D01*
X3391683Y1043355D01*
Y1045021D01*
X3391993Y1046688D01*
X3392613Y1048146D01*
X3393543Y1049396D01*
X3394628Y1050230D01*
X3395868Y1050438D01*
X3397108Y1050230D01*
X3398193Y1049396D01*
X3399123Y1048146D01*
X3399743Y1046688D01*
X3400053Y1045021D01*
Y1043355D01*
X3399743Y1041688D01*
X3399123Y1040230D01*
X3398193Y1038979D01*
X3397108Y1038146D01*
X3395868Y1037938D01*
G01X3404238D02*
Y1050438D01*
X3408268Y1040021D01*
X3412298Y1050438D01*
Y1037938D01*
G01X3092334Y2427151D02*
Y2439651D01*
X3096364Y2429234D01*
X3100394Y2439651D01*
Y2427151D01*
G01X3105819D02*
Y2439651D01*
X3111709D01*
G01X3109539Y2433609D02*
X3105819D01*
G01X3122094Y2433401D02*
X3125194D01*
Y2429651D01*
X3124264Y2428401D01*
X3123179Y2427568D01*
X3121629Y2427151D01*
X3120079Y2427568D01*
X3118994Y2428401D01*
X3118064Y2429651D01*
X3117444Y2431109D01*
X3117134Y2432776D01*
Y2434234D01*
X3117444Y2435484D01*
X3118064Y2436943D01*
X3118994Y2438193D01*
X3119924Y2439026D01*
X3121164Y2439651D01*
X3122249D01*
X3123489Y2439234D01*
X3124419Y2438401D01*
G01X3128914Y2422984D02*
X3138214D01*
G01X3142709Y2428817D02*
X3143949Y2427776D01*
X3145344Y2427151D01*
X3146584D01*
X3147824Y2427776D01*
X3148754Y2428817D01*
X3149219Y2430276D01*
X3148909Y2431734D01*
X3148134Y2432984D01*
X3146739Y2433818D01*
X3144879Y2434234D01*
X3143794Y2435068D01*
X3143329Y2436526D01*
X3143639Y2437984D01*
X3144414Y2439026D01*
X3145499Y2439651D01*
X3146584D01*
X3147669Y2439234D01*
X3148599Y2438193D01*
G01X3158364Y2439651D02*
Y2427151D01*
G01X3154799Y2439651D02*
X3161929D01*
G01X3167354D02*
Y2430693D01*
X3167974Y2428817D01*
X3169214Y2427568D01*
X3170764Y2427151D01*
X3172314Y2427568D01*
X3173554Y2428817D01*
X3174174Y2430693D01*
Y2439651D01*
G01X3184404Y2433818D02*
X3185024Y2434443D01*
X3185489Y2435484D01*
X3185799Y2436943D01*
X3185489Y2438193D01*
X3184869Y2439026D01*
X3183784Y2439651D01*
X3179599D01*
Y2427151D01*
X3184714D01*
X3185799Y2427984D01*
X3186419Y2429234D01*
X3186729Y2430693D01*
X3186419Y2432151D01*
X3185489Y2433401D01*
X3184404Y2433818D01*
X3179599D01*
G01X3106061Y2787463D02*
Y2799963D01*
X3110091Y2789546D01*
X3114121Y2799963D01*
Y2787463D01*
G01X3119546D02*
Y2799963D01*
X3125436D01*
G01X3123266Y2793921D02*
X3119546D01*
G01X3135821Y2793713D02*
X3138921D01*
Y2789963D01*
X3137991Y2788713D01*
X3136906Y2787880D01*
X3135356Y2787463D01*
X3133806Y2787880D01*
X3132721Y2788713D01*
X3131791Y2789963D01*
X3131171Y2791421D01*
X3130861Y2793088D01*
Y2794546D01*
X3131171Y2795796D01*
X3131791Y2797255D01*
X3132721Y2798505D01*
X3133651Y2799338D01*
X3134891Y2799963D01*
X3135976D01*
X3137216Y2799546D01*
X3138146Y2798713D01*
G01X3142641Y2783296D02*
X3151941D01*
G01X3156436Y2789129D02*
X3157676Y2788088D01*
X3159071Y2787463D01*
X3160311D01*
X3161551Y2788088D01*
X3162481Y2789129D01*
X3162946Y2790588D01*
X3162636Y2792046D01*
X3161861Y2793296D01*
X3160466Y2794130D01*
X3158606Y2794546D01*
X3157521Y2795380D01*
X3157056Y2796838D01*
X3157366Y2798296D01*
X3158141Y2799338D01*
X3159226Y2799963D01*
X3160311D01*
X3161396Y2799546D01*
X3162326Y2798505D01*
G01X3172091Y2799963D02*
Y2787463D01*
G01X3168526Y2799963D02*
X3175656D01*
G01X3181081D02*
Y2791005D01*
X3181701Y2789129D01*
X3182941Y2787880D01*
X3184491Y2787463D01*
X3186041Y2787880D01*
X3187281Y2789129D01*
X3187901Y2791005D01*
Y2799963D01*
G01X3198131Y2794130D02*
X3198751Y2794755D01*
X3199216Y2795796D01*
X3199526Y2797255D01*
X3199216Y2798505D01*
X3198596Y2799338D01*
X3197511Y2799963D01*
X3193326D01*
Y2787463D01*
X3198441D01*
X3199526Y2788296D01*
X3200146Y2789546D01*
X3200456Y2791005D01*
X3200146Y2792463D01*
X3199216Y2793713D01*
X3198131Y2794130D01*
X3193326D01*
G01X3125393Y1012938D02*
X3129268Y1025438D01*
X3133143Y1012938D01*
G01X3131748Y1017313D02*
X3126788D01*
G01X3138568Y1025438D02*
Y1012938D01*
X3144768D01*
G01X3150968Y1025438D02*
Y1012938D01*
X3157168D01*
G01X3175458Y1025438D02*
Y1016480D01*
X3176078Y1014604D01*
X3177318Y1013355D01*
X3178868Y1012938D01*
X3180418Y1013355D01*
X3181658Y1014604D01*
X3182278Y1016480D01*
Y1025438D01*
G01X3187703Y1012938D02*
Y1025438D01*
X3194833Y1012938D01*
Y1025438D01*
G01X3201808D02*
X3205528D01*
G01X3203668D02*
Y1012938D01*
G01X3201808D02*
X3205528D01*
G01X3216068Y1025438D02*
Y1012938D01*
G01X3212503Y1025438D02*
X3219633D01*
G01X3225213Y1014604D02*
X3226453Y1013563D01*
X3227848Y1012938D01*
X3229088D01*
X3230328Y1013563D01*
X3231258Y1014604D01*
X3231723Y1016063D01*
X3231413Y1017521D01*
X3230638Y1018771D01*
X3229243Y1019605D01*
X3227383Y1020021D01*
X3226298Y1020855D01*
X3225833Y1022313D01*
X3226143Y1023771D01*
X3226918Y1024813D01*
X3228003Y1025438D01*
X3229088D01*
X3230173Y1025021D01*
X3231103Y1023980D01*
G01X3249393Y1012938D02*
X3253268Y1025438D01*
X3257143Y1012938D01*
G01X3255748Y1017313D02*
X3250788D01*
G01X3262568Y1012938D02*
Y1025438D01*
X3266443D01*
X3267683Y1024813D01*
X3268458Y1023980D01*
X3268768Y1022313D01*
X3268458Y1020646D01*
X3267528Y1019605D01*
X3266443Y1018980D01*
X3262568D01*
G01X3266443D02*
X3268768Y1012938D01*
G01X3281168D02*
X3274968D01*
Y1025438D01*
X3281168D01*
G01X3278688Y1019396D02*
X3274968D01*
G01X3301008Y1025438D02*
X3304728D01*
G01X3302868D02*
Y1012938D01*
G01X3301008D02*
X3304728D01*
G01X3311703D02*
Y1025438D01*
X3318833Y1012938D01*
Y1025438D01*
G01X3336038Y1012938D02*
Y1025438D01*
X3340068Y1015021D01*
X3344098Y1025438D01*
Y1012938D01*
G01X3350608Y1025438D02*
X3354328D01*
G01X3352468D02*
Y1012938D01*
G01X3350608D02*
X3354328D01*
G01X3361768Y1025438D02*
Y1012938D01*
X3367968D01*
G01X3374013Y1014604D02*
X3375253Y1013563D01*
X3376648Y1012938D01*
X3377888D01*
X3379128Y1013563D01*
X3380058Y1014604D01*
X3380523Y1016063D01*
X3380213Y1017521D01*
X3379438Y1018771D01*
X3378043Y1019605D01*
X3376183Y1020021D01*
X3375098Y1020855D01*
X3374633Y1022313D01*
X3374943Y1023771D01*
X3375718Y1024813D01*
X3376803Y1025438D01*
X3377888D01*
X3378973Y1025021D01*
X3379903Y1023980D01*
G01X3126650Y2042816D02*
Y2055316D01*
X3130680Y2044899D01*
X3134710Y2055316D01*
Y2042816D01*
G01X3140135D02*
Y2055316D01*
X3146025D01*
G01X3143855Y2049274D02*
X3140135D01*
G01X3156410Y2049066D02*
X3159510D01*
Y2045316D01*
X3158580Y2044066D01*
X3157495Y2043233D01*
X3155945Y2042816D01*
X3154395Y2043233D01*
X3153310Y2044066D01*
X3152380Y2045316D01*
X3151760Y2046774D01*
X3151450Y2048441D01*
Y2049899D01*
X3151760Y2051149D01*
X3152380Y2052608D01*
X3153310Y2053858D01*
X3154240Y2054691D01*
X3155480Y2055316D01*
X3156565D01*
X3157805Y2054899D01*
X3158735Y2054066D01*
G01X3163230Y2038649D02*
X3172530D01*
G01X3177025Y2044482D02*
X3178265Y2043441D01*
X3179660Y2042816D01*
X3180900D01*
X3182140Y2043441D01*
X3183070Y2044482D01*
X3183535Y2045941D01*
X3183225Y2047399D01*
X3182450Y2048649D01*
X3181055Y2049483D01*
X3179195Y2049899D01*
X3178110Y2050733D01*
X3177645Y2052191D01*
X3177955Y2053649D01*
X3178730Y2054691D01*
X3179815Y2055316D01*
X3180900D01*
X3181985Y2054899D01*
X3182915Y2053858D01*
G01X3192680Y2055316D02*
Y2042816D01*
G01X3189115Y2055316D02*
X3196245D01*
G01X3201670D02*
Y2046358D01*
X3202290Y2044482D01*
X3203530Y2043233D01*
X3205080Y2042816D01*
X3206630Y2043233D01*
X3207870Y2044482D01*
X3208490Y2046358D01*
Y2055316D01*
G01X3218720Y2049483D02*
X3219340Y2050108D01*
X3219805Y2051149D01*
X3220115Y2052608D01*
X3219805Y2053858D01*
X3219185Y2054691D01*
X3218100Y2055316D01*
X3213915D01*
Y2042816D01*
X3219030D01*
X3220115Y2043649D01*
X3220735Y2044899D01*
X3221045Y2046358D01*
X3220735Y2047816D01*
X3219805Y2049066D01*
X3218720Y2049483D01*
X3213915D01*
G01X3137749Y2356318D02*
X3141779D01*
G01X3137749Y2381318D02*
X3141779D01*
G01X3137749Y2406318D02*
X3141779D01*
G01X3151476Y2716630D02*
X3155506D01*
G01X3151476Y2741630D02*
X3155506D01*
G01X3151476Y2766630D02*
X3155506D01*
G01X3172668Y1000438D02*
Y987938D01*
G01X3169103Y1000438D02*
X3176233D01*
G01X3185068Y987938D02*
X3183828Y988146D01*
X3182743Y988979D01*
X3181813Y990230D01*
X3181193Y991688D01*
X3180883Y993355D01*
Y995021D01*
X3181193Y996688D01*
X3181813Y998146D01*
X3182743Y999396D01*
X3183828Y1000230D01*
X3185068Y1000438D01*
X3186308Y1000230D01*
X3187393Y999396D01*
X3188323Y998146D01*
X3188943Y996688D01*
X3189253Y995021D01*
Y993355D01*
X3188943Y991688D01*
X3188323Y990230D01*
X3187393Y988979D01*
X3186308Y988146D01*
X3185068Y987938D01*
G01X3194368Y1000438D02*
Y987938D01*
X3200568D01*
G01X3212968D02*
X3206768D01*
Y1000438D01*
X3212968D01*
G01X3210488Y994396D02*
X3206768D01*
G01X3219168Y987938D02*
Y1000438D01*
X3223043D01*
X3224283Y999813D01*
X3225058Y998980D01*
X3225368Y997313D01*
X3225058Y995646D01*
X3224128Y994605D01*
X3223043Y993980D01*
X3219168D01*
G01X3223043D02*
X3225368Y987938D01*
G01X3230793D02*
X3234668Y1000438D01*
X3238543Y987938D01*
G01X3237148Y992313D02*
X3232188D01*
G01X3243503Y987938D02*
Y1000438D01*
X3250633Y987938D01*
Y1000438D01*
G01X3262878Y999396D02*
X3261948Y1000021D01*
X3260863Y1000438D01*
X3259623D01*
X3258228Y999813D01*
X3257143Y998771D01*
X3256368Y997521D01*
X3255748Y995438D01*
X3255593Y993563D01*
X3255903Y991688D01*
X3256368Y990438D01*
X3257298Y989188D01*
X3258383Y988355D01*
X3259468Y987938D01*
X3260553D01*
X3261638Y988355D01*
X3262568Y988979D01*
X3263343Y989813D01*
G01X3274968Y987938D02*
X3268768D01*
Y1000438D01*
X3274968D01*
G01X3272488Y994396D02*
X3268768D01*
G01X3279618Y983771D02*
X3288918D01*
G01X3293258Y987938D02*
Y1000438D01*
X3296358D01*
X3297598Y999813D01*
X3298528Y998980D01*
X3299303Y997730D01*
X3299923Y996271D01*
X3300078Y994188D01*
X3299923Y992105D01*
X3299303Y990646D01*
X3298528Y989396D01*
X3297598Y988563D01*
X3296358Y987938D01*
X3293258D01*
G01X3305968D02*
Y1000438D01*
X3309843D01*
X3311083Y999813D01*
X3311858Y998980D01*
X3312168Y997313D01*
X3311858Y995646D01*
X3310928Y994605D01*
X3309843Y993980D01*
X3305968D01*
G01X3309843D02*
X3312168Y987938D01*
G01X3319608Y1000438D02*
X3323328D01*
G01X3321468D02*
Y987938D01*
G01X3319608D02*
X3323328D01*
G01X3330768Y1000438D02*
Y987938D01*
X3336968D01*
G01X3343168Y1000438D02*
Y987938D01*
X3349368D01*
G01X3160966Y1329053D02*
Y1341553D01*
X3164996Y1331136D01*
X3169026Y1341553D01*
Y1329053D01*
G01X3174451D02*
Y1341553D01*
X3180341D01*
G01X3178171Y1335511D02*
X3174451D01*
G01X3190726Y1335303D02*
X3193826D01*
Y1331553D01*
X3192896Y1330303D01*
X3191811Y1329470D01*
X3190261Y1329053D01*
X3188711Y1329470D01*
X3187626Y1330303D01*
X3186696Y1331553D01*
X3186076Y1333011D01*
X3185766Y1334678D01*
Y1336136D01*
X3186076Y1337386D01*
X3186696Y1338845D01*
X3187626Y1340095D01*
X3188556Y1340928D01*
X3189796Y1341553D01*
X3190881D01*
X3192121Y1341136D01*
X3193051Y1340303D01*
G01X3197546Y1324886D02*
X3206846D01*
G01X3211341Y1330719D02*
X3212581Y1329678D01*
X3213976Y1329053D01*
X3215216D01*
X3216456Y1329678D01*
X3217386Y1330719D01*
X3217851Y1332178D01*
X3217541Y1333636D01*
X3216766Y1334886D01*
X3215371Y1335720D01*
X3213511Y1336136D01*
X3212426Y1336970D01*
X3211961Y1338428D01*
X3212271Y1339886D01*
X3213046Y1340928D01*
X3214131Y1341553D01*
X3215216D01*
X3216301Y1341136D01*
X3217231Y1340095D01*
G01X3226996Y1341553D02*
Y1329053D01*
G01X3223431Y1341553D02*
X3230561D01*
G01X3235986D02*
Y1332595D01*
X3236606Y1330719D01*
X3237846Y1329470D01*
X3239396Y1329053D01*
X3240946Y1329470D01*
X3242186Y1330719D01*
X3242806Y1332595D01*
Y1341553D01*
G01X3253036Y1335720D02*
X3253656Y1336345D01*
X3254121Y1337386D01*
X3254431Y1338845D01*
X3254121Y1340095D01*
X3253501Y1340928D01*
X3252416Y1341553D01*
X3248231D01*
Y1329053D01*
X3253346D01*
X3254431Y1329886D01*
X3255051Y1331136D01*
X3255361Y1332595D01*
X3255051Y1334053D01*
X3254121Y1335303D01*
X3253036Y1335720D01*
X3248231D01*
G01X3160966Y1679071D02*
Y1691571D01*
X3164996Y1681154D01*
X3169026Y1691571D01*
Y1679071D01*
G01X3174451D02*
Y1691571D01*
X3180341D01*
G01X3178171Y1685529D02*
X3174451D01*
G01X3190726Y1685321D02*
X3193826D01*
Y1681571D01*
X3192896Y1680321D01*
X3191811Y1679488D01*
X3190261Y1679071D01*
X3188711Y1679488D01*
X3187626Y1680321D01*
X3186696Y1681571D01*
X3186076Y1683029D01*
X3185766Y1684696D01*
Y1686154D01*
X3186076Y1687404D01*
X3186696Y1688863D01*
X3187626Y1690113D01*
X3188556Y1690946D01*
X3189796Y1691571D01*
X3190881D01*
X3192121Y1691154D01*
X3193051Y1690321D01*
G01X3197546Y1674904D02*
X3206846D01*
G01X3211341Y1680737D02*
X3212581Y1679696D01*
X3213976Y1679071D01*
X3215216D01*
X3216456Y1679696D01*
X3217386Y1680737D01*
X3217851Y1682196D01*
X3217541Y1683654D01*
X3216766Y1684904D01*
X3215371Y1685738D01*
X3213511Y1686154D01*
X3212426Y1686988D01*
X3211961Y1688446D01*
X3212271Y1689904D01*
X3213046Y1690946D01*
X3214131Y1691571D01*
X3215216D01*
X3216301Y1691154D01*
X3217231Y1690113D01*
G01X3226996Y1691571D02*
Y1679071D01*
G01X3223431Y1691571D02*
X3230561D01*
G01X3235986D02*
Y1682613D01*
X3236606Y1680737D01*
X3237846Y1679488D01*
X3239396Y1679071D01*
X3240946Y1679488D01*
X3242186Y1680737D01*
X3242806Y1682613D01*
Y1691571D01*
G01X3253036Y1685738D02*
X3253656Y1686363D01*
X3254121Y1687404D01*
X3254431Y1688863D01*
X3254121Y1690113D01*
X3253501Y1690946D01*
X3252416Y1691571D01*
X3248231D01*
Y1679071D01*
X3253346D01*
X3254431Y1679904D01*
X3255051Y1681154D01*
X3255361Y1682613D01*
X3255051Y1684071D01*
X3254121Y1685321D01*
X3253036Y1685738D01*
X3248231D01*
G01X3172065Y1971983D02*
X3176095D01*
G01X3172065Y1996983D02*
X3176095D01*
G01X3172065Y2021983D02*
X3176095D01*
G01X3195763Y1680D02*
X3199483D01*
G01X3197468Y4388D02*
Y-1029D01*
G01X3209868Y-2487D02*
Y10013D01*
X3208008Y7513D01*
G01Y-2487D02*
X3211728D01*
G01X3222268Y-2904D02*
X3221958Y-2695D01*
Y-2279D01*
X3222268Y-2070D01*
X3222578Y-2279D01*
Y-2695D01*
X3222268Y-2904D01*
G01X3232033Y-1029D02*
X3233118Y-2070D01*
X3234358Y-2487D01*
X3235598Y-2070D01*
X3236683Y-821D01*
X3237458Y1055D01*
X3237768Y2930D01*
Y5221D01*
X3237458Y7096D01*
X3236683Y8763D01*
X3235753Y9596D01*
X3234668Y10013D01*
X3233428Y9596D01*
X3232498Y8763D01*
X3231878Y7513D01*
X3231568Y5846D01*
X3231878Y4388D01*
X3232653Y2930D01*
X3233583Y2096D01*
X3234668Y1888D01*
X3235908Y2304D01*
X3236838Y3346D01*
X3237768Y5221D01*
G01X3244123Y2721D02*
X3245208Y4180D01*
X3246138Y5013D01*
X3247378Y5430D01*
X3248463Y5013D01*
X3249238Y4180D01*
X3249858Y2930D01*
X3250013Y1471D01*
X3249858Y221D01*
X3249238Y-1029D01*
X3248308Y-2070D01*
X3247223Y-2487D01*
X3245983Y-2070D01*
X3244898Y-821D01*
X3244278Y1055D01*
X3244123Y3138D01*
X3244433Y5846D01*
X3244898Y7305D01*
X3245673Y8763D01*
X3246758Y9805D01*
X3247843Y10013D01*
X3248928Y9596D01*
X3249703Y8555D01*
G01X3256678Y-2904D02*
X3262258Y10013D01*
G01X3269853Y1680D02*
X3273883D01*
G01X3284268Y-2487D02*
Y10013D01*
X3282408Y7513D01*
G01Y-2487D02*
X3286128D01*
G01X3296668Y-2904D02*
X3296358Y-2695D01*
Y-2279D01*
X3296668Y-2070D01*
X3296978Y-2279D01*
Y-2695D01*
X3296668Y-2904D01*
G01X3306433Y-1029D02*
X3307518Y-2070D01*
X3308758Y-2487D01*
X3309998Y-2070D01*
X3311083Y-821D01*
X3311858Y1055D01*
X3312168Y2930D01*
Y5221D01*
X3311858Y7096D01*
X3311083Y8763D01*
X3310153Y9596D01*
X3309068Y10013D01*
X3307828Y9596D01*
X3306898Y8763D01*
X3306278Y7513D01*
X3305968Y5846D01*
X3306278Y4388D01*
X3307053Y2930D01*
X3307983Y2096D01*
X3309068Y1888D01*
X3310308Y2304D01*
X3311238Y3346D01*
X3312168Y5221D01*
G01X3318523Y2721D02*
X3319608Y4180D01*
X3320538Y5013D01*
X3321778Y5430D01*
X3322863Y5013D01*
X3323638Y4180D01*
X3324258Y2930D01*
X3324413Y1471D01*
X3324258Y221D01*
X3323638Y-1029D01*
X3322708Y-2070D01*
X3321623Y-2487D01*
X3320383Y-2070D01*
X3319298Y-821D01*
X3318678Y1055D01*
X3318523Y3138D01*
X3318833Y5846D01*
X3319298Y7305D01*
X3320073Y8763D01*
X3321158Y9805D01*
X3322243Y10013D01*
X3323328Y9596D01*
X3324103Y8555D01*
G01X3195763Y34830D02*
X3199483D01*
G01X3197468Y37538D02*
Y32121D01*
G01X3209868Y30663D02*
Y43163D01*
X3208008Y40663D01*
G01Y30663D02*
X3211728D01*
G01X3222268Y30246D02*
X3221958Y30455D01*
Y30871D01*
X3222268Y31080D01*
X3222578Y30871D01*
Y30455D01*
X3222268Y30246D01*
G01X3232033Y32121D02*
X3233118Y31080D01*
X3234358Y30663D01*
X3235598Y31080D01*
X3236683Y32329D01*
X3237458Y34205D01*
X3237768Y36080D01*
Y38371D01*
X3237458Y40246D01*
X3236683Y41913D01*
X3235753Y42746D01*
X3234668Y43163D01*
X3233428Y42746D01*
X3232498Y41913D01*
X3231878Y40663D01*
X3231568Y38996D01*
X3231878Y37538D01*
X3232653Y36080D01*
X3233583Y35246D01*
X3234668Y35038D01*
X3235908Y35454D01*
X3236838Y36496D01*
X3237768Y38371D01*
G01X3244123Y35871D02*
X3245208Y37330D01*
X3246138Y38163D01*
X3247378Y38580D01*
X3248463Y38163D01*
X3249238Y37330D01*
X3249858Y36080D01*
X3250013Y34621D01*
X3249858Y33371D01*
X3249238Y32121D01*
X3248308Y31080D01*
X3247223Y30663D01*
X3245983Y31080D01*
X3244898Y32329D01*
X3244278Y34205D01*
X3244123Y36288D01*
X3244433Y38996D01*
X3244898Y40455D01*
X3245673Y41913D01*
X3246758Y42955D01*
X3247843Y43163D01*
X3248928Y42746D01*
X3249703Y41705D01*
G01X3256678Y30246D02*
X3262258Y43163D01*
G01X3269853Y34830D02*
X3273883D01*
G01X3284268Y30663D02*
Y43163D01*
X3282408Y40663D01*
G01Y30663D02*
X3286128D01*
G01X3296668Y30246D02*
X3296358Y30455D01*
Y30871D01*
X3296668Y31080D01*
X3296978Y30871D01*
Y30455D01*
X3296668Y30246D01*
G01X3306433Y32121D02*
X3307518Y31080D01*
X3308758Y30663D01*
X3309998Y31080D01*
X3311083Y32329D01*
X3311858Y34205D01*
X3312168Y36080D01*
Y38371D01*
X3311858Y40246D01*
X3311083Y41913D01*
X3310153Y42746D01*
X3309068Y43163D01*
X3307828Y42746D01*
X3306898Y41913D01*
X3306278Y40663D01*
X3305968Y38996D01*
X3306278Y37538D01*
X3307053Y36080D01*
X3307983Y35246D01*
X3309068Y35038D01*
X3310308Y35454D01*
X3311238Y36496D01*
X3312168Y38371D01*
G01X3318523Y35871D02*
X3319608Y37330D01*
X3320538Y38163D01*
X3321778Y38580D01*
X3322863Y38163D01*
X3323638Y37330D01*
X3324258Y36080D01*
X3324413Y34621D01*
X3324258Y33371D01*
X3323638Y32121D01*
X3322708Y31080D01*
X3321623Y30663D01*
X3320383Y31080D01*
X3319298Y32329D01*
X3318678Y34205D01*
X3318523Y36288D01*
X3318833Y38996D01*
X3319298Y40455D01*
X3320073Y41913D01*
X3321158Y42955D01*
X3322243Y43163D01*
X3323328Y42746D01*
X3324103Y41705D01*
G01X3195763Y67980D02*
X3199483D01*
G01X3197468Y70688D02*
Y65271D01*
G01X3209868Y63813D02*
Y76313D01*
X3208008Y73813D01*
G01Y63813D02*
X3211728D01*
G01X3222268Y63396D02*
X3221958Y63605D01*
Y64021D01*
X3222268Y64230D01*
X3222578Y64021D01*
Y63605D01*
X3222268Y63396D01*
G01X3232033Y65271D02*
X3233118Y64230D01*
X3234358Y63813D01*
X3235598Y64230D01*
X3236683Y65479D01*
X3237458Y67355D01*
X3237768Y69230D01*
Y71521D01*
X3237458Y73396D01*
X3236683Y75063D01*
X3235753Y75896D01*
X3234668Y76313D01*
X3233428Y75896D01*
X3232498Y75063D01*
X3231878Y73813D01*
X3231568Y72146D01*
X3231878Y70688D01*
X3232653Y69230D01*
X3233583Y68396D01*
X3234668Y68188D01*
X3235908Y68604D01*
X3236838Y69646D01*
X3237768Y71521D01*
G01X3244123Y69021D02*
X3245208Y70480D01*
X3246138Y71313D01*
X3247378Y71730D01*
X3248463Y71313D01*
X3249238Y70480D01*
X3249858Y69230D01*
X3250013Y67771D01*
X3249858Y66521D01*
X3249238Y65271D01*
X3248308Y64230D01*
X3247223Y63813D01*
X3245983Y64230D01*
X3244898Y65479D01*
X3244278Y67355D01*
X3244123Y69438D01*
X3244433Y72146D01*
X3244898Y73605D01*
X3245673Y75063D01*
X3246758Y76105D01*
X3247843Y76313D01*
X3248928Y75896D01*
X3249703Y74855D01*
G01X3256678Y63396D02*
X3262258Y76313D01*
G01X3269853Y67980D02*
X3273883D01*
G01X3284268Y63813D02*
Y76313D01*
X3282408Y73813D01*
G01Y63813D02*
X3286128D01*
G01X3296668Y63396D02*
X3296358Y63605D01*
Y64021D01*
X3296668Y64230D01*
X3296978Y64021D01*
Y63605D01*
X3296668Y63396D01*
G01X3306433Y65271D02*
X3307518Y64230D01*
X3308758Y63813D01*
X3309998Y64230D01*
X3311083Y65479D01*
X3311858Y67355D01*
X3312168Y69230D01*
Y71521D01*
X3311858Y73396D01*
X3311083Y75063D01*
X3310153Y75896D01*
X3309068Y76313D01*
X3307828Y75896D01*
X3306898Y75063D01*
X3306278Y73813D01*
X3305968Y72146D01*
X3306278Y70688D01*
X3307053Y69230D01*
X3307983Y68396D01*
X3309068Y68188D01*
X3310308Y68604D01*
X3311238Y69646D01*
X3312168Y71521D01*
G01X3318523Y69021D02*
X3319608Y70480D01*
X3320538Y71313D01*
X3321778Y71730D01*
X3322863Y71313D01*
X3323638Y70480D01*
X3324258Y69230D01*
X3324413Y67771D01*
X3324258Y66521D01*
X3323638Y65271D01*
X3322708Y64230D01*
X3321623Y63813D01*
X3320383Y64230D01*
X3319298Y65479D01*
X3318678Y67355D01*
X3318523Y69438D01*
X3318833Y72146D01*
X3319298Y73605D01*
X3320073Y75063D01*
X3321158Y76105D01*
X3322243Y76313D01*
X3323328Y75896D01*
X3324103Y74855D01*
G01X3195763Y333180D02*
X3199483D01*
G01X3197468Y335888D02*
Y330471D01*
G01X3209868Y329013D02*
Y341513D01*
X3208008Y339013D01*
G01Y329013D02*
X3211728D01*
G01X3222268Y328596D02*
X3221958Y328805D01*
Y329221D01*
X3222268Y329430D01*
X3222578Y329221D01*
Y328805D01*
X3222268Y328596D01*
G01X3232033Y330471D02*
X3233118Y329430D01*
X3234358Y329013D01*
X3235598Y329430D01*
X3236683Y330679D01*
X3237458Y332555D01*
X3237768Y334430D01*
Y336721D01*
X3237458Y338596D01*
X3236683Y340263D01*
X3235753Y341096D01*
X3234668Y341513D01*
X3233428Y341096D01*
X3232498Y340263D01*
X3231878Y339013D01*
X3231568Y337346D01*
X3231878Y335888D01*
X3232653Y334430D01*
X3233583Y333596D01*
X3234668Y333388D01*
X3235908Y333804D01*
X3236838Y334846D01*
X3237768Y336721D01*
G01X3244123Y334221D02*
X3245208Y335680D01*
X3246138Y336513D01*
X3247378Y336930D01*
X3248463Y336513D01*
X3249238Y335680D01*
X3249858Y334430D01*
X3250013Y332971D01*
X3249858Y331721D01*
X3249238Y330471D01*
X3248308Y329430D01*
X3247223Y329013D01*
X3245983Y329430D01*
X3244898Y330679D01*
X3244278Y332555D01*
X3244123Y334638D01*
X3244433Y337346D01*
X3244898Y338805D01*
X3245673Y340263D01*
X3246758Y341305D01*
X3247843Y341513D01*
X3248928Y341096D01*
X3249703Y340055D01*
G01X3256678Y328596D02*
X3262258Y341513D01*
G01X3269853Y333180D02*
X3273883D01*
G01X3284268Y329013D02*
Y341513D01*
X3282408Y339013D01*
G01Y329013D02*
X3286128D01*
G01X3296668Y328596D02*
X3296358Y328805D01*
Y329221D01*
X3296668Y329430D01*
X3296978Y329221D01*
Y328805D01*
X3296668Y328596D01*
G01X3306433Y330471D02*
X3307518Y329430D01*
X3308758Y329013D01*
X3309998Y329430D01*
X3311083Y330679D01*
X3311858Y332555D01*
X3312168Y334430D01*
Y336721D01*
X3311858Y338596D01*
X3311083Y340263D01*
X3310153Y341096D01*
X3309068Y341513D01*
X3307828Y341096D01*
X3306898Y340263D01*
X3306278Y339013D01*
X3305968Y337346D01*
X3306278Y335888D01*
X3307053Y334430D01*
X3307983Y333596D01*
X3309068Y333388D01*
X3310308Y333804D01*
X3311238Y334846D01*
X3312168Y336721D01*
G01X3318523Y334221D02*
X3319608Y335680D01*
X3320538Y336513D01*
X3321778Y336930D01*
X3322863Y336513D01*
X3323638Y335680D01*
X3324258Y334430D01*
X3324413Y332971D01*
X3324258Y331721D01*
X3323638Y330471D01*
X3322708Y329430D01*
X3321623Y329013D01*
X3320383Y329430D01*
X3319298Y330679D01*
X3318678Y332555D01*
X3318523Y334638D01*
X3318833Y337346D01*
X3319298Y338805D01*
X3320073Y340263D01*
X3321158Y341305D01*
X3322243Y341513D01*
X3323328Y341096D01*
X3324103Y340055D01*
G01X3201963Y399480D02*
X3205683D01*
G01X3203668Y402188D02*
Y396771D01*
G01X3212658Y397813D02*
X3213588Y396354D01*
X3214828Y395521D01*
X3216223Y395313D01*
X3217463Y395521D01*
X3218703Y396563D01*
X3219478Y397813D01*
X3219633Y399063D01*
X3219323Y400521D01*
X3218238Y401563D01*
X3217153Y401980D01*
X3215758D01*
G01X3217153D02*
X3218083Y402605D01*
X3218858Y403646D01*
X3219168Y404896D01*
X3218858Y406146D01*
X3218083Y407188D01*
X3216688Y407813D01*
X3215293Y407605D01*
X3213898Y406771D01*
G01X3228468Y394896D02*
X3228158Y395105D01*
Y395521D01*
X3228468Y395730D01*
X3228778Y395521D01*
Y395105D01*
X3228468Y394896D01*
G01X3240868Y395313D02*
Y407813D01*
X3239008Y405313D01*
G01Y395313D02*
X3242728D01*
G01X3255128D02*
Y407813D01*
X3249393Y398855D01*
X3257143D01*
G01X3262878Y394896D02*
X3268458Y407813D01*
G01X3276053Y399480D02*
X3280083D01*
G01X3290468Y407813D02*
X3289228Y407396D01*
X3288298Y406355D01*
X3287678Y405105D01*
X3287213Y403438D01*
X3287058Y401563D01*
X3287213Y399688D01*
X3287678Y398021D01*
X3288298Y396771D01*
X3289228Y395730D01*
X3290468Y395313D01*
X3291708Y395730D01*
X3292638Y396771D01*
X3293258Y398021D01*
X3293723Y399688D01*
X3293878Y401563D01*
X3293723Y403438D01*
X3293258Y405105D01*
X3292638Y406355D01*
X3291708Y407396D01*
X3290468Y407813D01*
G01X3302868Y394896D02*
X3302558Y395105D01*
Y395521D01*
X3302868Y395730D01*
X3303178Y395521D01*
Y395105D01*
X3302868Y394896D01*
G01X3315268Y407813D02*
X3314028Y407396D01*
X3313098Y406355D01*
X3312478Y405105D01*
X3312013Y403438D01*
X3311858Y401563D01*
X3312013Y399688D01*
X3312478Y398021D01*
X3313098Y396771D01*
X3314028Y395730D01*
X3315268Y395313D01*
X3316508Y395730D01*
X3317438Y396771D01*
X3318058Y398021D01*
X3318523Y399688D01*
X3318678Y401563D01*
X3318523Y403438D01*
X3318058Y405105D01*
X3317438Y406355D01*
X3316508Y407396D01*
X3315268Y407813D01*
G01X3195763Y764130D02*
X3199483D01*
G01X3197468Y766838D02*
Y761421D01*
G01X3209868Y759963D02*
Y772463D01*
X3208008Y769963D01*
G01Y759963D02*
X3211728D01*
G01X3222268Y759546D02*
X3221958Y759755D01*
Y760171D01*
X3222268Y760380D01*
X3222578Y760171D01*
Y759755D01*
X3222268Y759546D01*
G01X3232033Y761421D02*
X3233118Y760380D01*
X3234358Y759963D01*
X3235598Y760380D01*
X3236683Y761629D01*
X3237458Y763505D01*
X3237768Y765380D01*
Y767671D01*
X3237458Y769546D01*
X3236683Y771213D01*
X3235753Y772046D01*
X3234668Y772463D01*
X3233428Y772046D01*
X3232498Y771213D01*
X3231878Y769963D01*
X3231568Y768296D01*
X3231878Y766838D01*
X3232653Y765380D01*
X3233583Y764546D01*
X3234668Y764338D01*
X3235908Y764754D01*
X3236838Y765796D01*
X3237768Y767671D01*
G01X3244123Y765171D02*
X3245208Y766630D01*
X3246138Y767463D01*
X3247378Y767880D01*
X3248463Y767463D01*
X3249238Y766630D01*
X3249858Y765380D01*
X3250013Y763921D01*
X3249858Y762671D01*
X3249238Y761421D01*
X3248308Y760380D01*
X3247223Y759963D01*
X3245983Y760380D01*
X3244898Y761629D01*
X3244278Y763505D01*
X3244123Y765588D01*
X3244433Y768296D01*
X3244898Y769755D01*
X3245673Y771213D01*
X3246758Y772255D01*
X3247843Y772463D01*
X3248928Y772046D01*
X3249703Y771005D01*
G01X3256678Y759546D02*
X3262258Y772463D01*
G01X3269853Y764130D02*
X3273883D01*
G01X3284268Y759963D02*
Y772463D01*
X3282408Y769963D01*
G01Y759963D02*
X3286128D01*
G01X3296668Y759546D02*
X3296358Y759755D01*
Y760171D01*
X3296668Y760380D01*
X3296978Y760171D01*
Y759755D01*
X3296668Y759546D01*
G01X3306433Y761421D02*
X3307518Y760380D01*
X3308758Y759963D01*
X3309998Y760380D01*
X3311083Y761629D01*
X3311858Y763505D01*
X3312168Y765380D01*
Y767671D01*
X3311858Y769546D01*
X3311083Y771213D01*
X3310153Y772046D01*
X3309068Y772463D01*
X3307828Y772046D01*
X3306898Y771213D01*
X3306278Y769963D01*
X3305968Y768296D01*
X3306278Y766838D01*
X3307053Y765380D01*
X3307983Y764546D01*
X3309068Y764338D01*
X3310308Y764754D01*
X3311238Y765796D01*
X3312168Y767671D01*
G01X3318523Y765171D02*
X3319608Y766630D01*
X3320538Y767463D01*
X3321778Y767880D01*
X3322863Y767463D01*
X3323638Y766630D01*
X3324258Y765380D01*
X3324413Y763921D01*
X3324258Y762671D01*
X3323638Y761421D01*
X3322708Y760380D01*
X3321623Y759963D01*
X3320383Y760380D01*
X3319298Y761629D01*
X3318678Y763505D01*
X3318523Y765588D01*
X3318833Y768296D01*
X3319298Y769755D01*
X3320073Y771213D01*
X3321158Y772255D01*
X3322243Y772463D01*
X3323328Y772046D01*
X3324103Y771005D01*
G01X3195763Y797280D02*
X3199483D01*
G01X3197468Y799988D02*
Y794571D01*
G01X3209868Y793113D02*
Y805613D01*
X3208008Y803113D01*
G01Y793113D02*
X3211728D01*
G01X3222268Y792696D02*
X3221958Y792905D01*
Y793321D01*
X3222268Y793530D01*
X3222578Y793321D01*
Y792905D01*
X3222268Y792696D01*
G01X3232033Y794571D02*
X3233118Y793530D01*
X3234358Y793113D01*
X3235598Y793530D01*
X3236683Y794779D01*
X3237458Y796655D01*
X3237768Y798530D01*
Y800821D01*
X3237458Y802696D01*
X3236683Y804363D01*
X3235753Y805196D01*
X3234668Y805613D01*
X3233428Y805196D01*
X3232498Y804363D01*
X3231878Y803113D01*
X3231568Y801446D01*
X3231878Y799988D01*
X3232653Y798530D01*
X3233583Y797696D01*
X3234668Y797488D01*
X3235908Y797904D01*
X3236838Y798946D01*
X3237768Y800821D01*
G01X3244123Y798321D02*
X3245208Y799780D01*
X3246138Y800613D01*
X3247378Y801030D01*
X3248463Y800613D01*
X3249238Y799780D01*
X3249858Y798530D01*
X3250013Y797071D01*
X3249858Y795821D01*
X3249238Y794571D01*
X3248308Y793530D01*
X3247223Y793113D01*
X3245983Y793530D01*
X3244898Y794779D01*
X3244278Y796655D01*
X3244123Y798738D01*
X3244433Y801446D01*
X3244898Y802905D01*
X3245673Y804363D01*
X3246758Y805405D01*
X3247843Y805613D01*
X3248928Y805196D01*
X3249703Y804155D01*
G01X3256678Y792696D02*
X3262258Y805613D01*
G01X3269853Y797280D02*
X3273883D01*
G01X3284268Y793113D02*
Y805613D01*
X3282408Y803113D01*
G01Y793113D02*
X3286128D01*
G01X3296668Y792696D02*
X3296358Y792905D01*
Y793321D01*
X3296668Y793530D01*
X3296978Y793321D01*
Y792905D01*
X3296668Y792696D01*
G01X3306433Y794571D02*
X3307518Y793530D01*
X3308758Y793113D01*
X3309998Y793530D01*
X3311083Y794779D01*
X3311858Y796655D01*
X3312168Y798530D01*
Y800821D01*
X3311858Y802696D01*
X3311083Y804363D01*
X3310153Y805196D01*
X3309068Y805613D01*
X3307828Y805196D01*
X3306898Y804363D01*
X3306278Y803113D01*
X3305968Y801446D01*
X3306278Y799988D01*
X3307053Y798530D01*
X3307983Y797696D01*
X3309068Y797488D01*
X3310308Y797904D01*
X3311238Y798946D01*
X3312168Y800821D01*
G01X3318523Y798321D02*
X3319608Y799780D01*
X3320538Y800613D01*
X3321778Y801030D01*
X3322863Y800613D01*
X3323638Y799780D01*
X3324258Y798530D01*
X3324413Y797071D01*
X3324258Y795821D01*
X3323638Y794571D01*
X3322708Y793530D01*
X3321623Y793113D01*
X3320383Y793530D01*
X3319298Y794779D01*
X3318678Y796655D01*
X3318523Y798738D01*
X3318833Y801446D01*
X3319298Y802905D01*
X3320073Y804363D01*
X3321158Y805405D01*
X3322243Y805613D01*
X3323328Y805196D01*
X3324103Y804155D01*
G01X3201963Y830430D02*
X3205683D01*
G01X3203668Y833138D02*
Y827721D01*
G01X3216068Y838763D02*
X3214828Y838346D01*
X3213898Y837305D01*
X3213278Y836055D01*
X3212813Y834388D01*
X3212658Y832513D01*
X3212813Y830638D01*
X3213278Y828971D01*
X3213898Y827721D01*
X3214828Y826680D01*
X3216068Y826263D01*
X3217308Y826680D01*
X3218238Y827721D01*
X3218858Y828971D01*
X3219323Y830638D01*
X3219478Y832513D01*
X3219323Y834388D01*
X3218858Y836055D01*
X3218238Y837305D01*
X3217308Y838346D01*
X3216068Y838763D01*
G01X3228468Y825846D02*
X3228158Y826055D01*
Y826471D01*
X3228468Y826680D01*
X3228778Y826471D01*
Y826055D01*
X3228468Y825846D01*
G01X3240868Y838763D02*
X3239628Y838346D01*
X3238698Y837305D01*
X3238078Y836055D01*
X3237613Y834388D01*
X3237458Y832513D01*
X3237613Y830638D01*
X3238078Y828971D01*
X3238698Y827721D01*
X3239628Y826680D01*
X3240868Y826263D01*
X3242108Y826680D01*
X3243038Y827721D01*
X3243658Y828971D01*
X3244123Y830638D01*
X3244278Y832513D01*
X3244123Y834388D01*
X3243658Y836055D01*
X3243038Y837305D01*
X3242108Y838346D01*
X3240868Y838763D01*
G01X3250478Y825846D02*
X3256058Y838763D01*
G01X3263653Y830430D02*
X3267683D01*
G01X3278068Y826263D02*
Y838763D01*
X3276208Y836263D01*
G01Y826263D02*
X3279928D01*
G01X3290468Y838763D02*
X3289228Y838346D01*
X3288298Y837305D01*
X3287678Y836055D01*
X3287213Y834388D01*
X3287058Y832513D01*
X3287213Y830638D01*
X3287678Y828971D01*
X3288298Y827721D01*
X3289228Y826680D01*
X3290468Y826263D01*
X3291708Y826680D01*
X3292638Y827721D01*
X3293258Y828971D01*
X3293723Y830638D01*
X3293878Y832513D01*
X3293723Y834388D01*
X3293258Y836055D01*
X3292638Y837305D01*
X3291708Y838346D01*
X3290468Y838763D01*
G01X3302868Y825846D02*
X3302558Y826055D01*
Y826471D01*
X3302868Y826680D01*
X3303178Y826471D01*
Y826055D01*
X3302868Y825846D01*
G01X3315268Y838763D02*
X3314028Y838346D01*
X3313098Y837305D01*
X3312478Y836055D01*
X3312013Y834388D01*
X3311858Y832513D01*
X3312013Y830638D01*
X3312478Y828971D01*
X3313098Y827721D01*
X3314028Y826680D01*
X3315268Y826263D01*
X3316508Y826680D01*
X3317438Y827721D01*
X3318058Y828971D01*
X3318523Y830638D01*
X3318678Y832513D01*
X3318523Y834388D01*
X3318058Y836055D01*
X3317438Y837305D01*
X3316508Y838346D01*
X3315268Y838763D01*
G01X3201963Y863580D02*
X3205683D01*
G01X3203668Y866288D02*
Y860871D01*
G01X3216068Y871913D02*
X3214828Y871496D01*
X3213898Y870455D01*
X3213278Y869205D01*
X3212813Y867538D01*
X3212658Y865663D01*
X3212813Y863788D01*
X3213278Y862121D01*
X3213898Y860871D01*
X3214828Y859830D01*
X3216068Y859413D01*
X3217308Y859830D01*
X3218238Y860871D01*
X3218858Y862121D01*
X3219323Y863788D01*
X3219478Y865663D01*
X3219323Y867538D01*
X3218858Y869205D01*
X3218238Y870455D01*
X3217308Y871496D01*
X3216068Y871913D01*
G01X3228468Y858996D02*
X3228158Y859205D01*
Y859621D01*
X3228468Y859830D01*
X3228778Y859621D01*
Y859205D01*
X3228468Y858996D01*
G01X3240868Y871913D02*
X3239628Y871496D01*
X3238698Y870455D01*
X3238078Y869205D01*
X3237613Y867538D01*
X3237458Y865663D01*
X3237613Y863788D01*
X3238078Y862121D01*
X3238698Y860871D01*
X3239628Y859830D01*
X3240868Y859413D01*
X3242108Y859830D01*
X3243038Y860871D01*
X3243658Y862121D01*
X3244123Y863788D01*
X3244278Y865663D01*
X3244123Y867538D01*
X3243658Y869205D01*
X3243038Y870455D01*
X3242108Y871496D01*
X3240868Y871913D01*
G01X3250478Y858996D02*
X3256058Y871913D01*
G01X3263653Y863580D02*
X3267683D01*
G01X3278068Y859413D02*
Y871913D01*
X3276208Y869413D01*
G01Y859413D02*
X3279928D01*
G01X3290468Y871913D02*
X3289228Y871496D01*
X3288298Y870455D01*
X3287678Y869205D01*
X3287213Y867538D01*
X3287058Y865663D01*
X3287213Y863788D01*
X3287678Y862121D01*
X3288298Y860871D01*
X3289228Y859830D01*
X3290468Y859413D01*
X3291708Y859830D01*
X3292638Y860871D01*
X3293258Y862121D01*
X3293723Y863788D01*
X3293878Y865663D01*
X3293723Y867538D01*
X3293258Y869205D01*
X3292638Y870455D01*
X3291708Y871496D01*
X3290468Y871913D01*
G01X3302868Y858996D02*
X3302558Y859205D01*
Y859621D01*
X3302868Y859830D01*
X3303178Y859621D01*
Y859205D01*
X3302868Y858996D01*
G01X3315268Y871913D02*
X3314028Y871496D01*
X3313098Y870455D01*
X3312478Y869205D01*
X3312013Y867538D01*
X3311858Y865663D01*
X3312013Y863788D01*
X3312478Y862121D01*
X3313098Y860871D01*
X3314028Y859830D01*
X3315268Y859413D01*
X3316508Y859830D01*
X3317438Y860871D01*
X3318058Y862121D01*
X3318523Y863788D01*
X3318678Y865663D01*
X3318523Y867538D01*
X3318058Y869205D01*
X3317438Y870455D01*
X3316508Y871496D01*
X3315268Y871913D01*
G01X3208163Y-31470D02*
X3211883D01*
G01X3209868Y-28762D02*
Y-34179D01*
G01X3219323Y-25220D02*
X3220253Y-23971D01*
X3221338Y-23345D01*
X3222578Y-23137D01*
X3224128Y-23554D01*
X3225213Y-24595D01*
X3225523Y-25845D01*
X3225368Y-27096D01*
X3224748Y-28137D01*
X3221648Y-30220D01*
X3220253Y-31679D01*
X3219323Y-33762D01*
X3219013Y-35637D01*
X3225523D01*
G01X3234668Y-36054D02*
X3234358Y-35845D01*
Y-35429D01*
X3234668Y-35220D01*
X3234978Y-35429D01*
Y-35845D01*
X3234668Y-36054D01*
G01X3247068Y-23137D02*
X3245828Y-23554D01*
X3244898Y-24595D01*
X3244278Y-25845D01*
X3243813Y-27512D01*
X3243658Y-29387D01*
X3243813Y-31262D01*
X3244278Y-32929D01*
X3244898Y-34179D01*
X3245828Y-35220D01*
X3247068Y-35637D01*
X3248308Y-35220D01*
X3249238Y-34179D01*
X3249858Y-32929D01*
X3250323Y-31262D01*
X3250478Y-29387D01*
X3250323Y-27512D01*
X3249858Y-25845D01*
X3249238Y-24595D01*
X3248308Y-23554D01*
X3247068Y-23137D01*
G01X3256678Y-36054D02*
X3262258Y-23137D01*
G01X3269853Y-31470D02*
X3273883D01*
G01X3281323Y-25220D02*
X3282253Y-23971D01*
X3283338Y-23345D01*
X3284578Y-23137D01*
X3286128Y-23554D01*
X3287213Y-24595D01*
X3287523Y-25845D01*
X3287368Y-27096D01*
X3286748Y-28137D01*
X3283648Y-30220D01*
X3282253Y-31679D01*
X3281323Y-33762D01*
X3281013Y-35637D01*
X3287523D01*
G01X3296668Y-36054D02*
X3296358Y-35845D01*
Y-35429D01*
X3296668Y-35220D01*
X3296978Y-35429D01*
Y-35845D01*
X3296668Y-36054D01*
G01X3309068Y-23137D02*
X3307828Y-23554D01*
X3306898Y-24595D01*
X3306278Y-25845D01*
X3305813Y-27512D01*
X3305658Y-29387D01*
X3305813Y-31262D01*
X3306278Y-32929D01*
X3306898Y-34179D01*
X3307828Y-35220D01*
X3309068Y-35637D01*
X3310308Y-35220D01*
X3311238Y-34179D01*
X3311858Y-32929D01*
X3312323Y-31262D01*
X3312478Y-29387D01*
X3312323Y-27512D01*
X3311858Y-25845D01*
X3311238Y-24595D01*
X3310308Y-23554D01*
X3309068Y-23137D01*
G01X3208163Y101130D02*
X3211883D01*
G01X3209868Y103838D02*
Y98421D01*
G01X3219323Y107380D02*
X3220253Y108629D01*
X3221338Y109255D01*
X3222578Y109463D01*
X3224128Y109046D01*
X3225213Y108005D01*
X3225523Y106755D01*
X3225368Y105504D01*
X3224748Y104463D01*
X3221648Y102380D01*
X3220253Y100921D01*
X3219323Y98838D01*
X3219013Y96963D01*
X3225523D01*
G01X3234668Y96546D02*
X3234358Y96755D01*
Y97171D01*
X3234668Y97380D01*
X3234978Y97171D01*
Y96755D01*
X3234668Y96546D01*
G01X3247068Y109463D02*
X3245828Y109046D01*
X3244898Y108005D01*
X3244278Y106755D01*
X3243813Y105088D01*
X3243658Y103213D01*
X3243813Y101338D01*
X3244278Y99671D01*
X3244898Y98421D01*
X3245828Y97380D01*
X3247068Y96963D01*
X3248308Y97380D01*
X3249238Y98421D01*
X3249858Y99671D01*
X3250323Y101338D01*
X3250478Y103213D01*
X3250323Y105088D01*
X3249858Y106755D01*
X3249238Y108005D01*
X3248308Y109046D01*
X3247068Y109463D01*
G01X3256678Y96546D02*
X3262258Y109463D01*
G01X3269853Y101130D02*
X3273883D01*
G01X3281323Y107380D02*
X3282253Y108629D01*
X3283338Y109255D01*
X3284578Y109463D01*
X3286128Y109046D01*
X3287213Y108005D01*
X3287523Y106755D01*
X3287368Y105504D01*
X3286748Y104463D01*
X3283648Y102380D01*
X3282253Y100921D01*
X3281323Y98838D01*
X3281013Y96963D01*
X3287523D01*
G01X3296668Y96546D02*
X3296358Y96755D01*
Y97171D01*
X3296668Y97380D01*
X3296978Y97171D01*
Y96755D01*
X3296668Y96546D01*
G01X3309068Y109463D02*
X3307828Y109046D01*
X3306898Y108005D01*
X3306278Y106755D01*
X3305813Y105088D01*
X3305658Y103213D01*
X3305813Y101338D01*
X3306278Y99671D01*
X3306898Y98421D01*
X3307828Y97380D01*
X3309068Y96963D01*
X3310308Y97380D01*
X3311238Y98421D01*
X3311858Y99671D01*
X3312323Y101338D01*
X3312478Y103213D01*
X3312323Y105088D01*
X3311858Y106755D01*
X3311238Y108005D01*
X3310308Y109046D01*
X3309068Y109463D01*
G01X3208163Y134280D02*
X3211883D01*
G01X3209868Y136988D02*
Y131571D01*
G01X3219323Y140530D02*
X3220253Y141779D01*
X3221338Y142405D01*
X3222578Y142613D01*
X3224128Y142196D01*
X3225213Y141155D01*
X3225523Y139905D01*
X3225368Y138654D01*
X3224748Y137613D01*
X3221648Y135530D01*
X3220253Y134071D01*
X3219323Y131988D01*
X3219013Y130113D01*
X3225523D01*
G01X3234668Y129696D02*
X3234358Y129905D01*
Y130321D01*
X3234668Y130530D01*
X3234978Y130321D01*
Y129905D01*
X3234668Y129696D01*
G01X3247068Y142613D02*
X3245828Y142196D01*
X3244898Y141155D01*
X3244278Y139905D01*
X3243813Y138238D01*
X3243658Y136363D01*
X3243813Y134488D01*
X3244278Y132821D01*
X3244898Y131571D01*
X3245828Y130530D01*
X3247068Y130113D01*
X3248308Y130530D01*
X3249238Y131571D01*
X3249858Y132821D01*
X3250323Y134488D01*
X3250478Y136363D01*
X3250323Y138238D01*
X3249858Y139905D01*
X3249238Y141155D01*
X3248308Y142196D01*
X3247068Y142613D01*
G01X3256678Y129696D02*
X3262258Y142613D01*
G01X3269853Y134280D02*
X3273883D01*
G01X3281323Y140530D02*
X3282253Y141779D01*
X3283338Y142405D01*
X3284578Y142613D01*
X3286128Y142196D01*
X3287213Y141155D01*
X3287523Y139905D01*
X3287368Y138654D01*
X3286748Y137613D01*
X3283648Y135530D01*
X3282253Y134071D01*
X3281323Y131988D01*
X3281013Y130113D01*
X3287523D01*
G01X3296668Y129696D02*
X3296358Y129905D01*
Y130321D01*
X3296668Y130530D01*
X3296978Y130321D01*
Y129905D01*
X3296668Y129696D01*
G01X3309068Y142613D02*
X3307828Y142196D01*
X3306898Y141155D01*
X3306278Y139905D01*
X3305813Y138238D01*
X3305658Y136363D01*
X3305813Y134488D01*
X3306278Y132821D01*
X3306898Y131571D01*
X3307828Y130530D01*
X3309068Y130113D01*
X3310308Y130530D01*
X3311238Y131571D01*
X3311858Y132821D01*
X3312323Y134488D01*
X3312478Y136363D01*
X3312323Y138238D01*
X3311858Y139905D01*
X3311238Y141155D01*
X3310308Y142196D01*
X3309068Y142613D01*
G01X3208163Y167430D02*
X3211883D01*
G01X3209868Y170138D02*
Y164721D01*
G01X3219323Y173680D02*
X3220253Y174929D01*
X3221338Y175555D01*
X3222578Y175763D01*
X3224128Y175346D01*
X3225213Y174305D01*
X3225523Y173055D01*
X3225368Y171804D01*
X3224748Y170763D01*
X3221648Y168680D01*
X3220253Y167221D01*
X3219323Y165138D01*
X3219013Y163263D01*
X3225523D01*
G01X3234668Y162846D02*
X3234358Y163055D01*
Y163471D01*
X3234668Y163680D01*
X3234978Y163471D01*
Y163055D01*
X3234668Y162846D01*
G01X3247068Y175763D02*
X3245828Y175346D01*
X3244898Y174305D01*
X3244278Y173055D01*
X3243813Y171388D01*
X3243658Y169513D01*
X3243813Y167638D01*
X3244278Y165971D01*
X3244898Y164721D01*
X3245828Y163680D01*
X3247068Y163263D01*
X3248308Y163680D01*
X3249238Y164721D01*
X3249858Y165971D01*
X3250323Y167638D01*
X3250478Y169513D01*
X3250323Y171388D01*
X3249858Y173055D01*
X3249238Y174305D01*
X3248308Y175346D01*
X3247068Y175763D01*
G01X3256678Y162846D02*
X3262258Y175763D01*
G01X3269853Y167430D02*
X3273883D01*
G01X3281323Y173680D02*
X3282253Y174929D01*
X3283338Y175555D01*
X3284578Y175763D01*
X3286128Y175346D01*
X3287213Y174305D01*
X3287523Y173055D01*
X3287368Y171804D01*
X3286748Y170763D01*
X3283648Y168680D01*
X3282253Y167221D01*
X3281323Y165138D01*
X3281013Y163263D01*
X3287523D01*
G01X3296668Y162846D02*
X3296358Y163055D01*
Y163471D01*
X3296668Y163680D01*
X3296978Y163471D01*
Y163055D01*
X3296668Y162846D01*
G01X3309068Y175763D02*
X3307828Y175346D01*
X3306898Y174305D01*
X3306278Y173055D01*
X3305813Y171388D01*
X3305658Y169513D01*
X3305813Y167638D01*
X3306278Y165971D01*
X3306898Y164721D01*
X3307828Y163680D01*
X3309068Y163263D01*
X3310308Y163680D01*
X3311238Y164721D01*
X3311858Y165971D01*
X3312323Y167638D01*
X3312478Y169513D01*
X3312323Y171388D01*
X3311858Y173055D01*
X3311238Y174305D01*
X3310308Y175346D01*
X3309068Y175763D01*
G01X3208163Y200580D02*
X3211883D01*
G01X3209868Y203288D02*
Y197871D01*
G01X3219323Y206830D02*
X3220253Y208079D01*
X3221338Y208705D01*
X3222578Y208913D01*
X3224128Y208496D01*
X3225213Y207455D01*
X3225523Y206205D01*
X3225368Y204954D01*
X3224748Y203913D01*
X3221648Y201830D01*
X3220253Y200371D01*
X3219323Y198288D01*
X3219013Y196413D01*
X3225523D01*
G01X3234668Y195996D02*
X3234358Y196205D01*
Y196621D01*
X3234668Y196830D01*
X3234978Y196621D01*
Y196205D01*
X3234668Y195996D01*
G01X3247068Y208913D02*
X3245828Y208496D01*
X3244898Y207455D01*
X3244278Y206205D01*
X3243813Y204538D01*
X3243658Y202663D01*
X3243813Y200788D01*
X3244278Y199121D01*
X3244898Y197871D01*
X3245828Y196830D01*
X3247068Y196413D01*
X3248308Y196830D01*
X3249238Y197871D01*
X3249858Y199121D01*
X3250323Y200788D01*
X3250478Y202663D01*
X3250323Y204538D01*
X3249858Y206205D01*
X3249238Y207455D01*
X3248308Y208496D01*
X3247068Y208913D01*
G01X3256678Y195996D02*
X3262258Y208913D01*
G01X3269853Y200580D02*
X3273883D01*
G01X3284268Y208913D02*
X3283028Y208496D01*
X3282098Y207455D01*
X3281478Y206205D01*
X3281013Y204538D01*
X3280858Y202663D01*
X3281013Y200788D01*
X3281478Y199121D01*
X3282098Y197871D01*
X3283028Y196830D01*
X3284268Y196413D01*
X3285508Y196830D01*
X3286438Y197871D01*
X3287058Y199121D01*
X3287523Y200788D01*
X3287678Y202663D01*
X3287523Y204538D01*
X3287058Y206205D01*
X3286438Y207455D01*
X3285508Y208496D01*
X3284268Y208913D01*
G01X3296668Y195996D02*
X3296358Y196205D01*
Y196621D01*
X3296668Y196830D01*
X3296978Y196621D01*
Y196205D01*
X3296668Y195996D01*
G01X3309068Y208913D02*
X3307828Y208496D01*
X3306898Y207455D01*
X3306278Y206205D01*
X3305813Y204538D01*
X3305658Y202663D01*
X3305813Y200788D01*
X3306278Y199121D01*
X3306898Y197871D01*
X3307828Y196830D01*
X3309068Y196413D01*
X3310308Y196830D01*
X3311238Y197871D01*
X3311858Y199121D01*
X3312323Y200788D01*
X3312478Y202663D01*
X3312323Y204538D01*
X3311858Y206205D01*
X3311238Y207455D01*
X3310308Y208496D01*
X3309068Y208913D01*
G01X3208163Y233730D02*
X3211883D01*
G01X3209868Y236438D02*
Y231021D01*
G01X3219323Y239980D02*
X3220253Y241229D01*
X3221338Y241855D01*
X3222578Y242063D01*
X3224128Y241646D01*
X3225213Y240605D01*
X3225523Y239355D01*
X3225368Y238104D01*
X3224748Y237063D01*
X3221648Y234980D01*
X3220253Y233521D01*
X3219323Y231438D01*
X3219013Y229563D01*
X3225523D01*
G01X3234668Y229146D02*
X3234358Y229355D01*
Y229771D01*
X3234668Y229980D01*
X3234978Y229771D01*
Y229355D01*
X3234668Y229146D01*
G01X3247068Y242063D02*
X3245828Y241646D01*
X3244898Y240605D01*
X3244278Y239355D01*
X3243813Y237688D01*
X3243658Y235813D01*
X3243813Y233938D01*
X3244278Y232271D01*
X3244898Y231021D01*
X3245828Y229980D01*
X3247068Y229563D01*
X3248308Y229980D01*
X3249238Y231021D01*
X3249858Y232271D01*
X3250323Y233938D01*
X3250478Y235813D01*
X3250323Y237688D01*
X3249858Y239355D01*
X3249238Y240605D01*
X3248308Y241646D01*
X3247068Y242063D01*
G01X3256678Y229146D02*
X3262258Y242063D01*
G01X3269853Y233730D02*
X3273883D01*
G01X3281323Y239980D02*
X3282253Y241229D01*
X3283338Y241855D01*
X3284578Y242063D01*
X3286128Y241646D01*
X3287213Y240605D01*
X3287523Y239355D01*
X3287368Y238104D01*
X3286748Y237063D01*
X3283648Y234980D01*
X3282253Y233521D01*
X3281323Y231438D01*
X3281013Y229563D01*
X3287523D01*
G01X3296668Y229146D02*
X3296358Y229355D01*
Y229771D01*
X3296668Y229980D01*
X3296978Y229771D01*
Y229355D01*
X3296668Y229146D01*
G01X3309068Y242063D02*
X3307828Y241646D01*
X3306898Y240605D01*
X3306278Y239355D01*
X3305813Y237688D01*
X3305658Y235813D01*
X3305813Y233938D01*
X3306278Y232271D01*
X3306898Y231021D01*
X3307828Y229980D01*
X3309068Y229563D01*
X3310308Y229980D01*
X3311238Y231021D01*
X3311858Y232271D01*
X3312323Y233938D01*
X3312478Y235813D01*
X3312323Y237688D01*
X3311858Y239355D01*
X3311238Y240605D01*
X3310308Y241646D01*
X3309068Y242063D01*
G01X3208163Y266880D02*
X3211883D01*
G01X3209868Y269588D02*
Y264171D01*
G01X3219323Y273130D02*
X3220253Y274379D01*
X3221338Y275005D01*
X3222578Y275213D01*
X3224128Y274796D01*
X3225213Y273755D01*
X3225523Y272505D01*
X3225368Y271254D01*
X3224748Y270213D01*
X3221648Y268130D01*
X3220253Y266671D01*
X3219323Y264588D01*
X3219013Y262713D01*
X3225523D01*
G01X3234668Y262296D02*
X3234358Y262505D01*
Y262921D01*
X3234668Y263130D01*
X3234978Y262921D01*
Y262505D01*
X3234668Y262296D01*
G01X3247068Y275213D02*
X3245828Y274796D01*
X3244898Y273755D01*
X3244278Y272505D01*
X3243813Y270838D01*
X3243658Y268963D01*
X3243813Y267088D01*
X3244278Y265421D01*
X3244898Y264171D01*
X3245828Y263130D01*
X3247068Y262713D01*
X3248308Y263130D01*
X3249238Y264171D01*
X3249858Y265421D01*
X3250323Y267088D01*
X3250478Y268963D01*
X3250323Y270838D01*
X3249858Y272505D01*
X3249238Y273755D01*
X3248308Y274796D01*
X3247068Y275213D01*
G01X3256678Y262296D02*
X3262258Y275213D01*
G01X3269853Y266880D02*
X3273883D01*
G01X3281323Y273130D02*
X3282253Y274379D01*
X3283338Y275005D01*
X3284578Y275213D01*
X3286128Y274796D01*
X3287213Y273755D01*
X3287523Y272505D01*
X3287368Y271254D01*
X3286748Y270213D01*
X3283648Y268130D01*
X3282253Y266671D01*
X3281323Y264588D01*
X3281013Y262713D01*
X3287523D01*
G01X3296668Y262296D02*
X3296358Y262505D01*
Y262921D01*
X3296668Y263130D01*
X3296978Y262921D01*
Y262505D01*
X3296668Y262296D01*
G01X3309068Y275213D02*
X3307828Y274796D01*
X3306898Y273755D01*
X3306278Y272505D01*
X3305813Y270838D01*
X3305658Y268963D01*
X3305813Y267088D01*
X3306278Y265421D01*
X3306898Y264171D01*
X3307828Y263130D01*
X3309068Y262713D01*
X3310308Y263130D01*
X3311238Y264171D01*
X3311858Y265421D01*
X3312323Y267088D01*
X3312478Y268963D01*
X3312323Y270838D01*
X3311858Y272505D01*
X3311238Y273755D01*
X3310308Y274796D01*
X3309068Y275213D01*
G01X3208163Y300030D02*
X3211883D01*
G01X3209868Y302738D02*
Y297321D01*
G01X3219323Y306280D02*
X3220253Y307529D01*
X3221338Y308155D01*
X3222578Y308363D01*
X3224128Y307946D01*
X3225213Y306905D01*
X3225523Y305655D01*
X3225368Y304404D01*
X3224748Y303363D01*
X3221648Y301280D01*
X3220253Y299821D01*
X3219323Y297738D01*
X3219013Y295863D01*
X3225523D01*
G01X3234668Y295446D02*
X3234358Y295655D01*
Y296071D01*
X3234668Y296280D01*
X3234978Y296071D01*
Y295655D01*
X3234668Y295446D01*
G01X3247068Y308363D02*
X3245828Y307946D01*
X3244898Y306905D01*
X3244278Y305655D01*
X3243813Y303988D01*
X3243658Y302113D01*
X3243813Y300238D01*
X3244278Y298571D01*
X3244898Y297321D01*
X3245828Y296280D01*
X3247068Y295863D01*
X3248308Y296280D01*
X3249238Y297321D01*
X3249858Y298571D01*
X3250323Y300238D01*
X3250478Y302113D01*
X3250323Y303988D01*
X3249858Y305655D01*
X3249238Y306905D01*
X3248308Y307946D01*
X3247068Y308363D01*
G01X3256678Y295446D02*
X3262258Y308363D01*
G01X3269853Y300030D02*
X3273883D01*
G01X3281323Y306280D02*
X3282253Y307529D01*
X3283338Y308155D01*
X3284578Y308363D01*
X3286128Y307946D01*
X3287213Y306905D01*
X3287523Y305655D01*
X3287368Y304404D01*
X3286748Y303363D01*
X3283648Y301280D01*
X3282253Y299821D01*
X3281323Y297738D01*
X3281013Y295863D01*
X3287523D01*
G01X3296668Y295446D02*
X3296358Y295655D01*
Y296071D01*
X3296668Y296280D01*
X3296978Y296071D01*
Y295655D01*
X3296668Y295446D01*
G01X3309068Y308363D02*
X3307828Y307946D01*
X3306898Y306905D01*
X3306278Y305655D01*
X3305813Y303988D01*
X3305658Y302113D01*
X3305813Y300238D01*
X3306278Y298571D01*
X3306898Y297321D01*
X3307828Y296280D01*
X3309068Y295863D01*
X3310308Y296280D01*
X3311238Y297321D01*
X3311858Y298571D01*
X3312323Y300238D01*
X3312478Y302113D01*
X3312323Y303988D01*
X3311858Y305655D01*
X3311238Y306905D01*
X3310308Y307946D01*
X3309068Y308363D01*
G01X3208163Y366330D02*
X3211883D01*
G01X3209868Y369038D02*
Y363621D01*
G01X3219323Y372580D02*
X3220253Y373829D01*
X3221338Y374455D01*
X3222578Y374663D01*
X3224128Y374246D01*
X3225213Y373205D01*
X3225523Y371955D01*
X3225368Y370704D01*
X3224748Y369663D01*
X3221648Y367580D01*
X3220253Y366121D01*
X3219323Y364038D01*
X3219013Y362163D01*
X3225523D01*
G01X3234668Y361746D02*
X3234358Y361955D01*
Y362371D01*
X3234668Y362580D01*
X3234978Y362371D01*
Y361955D01*
X3234668Y361746D01*
G01X3247068Y374663D02*
X3245828Y374246D01*
X3244898Y373205D01*
X3244278Y371955D01*
X3243813Y370288D01*
X3243658Y368413D01*
X3243813Y366538D01*
X3244278Y364871D01*
X3244898Y363621D01*
X3245828Y362580D01*
X3247068Y362163D01*
X3248308Y362580D01*
X3249238Y363621D01*
X3249858Y364871D01*
X3250323Y366538D01*
X3250478Y368413D01*
X3250323Y370288D01*
X3249858Y371955D01*
X3249238Y373205D01*
X3248308Y374246D01*
X3247068Y374663D01*
G01X3256678Y361746D02*
X3262258Y374663D01*
G01X3269853Y366330D02*
X3273883D01*
G01X3281323Y372580D02*
X3282253Y373829D01*
X3283338Y374455D01*
X3284578Y374663D01*
X3286128Y374246D01*
X3287213Y373205D01*
X3287523Y371955D01*
X3287368Y370704D01*
X3286748Y369663D01*
X3283648Y367580D01*
X3282253Y366121D01*
X3281323Y364038D01*
X3281013Y362163D01*
X3287523D01*
G01X3296668Y361746D02*
X3296358Y361955D01*
Y362371D01*
X3296668Y362580D01*
X3296978Y362371D01*
Y361955D01*
X3296668Y361746D01*
G01X3309068Y374663D02*
X3307828Y374246D01*
X3306898Y373205D01*
X3306278Y371955D01*
X3305813Y370288D01*
X3305658Y368413D01*
X3305813Y366538D01*
X3306278Y364871D01*
X3306898Y363621D01*
X3307828Y362580D01*
X3309068Y362163D01*
X3310308Y362580D01*
X3311238Y363621D01*
X3311858Y364871D01*
X3312323Y366538D01*
X3312478Y368413D01*
X3312323Y370288D01*
X3311858Y371955D01*
X3311238Y373205D01*
X3310308Y374246D01*
X3309068Y374663D01*
G01X3208163Y432630D02*
X3211883D01*
G01X3209868Y435338D02*
Y429921D01*
G01X3218858Y430963D02*
X3219788Y429504D01*
X3221028Y428671D01*
X3222423Y428463D01*
X3223663Y428671D01*
X3224903Y429713D01*
X3225678Y430963D01*
X3225833Y432213D01*
X3225523Y433671D01*
X3224438Y434713D01*
X3223353Y435130D01*
X3221958D01*
G01X3223353D02*
X3224283Y435755D01*
X3225058Y436796D01*
X3225368Y438046D01*
X3225058Y439296D01*
X3224283Y440338D01*
X3222888Y440963D01*
X3221493Y440755D01*
X3220098Y439921D01*
G01X3234668Y428046D02*
X3234358Y428255D01*
Y428671D01*
X3234668Y428880D01*
X3234978Y428671D01*
Y428255D01*
X3234668Y428046D01*
G01X3247068Y440963D02*
X3245828Y440546D01*
X3244898Y439505D01*
X3244278Y438255D01*
X3243813Y436588D01*
X3243658Y434713D01*
X3243813Y432838D01*
X3244278Y431171D01*
X3244898Y429921D01*
X3245828Y428880D01*
X3247068Y428463D01*
X3248308Y428880D01*
X3249238Y429921D01*
X3249858Y431171D01*
X3250323Y432838D01*
X3250478Y434713D01*
X3250323Y436588D01*
X3249858Y438255D01*
X3249238Y439505D01*
X3248308Y440546D01*
X3247068Y440963D01*
G01X3256678Y428046D02*
X3262258Y440963D01*
G01X3269853Y432630D02*
X3273883D01*
G01X3280858Y430963D02*
X3281788Y429504D01*
X3283028Y428671D01*
X3284423Y428463D01*
X3285663Y428671D01*
X3286903Y429713D01*
X3287678Y430963D01*
X3287833Y432213D01*
X3287523Y433671D01*
X3286438Y434713D01*
X3285353Y435130D01*
X3283958D01*
G01X3285353D02*
X3286283Y435755D01*
X3287058Y436796D01*
X3287368Y438046D01*
X3287058Y439296D01*
X3286283Y440338D01*
X3284888Y440963D01*
X3283493Y440755D01*
X3282098Y439921D01*
G01X3296668Y428046D02*
X3296358Y428255D01*
Y428671D01*
X3296668Y428880D01*
X3296978Y428671D01*
Y428255D01*
X3296668Y428046D01*
G01X3309068Y440963D02*
X3307828Y440546D01*
X3306898Y439505D01*
X3306278Y438255D01*
X3305813Y436588D01*
X3305658Y434713D01*
X3305813Y432838D01*
X3306278Y431171D01*
X3306898Y429921D01*
X3307828Y428880D01*
X3309068Y428463D01*
X3310308Y428880D01*
X3311238Y429921D01*
X3311858Y431171D01*
X3312323Y432838D01*
X3312478Y434713D01*
X3312323Y436588D01*
X3311858Y438255D01*
X3311238Y439505D01*
X3310308Y440546D01*
X3309068Y440963D01*
G01X3208163Y465780D02*
X3211883D01*
G01X3209868Y468488D02*
Y463071D01*
G01X3218858Y464113D02*
X3219788Y462654D01*
X3221028Y461821D01*
X3222423Y461613D01*
X3223663Y461821D01*
X3224903Y462863D01*
X3225678Y464113D01*
X3225833Y465363D01*
X3225523Y466821D01*
X3224438Y467863D01*
X3223353Y468280D01*
X3221958D01*
G01X3223353D02*
X3224283Y468905D01*
X3225058Y469946D01*
X3225368Y471196D01*
X3225058Y472446D01*
X3224283Y473488D01*
X3222888Y474113D01*
X3221493Y473905D01*
X3220098Y473071D01*
G01X3234668Y461196D02*
X3234358Y461405D01*
Y461821D01*
X3234668Y462030D01*
X3234978Y461821D01*
Y461405D01*
X3234668Y461196D01*
G01X3247068Y474113D02*
X3245828Y473696D01*
X3244898Y472655D01*
X3244278Y471405D01*
X3243813Y469738D01*
X3243658Y467863D01*
X3243813Y465988D01*
X3244278Y464321D01*
X3244898Y463071D01*
X3245828Y462030D01*
X3247068Y461613D01*
X3248308Y462030D01*
X3249238Y463071D01*
X3249858Y464321D01*
X3250323Y465988D01*
X3250478Y467863D01*
X3250323Y469738D01*
X3249858Y471405D01*
X3249238Y472655D01*
X3248308Y473696D01*
X3247068Y474113D01*
G01X3256678Y461196D02*
X3262258Y474113D01*
G01X3269853Y465780D02*
X3273883D01*
G01X3280858Y464113D02*
X3281788Y462654D01*
X3283028Y461821D01*
X3284423Y461613D01*
X3285663Y461821D01*
X3286903Y462863D01*
X3287678Y464113D01*
X3287833Y465363D01*
X3287523Y466821D01*
X3286438Y467863D01*
X3285353Y468280D01*
X3283958D01*
G01X3285353D02*
X3286283Y468905D01*
X3287058Y469946D01*
X3287368Y471196D01*
X3287058Y472446D01*
X3286283Y473488D01*
X3284888Y474113D01*
X3283493Y473905D01*
X3282098Y473071D01*
G01X3296668Y461196D02*
X3296358Y461405D01*
Y461821D01*
X3296668Y462030D01*
X3296978Y461821D01*
Y461405D01*
X3296668Y461196D01*
G01X3309068Y474113D02*
X3307828Y473696D01*
X3306898Y472655D01*
X3306278Y471405D01*
X3305813Y469738D01*
X3305658Y467863D01*
X3305813Y465988D01*
X3306278Y464321D01*
X3306898Y463071D01*
X3307828Y462030D01*
X3309068Y461613D01*
X3310308Y462030D01*
X3311238Y463071D01*
X3311858Y464321D01*
X3312323Y465988D01*
X3312478Y467863D01*
X3312323Y469738D01*
X3311858Y471405D01*
X3311238Y472655D01*
X3310308Y473696D01*
X3309068Y474113D01*
G01X3208163Y498930D02*
X3211883D01*
G01X3209868Y501638D02*
Y496221D01*
G01X3218858Y497263D02*
X3219788Y495804D01*
X3221028Y494971D01*
X3222423Y494763D01*
X3223663Y494971D01*
X3224903Y496013D01*
X3225678Y497263D01*
X3225833Y498513D01*
X3225523Y499971D01*
X3224438Y501013D01*
X3223353Y501430D01*
X3221958D01*
G01X3223353D02*
X3224283Y502055D01*
X3225058Y503096D01*
X3225368Y504346D01*
X3225058Y505596D01*
X3224283Y506638D01*
X3222888Y507263D01*
X3221493Y507055D01*
X3220098Y506221D01*
G01X3234668Y494346D02*
X3234358Y494555D01*
Y494971D01*
X3234668Y495180D01*
X3234978Y494971D01*
Y494555D01*
X3234668Y494346D01*
G01X3247068Y507263D02*
X3245828Y506846D01*
X3244898Y505805D01*
X3244278Y504555D01*
X3243813Y502888D01*
X3243658Y501013D01*
X3243813Y499138D01*
X3244278Y497471D01*
X3244898Y496221D01*
X3245828Y495180D01*
X3247068Y494763D01*
X3248308Y495180D01*
X3249238Y496221D01*
X3249858Y497471D01*
X3250323Y499138D01*
X3250478Y501013D01*
X3250323Y502888D01*
X3249858Y504555D01*
X3249238Y505805D01*
X3248308Y506846D01*
X3247068Y507263D01*
G01X3256678Y494346D02*
X3262258Y507263D01*
G01X3269853Y498930D02*
X3273883D01*
G01X3280858Y497263D02*
X3281788Y495804D01*
X3283028Y494971D01*
X3284423Y494763D01*
X3285663Y494971D01*
X3286903Y496013D01*
X3287678Y497263D01*
X3287833Y498513D01*
X3287523Y499971D01*
X3286438Y501013D01*
X3285353Y501430D01*
X3283958D01*
G01X3285353D02*
X3286283Y502055D01*
X3287058Y503096D01*
X3287368Y504346D01*
X3287058Y505596D01*
X3286283Y506638D01*
X3284888Y507263D01*
X3283493Y507055D01*
X3282098Y506221D01*
G01X3296668Y494346D02*
X3296358Y494555D01*
Y494971D01*
X3296668Y495180D01*
X3296978Y494971D01*
Y494555D01*
X3296668Y494346D01*
G01X3309068Y507263D02*
X3307828Y506846D01*
X3306898Y505805D01*
X3306278Y504555D01*
X3305813Y502888D01*
X3305658Y501013D01*
X3305813Y499138D01*
X3306278Y497471D01*
X3306898Y496221D01*
X3307828Y495180D01*
X3309068Y494763D01*
X3310308Y495180D01*
X3311238Y496221D01*
X3311858Y497471D01*
X3312323Y499138D01*
X3312478Y501013D01*
X3312323Y502888D01*
X3311858Y504555D01*
X3311238Y505805D01*
X3310308Y506846D01*
X3309068Y507263D01*
G01X3208163Y532080D02*
X3211883D01*
G01X3209868Y534788D02*
Y529371D01*
G01X3218858Y530413D02*
X3219788Y528954D01*
X3221028Y528121D01*
X3222423Y527913D01*
X3223663Y528121D01*
X3224903Y529163D01*
X3225678Y530413D01*
X3225833Y531663D01*
X3225523Y533121D01*
X3224438Y534163D01*
X3223353Y534580D01*
X3221958D01*
G01X3223353D02*
X3224283Y535205D01*
X3225058Y536246D01*
X3225368Y537496D01*
X3225058Y538746D01*
X3224283Y539788D01*
X3222888Y540413D01*
X3221493Y540205D01*
X3220098Y539371D01*
G01X3234668Y527496D02*
X3234358Y527705D01*
Y528121D01*
X3234668Y528330D01*
X3234978Y528121D01*
Y527705D01*
X3234668Y527496D01*
G01X3247068Y540413D02*
X3245828Y539996D01*
X3244898Y538955D01*
X3244278Y537705D01*
X3243813Y536038D01*
X3243658Y534163D01*
X3243813Y532288D01*
X3244278Y530621D01*
X3244898Y529371D01*
X3245828Y528330D01*
X3247068Y527913D01*
X3248308Y528330D01*
X3249238Y529371D01*
X3249858Y530621D01*
X3250323Y532288D01*
X3250478Y534163D01*
X3250323Y536038D01*
X3249858Y537705D01*
X3249238Y538955D01*
X3248308Y539996D01*
X3247068Y540413D01*
G01X3256678Y527496D02*
X3262258Y540413D01*
G01X3269853Y532080D02*
X3273883D01*
G01X3280858Y530413D02*
X3281788Y528954D01*
X3283028Y528121D01*
X3284423Y527913D01*
X3285663Y528121D01*
X3286903Y529163D01*
X3287678Y530413D01*
X3287833Y531663D01*
X3287523Y533121D01*
X3286438Y534163D01*
X3285353Y534580D01*
X3283958D01*
G01X3285353D02*
X3286283Y535205D01*
X3287058Y536246D01*
X3287368Y537496D01*
X3287058Y538746D01*
X3286283Y539788D01*
X3284888Y540413D01*
X3283493Y540205D01*
X3282098Y539371D01*
G01X3296668Y527496D02*
X3296358Y527705D01*
Y528121D01*
X3296668Y528330D01*
X3296978Y528121D01*
Y527705D01*
X3296668Y527496D01*
G01X3309068Y540413D02*
X3307828Y539996D01*
X3306898Y538955D01*
X3306278Y537705D01*
X3305813Y536038D01*
X3305658Y534163D01*
X3305813Y532288D01*
X3306278Y530621D01*
X3306898Y529371D01*
X3307828Y528330D01*
X3309068Y527913D01*
X3310308Y528330D01*
X3311238Y529371D01*
X3311858Y530621D01*
X3312323Y532288D01*
X3312478Y534163D01*
X3312323Y536038D01*
X3311858Y537705D01*
X3311238Y538955D01*
X3310308Y539996D01*
X3309068Y540413D01*
G01X3208163Y565230D02*
X3211883D01*
G01X3209868Y567938D02*
Y562521D01*
G01X3218858Y563563D02*
X3219788Y562104D01*
X3221028Y561271D01*
X3222423Y561063D01*
X3223663Y561271D01*
X3224903Y562313D01*
X3225678Y563563D01*
X3225833Y564813D01*
X3225523Y566271D01*
X3224438Y567313D01*
X3223353Y567730D01*
X3221958D01*
G01X3223353D02*
X3224283Y568355D01*
X3225058Y569396D01*
X3225368Y570646D01*
X3225058Y571896D01*
X3224283Y572938D01*
X3222888Y573563D01*
X3221493Y573355D01*
X3220098Y572521D01*
G01X3234668Y560646D02*
X3234358Y560855D01*
Y561271D01*
X3234668Y561480D01*
X3234978Y561271D01*
Y560855D01*
X3234668Y560646D01*
G01X3247068Y573563D02*
X3245828Y573146D01*
X3244898Y572105D01*
X3244278Y570855D01*
X3243813Y569188D01*
X3243658Y567313D01*
X3243813Y565438D01*
X3244278Y563771D01*
X3244898Y562521D01*
X3245828Y561480D01*
X3247068Y561063D01*
X3248308Y561480D01*
X3249238Y562521D01*
X3249858Y563771D01*
X3250323Y565438D01*
X3250478Y567313D01*
X3250323Y569188D01*
X3249858Y570855D01*
X3249238Y572105D01*
X3248308Y573146D01*
X3247068Y573563D01*
G01X3256678Y560646D02*
X3262258Y573563D01*
G01X3269853Y565230D02*
X3273883D01*
G01X3280858Y563563D02*
X3281788Y562104D01*
X3283028Y561271D01*
X3284423Y561063D01*
X3285663Y561271D01*
X3286903Y562313D01*
X3287678Y563563D01*
X3287833Y564813D01*
X3287523Y566271D01*
X3286438Y567313D01*
X3285353Y567730D01*
X3283958D01*
G01X3285353D02*
X3286283Y568355D01*
X3287058Y569396D01*
X3287368Y570646D01*
X3287058Y571896D01*
X3286283Y572938D01*
X3284888Y573563D01*
X3283493Y573355D01*
X3282098Y572521D01*
G01X3296668Y560646D02*
X3296358Y560855D01*
Y561271D01*
X3296668Y561480D01*
X3296978Y561271D01*
Y560855D01*
X3296668Y560646D01*
G01X3309068Y573563D02*
X3307828Y573146D01*
X3306898Y572105D01*
X3306278Y570855D01*
X3305813Y569188D01*
X3305658Y567313D01*
X3305813Y565438D01*
X3306278Y563771D01*
X3306898Y562521D01*
X3307828Y561480D01*
X3309068Y561063D01*
X3310308Y561480D01*
X3311238Y562521D01*
X3311858Y563771D01*
X3312323Y565438D01*
X3312478Y567313D01*
X3312323Y569188D01*
X3311858Y570855D01*
X3311238Y572105D01*
X3310308Y573146D01*
X3309068Y573563D01*
G01X3208163Y598380D02*
X3211883D01*
G01X3209868Y601088D02*
Y595671D01*
G01X3219323Y604630D02*
X3220253Y605879D01*
X3221338Y606505D01*
X3222578Y606713D01*
X3224128Y606296D01*
X3225213Y605255D01*
X3225523Y604005D01*
X3225368Y602754D01*
X3224748Y601713D01*
X3221648Y599630D01*
X3220253Y598171D01*
X3219323Y596088D01*
X3219013Y594213D01*
X3225523D01*
G01X3234668Y593796D02*
X3234358Y594005D01*
Y594421D01*
X3234668Y594630D01*
X3234978Y594421D01*
Y594005D01*
X3234668Y593796D01*
G01X3247068Y606713D02*
X3245828Y606296D01*
X3244898Y605255D01*
X3244278Y604005D01*
X3243813Y602338D01*
X3243658Y600463D01*
X3243813Y598588D01*
X3244278Y596921D01*
X3244898Y595671D01*
X3245828Y594630D01*
X3247068Y594213D01*
X3248308Y594630D01*
X3249238Y595671D01*
X3249858Y596921D01*
X3250323Y598588D01*
X3250478Y600463D01*
X3250323Y602338D01*
X3249858Y604005D01*
X3249238Y605255D01*
X3248308Y606296D01*
X3247068Y606713D01*
G01X3256678Y593796D02*
X3262258Y606713D01*
G01X3269853Y598380D02*
X3273883D01*
G01X3281323Y604630D02*
X3282253Y605879D01*
X3283338Y606505D01*
X3284578Y606713D01*
X3286128Y606296D01*
X3287213Y605255D01*
X3287523Y604005D01*
X3287368Y602754D01*
X3286748Y601713D01*
X3283648Y599630D01*
X3282253Y598171D01*
X3281323Y596088D01*
X3281013Y594213D01*
X3287523D01*
G01X3296668Y593796D02*
X3296358Y594005D01*
Y594421D01*
X3296668Y594630D01*
X3296978Y594421D01*
Y594005D01*
X3296668Y593796D01*
G01X3309068Y606713D02*
X3307828Y606296D01*
X3306898Y605255D01*
X3306278Y604005D01*
X3305813Y602338D01*
X3305658Y600463D01*
X3305813Y598588D01*
X3306278Y596921D01*
X3306898Y595671D01*
X3307828Y594630D01*
X3309068Y594213D01*
X3310308Y594630D01*
X3311238Y595671D01*
X3311858Y596921D01*
X3312323Y598588D01*
X3312478Y600463D01*
X3312323Y602338D01*
X3311858Y604005D01*
X3311238Y605255D01*
X3310308Y606296D01*
X3309068Y606713D01*
G01X3208163Y631530D02*
X3211883D01*
G01X3209868Y634238D02*
Y628821D01*
G01X3218858Y629863D02*
X3219788Y628404D01*
X3221028Y627571D01*
X3222423Y627363D01*
X3223663Y627571D01*
X3224903Y628613D01*
X3225678Y629863D01*
X3225833Y631113D01*
X3225523Y632571D01*
X3224438Y633613D01*
X3223353Y634030D01*
X3221958D01*
G01X3223353D02*
X3224283Y634655D01*
X3225058Y635696D01*
X3225368Y636946D01*
X3225058Y638196D01*
X3224283Y639238D01*
X3222888Y639863D01*
X3221493Y639655D01*
X3220098Y638821D01*
G01X3234668Y626946D02*
X3234358Y627155D01*
Y627571D01*
X3234668Y627780D01*
X3234978Y627571D01*
Y627155D01*
X3234668Y626946D01*
G01X3247068Y639863D02*
X3245828Y639446D01*
X3244898Y638405D01*
X3244278Y637155D01*
X3243813Y635488D01*
X3243658Y633613D01*
X3243813Y631738D01*
X3244278Y630071D01*
X3244898Y628821D01*
X3245828Y627780D01*
X3247068Y627363D01*
X3248308Y627780D01*
X3249238Y628821D01*
X3249858Y630071D01*
X3250323Y631738D01*
X3250478Y633613D01*
X3250323Y635488D01*
X3249858Y637155D01*
X3249238Y638405D01*
X3248308Y639446D01*
X3247068Y639863D01*
G01X3256678Y626946D02*
X3262258Y639863D01*
G01X3269853Y631530D02*
X3273883D01*
G01X3280858Y629863D02*
X3281788Y628404D01*
X3283028Y627571D01*
X3284423Y627363D01*
X3285663Y627571D01*
X3286903Y628613D01*
X3287678Y629863D01*
X3287833Y631113D01*
X3287523Y632571D01*
X3286438Y633613D01*
X3285353Y634030D01*
X3283958D01*
G01X3285353D02*
X3286283Y634655D01*
X3287058Y635696D01*
X3287368Y636946D01*
X3287058Y638196D01*
X3286283Y639238D01*
X3284888Y639863D01*
X3283493Y639655D01*
X3282098Y638821D01*
G01X3296668Y626946D02*
X3296358Y627155D01*
Y627571D01*
X3296668Y627780D01*
X3296978Y627571D01*
Y627155D01*
X3296668Y626946D01*
G01X3309068Y639863D02*
X3307828Y639446D01*
X3306898Y638405D01*
X3306278Y637155D01*
X3305813Y635488D01*
X3305658Y633613D01*
X3305813Y631738D01*
X3306278Y630071D01*
X3306898Y628821D01*
X3307828Y627780D01*
X3309068Y627363D01*
X3310308Y627780D01*
X3311238Y628821D01*
X3311858Y630071D01*
X3312323Y631738D01*
X3312478Y633613D01*
X3312323Y635488D01*
X3311858Y637155D01*
X3311238Y638405D01*
X3310308Y639446D01*
X3309068Y639863D01*
G01X3208163Y664680D02*
X3211883D01*
G01X3209868Y667388D02*
Y661971D01*
G01X3219323Y670930D02*
X3220253Y672179D01*
X3221338Y672805D01*
X3222578Y673013D01*
X3224128Y672596D01*
X3225213Y671555D01*
X3225523Y670305D01*
X3225368Y669054D01*
X3224748Y668013D01*
X3221648Y665930D01*
X3220253Y664471D01*
X3219323Y662388D01*
X3219013Y660513D01*
X3225523D01*
G01X3234668Y660096D02*
X3234358Y660305D01*
Y660721D01*
X3234668Y660930D01*
X3234978Y660721D01*
Y660305D01*
X3234668Y660096D01*
G01X3247068Y673013D02*
X3245828Y672596D01*
X3244898Y671555D01*
X3244278Y670305D01*
X3243813Y668638D01*
X3243658Y666763D01*
X3243813Y664888D01*
X3244278Y663221D01*
X3244898Y661971D01*
X3245828Y660930D01*
X3247068Y660513D01*
X3248308Y660930D01*
X3249238Y661971D01*
X3249858Y663221D01*
X3250323Y664888D01*
X3250478Y666763D01*
X3250323Y668638D01*
X3249858Y670305D01*
X3249238Y671555D01*
X3248308Y672596D01*
X3247068Y673013D01*
G01X3256678Y660096D02*
X3262258Y673013D01*
G01X3269853Y664680D02*
X3273883D01*
G01X3281323Y670930D02*
X3282253Y672179D01*
X3283338Y672805D01*
X3284578Y673013D01*
X3286128Y672596D01*
X3287213Y671555D01*
X3287523Y670305D01*
X3287368Y669054D01*
X3286748Y668013D01*
X3283648Y665930D01*
X3282253Y664471D01*
X3281323Y662388D01*
X3281013Y660513D01*
X3287523D01*
G01X3296668Y660096D02*
X3296358Y660305D01*
Y660721D01*
X3296668Y660930D01*
X3296978Y660721D01*
Y660305D01*
X3296668Y660096D01*
G01X3309068Y673013D02*
X3307828Y672596D01*
X3306898Y671555D01*
X3306278Y670305D01*
X3305813Y668638D01*
X3305658Y666763D01*
X3305813Y664888D01*
X3306278Y663221D01*
X3306898Y661971D01*
X3307828Y660930D01*
X3309068Y660513D01*
X3310308Y660930D01*
X3311238Y661971D01*
X3311858Y663221D01*
X3312323Y664888D01*
X3312478Y666763D01*
X3312323Y668638D01*
X3311858Y670305D01*
X3311238Y671555D01*
X3310308Y672596D01*
X3309068Y673013D01*
G01X3208163Y697830D02*
X3211883D01*
G01X3209868Y700538D02*
Y695121D01*
G01X3219323Y704080D02*
X3220253Y705329D01*
X3221338Y705955D01*
X3222578Y706163D01*
X3224128Y705746D01*
X3225213Y704705D01*
X3225523Y703455D01*
X3225368Y702204D01*
X3224748Y701163D01*
X3221648Y699080D01*
X3220253Y697621D01*
X3219323Y695538D01*
X3219013Y693663D01*
X3225523D01*
G01X3234668Y693246D02*
X3234358Y693455D01*
Y693871D01*
X3234668Y694080D01*
X3234978Y693871D01*
Y693455D01*
X3234668Y693246D01*
G01X3247068Y706163D02*
X3245828Y705746D01*
X3244898Y704705D01*
X3244278Y703455D01*
X3243813Y701788D01*
X3243658Y699913D01*
X3243813Y698038D01*
X3244278Y696371D01*
X3244898Y695121D01*
X3245828Y694080D01*
X3247068Y693663D01*
X3248308Y694080D01*
X3249238Y695121D01*
X3249858Y696371D01*
X3250323Y698038D01*
X3250478Y699913D01*
X3250323Y701788D01*
X3249858Y703455D01*
X3249238Y704705D01*
X3248308Y705746D01*
X3247068Y706163D01*
G01X3256678Y693246D02*
X3262258Y706163D01*
G01X3269853Y697830D02*
X3273883D01*
G01X3281323Y704080D02*
X3282253Y705329D01*
X3283338Y705955D01*
X3284578Y706163D01*
X3286128Y705746D01*
X3287213Y704705D01*
X3287523Y703455D01*
X3287368Y702204D01*
X3286748Y701163D01*
X3283648Y699080D01*
X3282253Y697621D01*
X3281323Y695538D01*
X3281013Y693663D01*
X3287523D01*
G01X3296668Y693246D02*
X3296358Y693455D01*
Y693871D01*
X3296668Y694080D01*
X3296978Y693871D01*
Y693455D01*
X3296668Y693246D01*
G01X3309068Y706163D02*
X3307828Y705746D01*
X3306898Y704705D01*
X3306278Y703455D01*
X3305813Y701788D01*
X3305658Y699913D01*
X3305813Y698038D01*
X3306278Y696371D01*
X3306898Y695121D01*
X3307828Y694080D01*
X3309068Y693663D01*
X3310308Y694080D01*
X3311238Y695121D01*
X3311858Y696371D01*
X3312323Y698038D01*
X3312478Y699913D01*
X3312323Y701788D01*
X3311858Y703455D01*
X3311238Y704705D01*
X3310308Y705746D01*
X3309068Y706163D01*
G01X3208163Y730980D02*
X3211883D01*
G01X3209868Y733688D02*
Y728271D01*
G01X3218858Y729313D02*
X3219788Y727854D01*
X3221028Y727021D01*
X3222423Y726813D01*
X3223663Y727021D01*
X3224903Y728063D01*
X3225678Y729313D01*
X3225833Y730563D01*
X3225523Y732021D01*
X3224438Y733063D01*
X3223353Y733480D01*
X3221958D01*
G01X3223353D02*
X3224283Y734105D01*
X3225058Y735146D01*
X3225368Y736396D01*
X3225058Y737646D01*
X3224283Y738688D01*
X3222888Y739313D01*
X3221493Y739105D01*
X3220098Y738271D01*
G01X3234668Y726396D02*
X3234358Y726605D01*
Y727021D01*
X3234668Y727230D01*
X3234978Y727021D01*
Y726605D01*
X3234668Y726396D01*
G01X3247068Y739313D02*
X3245828Y738896D01*
X3244898Y737855D01*
X3244278Y736605D01*
X3243813Y734938D01*
X3243658Y733063D01*
X3243813Y731188D01*
X3244278Y729521D01*
X3244898Y728271D01*
X3245828Y727230D01*
X3247068Y726813D01*
X3248308Y727230D01*
X3249238Y728271D01*
X3249858Y729521D01*
X3250323Y731188D01*
X3250478Y733063D01*
X3250323Y734938D01*
X3249858Y736605D01*
X3249238Y737855D01*
X3248308Y738896D01*
X3247068Y739313D01*
G01X3256678Y726396D02*
X3262258Y739313D01*
G01X3269853Y730980D02*
X3273883D01*
G01X3280858Y729313D02*
X3281788Y727854D01*
X3283028Y727021D01*
X3284423Y726813D01*
X3285663Y727021D01*
X3286903Y728063D01*
X3287678Y729313D01*
X3287833Y730563D01*
X3287523Y732021D01*
X3286438Y733063D01*
X3285353Y733480D01*
X3283958D01*
G01X3285353D02*
X3286283Y734105D01*
X3287058Y735146D01*
X3287368Y736396D01*
X3287058Y737646D01*
X3286283Y738688D01*
X3284888Y739313D01*
X3283493Y739105D01*
X3282098Y738271D01*
G01X3296668Y726396D02*
X3296358Y726605D01*
Y727021D01*
X3296668Y727230D01*
X3296978Y727021D01*
Y726605D01*
X3296668Y726396D01*
G01X3309068Y739313D02*
X3307828Y738896D01*
X3306898Y737855D01*
X3306278Y736605D01*
X3305813Y734938D01*
X3305658Y733063D01*
X3305813Y731188D01*
X3306278Y729521D01*
X3306898Y728271D01*
X3307828Y727230D01*
X3309068Y726813D01*
X3310308Y727230D01*
X3311238Y728271D01*
X3311858Y729521D01*
X3312323Y731188D01*
X3312478Y733063D01*
X3312323Y734938D01*
X3311858Y736605D01*
X3311238Y737855D01*
X3310308Y738896D01*
X3309068Y739313D01*
G01X3208163Y896730D02*
X3211883D01*
G01X3209868Y899438D02*
Y894021D01*
G01X3219323Y902980D02*
X3220253Y904229D01*
X3221338Y904855D01*
X3222578Y905063D01*
X3224128Y904646D01*
X3225213Y903605D01*
X3225523Y902355D01*
X3225368Y901104D01*
X3224748Y900063D01*
X3221648Y897980D01*
X3220253Y896521D01*
X3219323Y894438D01*
X3219013Y892563D01*
X3225523D01*
G01X3234668Y892146D02*
X3234358Y892355D01*
Y892771D01*
X3234668Y892980D01*
X3234978Y892771D01*
Y892355D01*
X3234668Y892146D01*
G01X3247068Y905063D02*
X3245828Y904646D01*
X3244898Y903605D01*
X3244278Y902355D01*
X3243813Y900688D01*
X3243658Y898813D01*
X3243813Y896938D01*
X3244278Y895271D01*
X3244898Y894021D01*
X3245828Y892980D01*
X3247068Y892563D01*
X3248308Y892980D01*
X3249238Y894021D01*
X3249858Y895271D01*
X3250323Y896938D01*
X3250478Y898813D01*
X3250323Y900688D01*
X3249858Y902355D01*
X3249238Y903605D01*
X3248308Y904646D01*
X3247068Y905063D01*
G01X3256678Y892146D02*
X3262258Y905063D01*
G01X3269853Y896730D02*
X3273883D01*
G01X3281323Y902980D02*
X3282253Y904229D01*
X3283338Y904855D01*
X3284578Y905063D01*
X3286128Y904646D01*
X3287213Y903605D01*
X3287523Y902355D01*
X3287368Y901104D01*
X3286748Y900063D01*
X3283648Y897980D01*
X3282253Y896521D01*
X3281323Y894438D01*
X3281013Y892563D01*
X3287523D01*
G01X3296668Y892146D02*
X3296358Y892355D01*
Y892771D01*
X3296668Y892980D01*
X3296978Y892771D01*
Y892355D01*
X3296668Y892146D01*
G01X3309068Y905063D02*
X3307828Y904646D01*
X3306898Y903605D01*
X3306278Y902355D01*
X3305813Y900688D01*
X3305658Y898813D01*
X3305813Y896938D01*
X3306278Y895271D01*
X3306898Y894021D01*
X3307828Y892980D01*
X3309068Y892563D01*
X3310308Y892980D01*
X3311238Y894021D01*
X3311858Y895271D01*
X3312323Y896938D01*
X3312478Y898813D01*
X3312323Y900688D01*
X3311858Y902355D01*
X3311238Y903605D01*
X3310308Y904646D01*
X3309068Y905063D01*
G01X3208163Y929880D02*
X3211883D01*
G01X3209868Y932588D02*
Y927171D01*
G01X3222268Y938213D02*
X3221028Y937796D01*
X3220098Y936755D01*
X3219478Y935505D01*
X3219013Y933838D01*
X3218858Y931963D01*
X3219013Y930088D01*
X3219478Y928421D01*
X3220098Y927171D01*
X3221028Y926130D01*
X3222268Y925713D01*
X3223508Y926130D01*
X3224438Y927171D01*
X3225058Y928421D01*
X3225523Y930088D01*
X3225678Y931963D01*
X3225523Y933838D01*
X3225058Y935505D01*
X3224438Y936755D01*
X3223508Y937796D01*
X3222268Y938213D01*
G01X3234668Y925296D02*
X3234358Y925505D01*
Y925921D01*
X3234668Y926130D01*
X3234978Y925921D01*
Y925505D01*
X3234668Y925296D01*
G01X3247068Y938213D02*
X3245828Y937796D01*
X3244898Y936755D01*
X3244278Y935505D01*
X3243813Y933838D01*
X3243658Y931963D01*
X3243813Y930088D01*
X3244278Y928421D01*
X3244898Y927171D01*
X3245828Y926130D01*
X3247068Y925713D01*
X3248308Y926130D01*
X3249238Y927171D01*
X3249858Y928421D01*
X3250323Y930088D01*
X3250478Y931963D01*
X3250323Y933838D01*
X3249858Y935505D01*
X3249238Y936755D01*
X3248308Y937796D01*
X3247068Y938213D01*
G01X3256678Y925296D02*
X3262258Y938213D01*
G01X3269853Y929880D02*
X3273883D01*
G01X3284268Y925713D02*
X3285353Y925921D01*
X3286593Y926546D01*
X3287368Y927588D01*
X3287678Y929046D01*
X3287368Y930504D01*
X3286438Y931755D01*
X3285043Y932380D01*
X3283493D01*
X3282563Y932796D01*
X3281788Y933838D01*
X3281478Y935296D01*
X3281943Y936755D01*
X3283028Y937796D01*
X3284268Y938213D01*
X3285508Y937796D01*
X3286593Y936755D01*
X3287058Y935296D01*
X3286748Y933838D01*
X3285973Y932796D01*
X3285043Y932380D01*
X3283493D01*
X3282098Y931755D01*
X3281168Y930504D01*
X3280858Y929046D01*
X3281168Y927588D01*
X3281943Y926546D01*
X3283183Y925921D01*
X3284268Y925713D01*
G01X3296668Y925296D02*
X3296358Y925505D01*
Y925921D01*
X3296668Y926130D01*
X3296978Y925921D01*
Y925505D01*
X3296668Y925296D01*
G01X3309068Y938213D02*
X3307828Y937796D01*
X3306898Y936755D01*
X3306278Y935505D01*
X3305813Y933838D01*
X3305658Y931963D01*
X3305813Y930088D01*
X3306278Y928421D01*
X3306898Y927171D01*
X3307828Y926130D01*
X3309068Y925713D01*
X3310308Y926130D01*
X3311238Y927171D01*
X3311858Y928421D01*
X3312323Y930088D01*
X3312478Y931963D01*
X3312323Y933838D01*
X3311858Y935505D01*
X3311238Y936755D01*
X3310308Y937796D01*
X3309068Y938213D01*
G01X3208163Y963030D02*
X3211883D01*
G01X3209868Y965738D02*
Y960321D01*
G01X3222268Y971363D02*
X3221028Y970946D01*
X3220098Y969905D01*
X3219478Y968655D01*
X3219013Y966988D01*
X3218858Y965113D01*
X3219013Y963238D01*
X3219478Y961571D01*
X3220098Y960321D01*
X3221028Y959280D01*
X3222268Y958863D01*
X3223508Y959280D01*
X3224438Y960321D01*
X3225058Y961571D01*
X3225523Y963238D01*
X3225678Y965113D01*
X3225523Y966988D01*
X3225058Y968655D01*
X3224438Y969905D01*
X3223508Y970946D01*
X3222268Y971363D01*
G01X3234668Y958446D02*
X3234358Y958655D01*
Y959071D01*
X3234668Y959280D01*
X3234978Y959071D01*
Y958655D01*
X3234668Y958446D01*
G01X3247068Y971363D02*
X3245828Y970946D01*
X3244898Y969905D01*
X3244278Y968655D01*
X3243813Y966988D01*
X3243658Y965113D01*
X3243813Y963238D01*
X3244278Y961571D01*
X3244898Y960321D01*
X3245828Y959280D01*
X3247068Y958863D01*
X3248308Y959280D01*
X3249238Y960321D01*
X3249858Y961571D01*
X3250323Y963238D01*
X3250478Y965113D01*
X3250323Y966988D01*
X3249858Y968655D01*
X3249238Y969905D01*
X3248308Y970946D01*
X3247068Y971363D01*
G01X3256678Y958446D02*
X3262258Y971363D01*
G01X3269853Y963030D02*
X3273883D01*
G01X3284268Y958863D02*
X3285353Y959071D01*
X3286593Y959696D01*
X3287368Y960738D01*
X3287678Y962196D01*
X3287368Y963654D01*
X3286438Y964905D01*
X3285043Y965530D01*
X3283493D01*
X3282563Y965946D01*
X3281788Y966988D01*
X3281478Y968446D01*
X3281943Y969905D01*
X3283028Y970946D01*
X3284268Y971363D01*
X3285508Y970946D01*
X3286593Y969905D01*
X3287058Y968446D01*
X3286748Y966988D01*
X3285973Y965946D01*
X3285043Y965530D01*
X3283493D01*
X3282098Y964905D01*
X3281168Y963654D01*
X3280858Y962196D01*
X3281168Y960738D01*
X3281943Y959696D01*
X3283183Y959071D01*
X3284268Y958863D01*
G01X3296668Y958446D02*
X3296358Y958655D01*
Y959071D01*
X3296668Y959280D01*
X3296978Y959071D01*
Y958655D01*
X3296668Y958446D01*
G01X3309068Y971363D02*
X3307828Y970946D01*
X3306898Y969905D01*
X3306278Y968655D01*
X3305813Y966988D01*
X3305658Y965113D01*
X3305813Y963238D01*
X3306278Y961571D01*
X3306898Y960321D01*
X3307828Y959280D01*
X3309068Y958863D01*
X3310308Y959280D01*
X3311238Y960321D01*
X3311858Y961571D01*
X3312323Y963238D01*
X3312478Y965113D01*
X3312323Y966988D01*
X3311858Y968655D01*
X3311238Y969905D01*
X3310308Y970946D01*
X3309068Y971363D01*
G01X3206381Y1258220D02*
X3210411D01*
G01X3206381Y1283220D02*
X3210411D01*
G01X3206381Y1308220D02*
X3210411D01*
G01X3206381Y1608238D02*
X3210411D01*
G01X3206381Y1633238D02*
X3210411D01*
G01X3206381Y1658238D02*
X3210411D01*
G01X3229664Y2352151D02*
Y2364651D01*
X3227804Y2362151D01*
G01Y2352151D02*
X3231524D01*
G01X3238654Y2354651D02*
X3239584Y2353192D01*
X3240824Y2352359D01*
X3242219Y2352151D01*
X3243459Y2352359D01*
X3244699Y2353401D01*
X3245474Y2354651D01*
X3245629Y2355901D01*
X3245319Y2357359D01*
X3244234Y2358401D01*
X3243149Y2358818D01*
X3241754D01*
G01X3243149D02*
X3244079Y2359443D01*
X3244854Y2360484D01*
X3245164Y2361734D01*
X3244854Y2362984D01*
X3244079Y2364026D01*
X3242684Y2364651D01*
X3241289Y2364443D01*
X3239894Y2363609D01*
G01X3251519Y2362568D02*
X3252449Y2363817D01*
X3253534Y2364443D01*
X3254774Y2364651D01*
X3256324Y2364234D01*
X3257409Y2363193D01*
X3257719Y2361943D01*
X3257564Y2360692D01*
X3256944Y2359651D01*
X3253844Y2357568D01*
X3252449Y2356109D01*
X3251519Y2354026D01*
X3251209Y2352151D01*
X3257719D01*
G01X3226719Y2387568D02*
X3227649Y2388817D01*
X3228734Y2389443D01*
X3229974Y2389651D01*
X3231524Y2389234D01*
X3232609Y2388193D01*
X3232919Y2386943D01*
X3232764Y2385692D01*
X3232144Y2384651D01*
X3229044Y2382568D01*
X3227649Y2381109D01*
X3226719Y2379026D01*
X3226409Y2377151D01*
X3232919D01*
G01X3239119Y2382359D02*
X3240204Y2383818D01*
X3241134Y2384651D01*
X3242374Y2385068D01*
X3243459Y2384651D01*
X3244234Y2383818D01*
X3244854Y2382568D01*
X3245009Y2381109D01*
X3244854Y2379859D01*
X3244234Y2378609D01*
X3243304Y2377568D01*
X3242219Y2377151D01*
X3240979Y2377568D01*
X3239894Y2378817D01*
X3239274Y2380693D01*
X3239119Y2382776D01*
X3239429Y2385484D01*
X3239894Y2386943D01*
X3240669Y2388401D01*
X3241754Y2389443D01*
X3242839Y2389651D01*
X3243924Y2389234D01*
X3244699Y2388193D01*
G01X3254464Y2389651D02*
X3253224Y2389234D01*
X3252294Y2388193D01*
X3251674Y2386943D01*
X3251209Y2385276D01*
X3251054Y2383401D01*
X3251209Y2381526D01*
X3251674Y2379859D01*
X3252294Y2378609D01*
X3253224Y2377568D01*
X3254464Y2377151D01*
X3255704Y2377568D01*
X3256634Y2378609D01*
X3257254Y2379859D01*
X3257719Y2381526D01*
X3257874Y2383401D01*
X3257719Y2385276D01*
X3257254Y2386943D01*
X3256634Y2388193D01*
X3255704Y2389234D01*
X3254464Y2389651D01*
G01X3229664Y2402151D02*
Y2414651D01*
X3227804Y2412151D01*
G01Y2402151D02*
X3231524D01*
G01X3238654Y2404651D02*
X3239584Y2403192D01*
X3240824Y2402359D01*
X3242219Y2402151D01*
X3243459Y2402359D01*
X3244699Y2403401D01*
X3245474Y2404651D01*
X3245629Y2405901D01*
X3245319Y2407359D01*
X3244234Y2408401D01*
X3243149Y2408818D01*
X3241754D01*
G01X3243149D02*
X3244079Y2409443D01*
X3244854Y2410484D01*
X3245164Y2411734D01*
X3244854Y2412984D01*
X3244079Y2414026D01*
X3242684Y2414651D01*
X3241289Y2414443D01*
X3239894Y2413609D01*
G01X3251519Y2407359D02*
X3252604Y2408818D01*
X3253534Y2409651D01*
X3254774Y2410068D01*
X3255859Y2409651D01*
X3256634Y2408818D01*
X3257254Y2407568D01*
X3257409Y2406109D01*
X3257254Y2404859D01*
X3256634Y2403609D01*
X3255704Y2402568D01*
X3254619Y2402151D01*
X3253379Y2402568D01*
X3252294Y2403817D01*
X3251674Y2405693D01*
X3251519Y2407776D01*
X3251829Y2410484D01*
X3252294Y2411943D01*
X3253069Y2413401D01*
X3254154Y2414443D01*
X3255239Y2414651D01*
X3256324Y2414234D01*
X3257099Y2413193D01*
G01X3229664Y2427151D02*
X3228424Y2427359D01*
X3227339Y2428192D01*
X3226409Y2429443D01*
X3225789Y2430901D01*
X3225479Y2432568D01*
Y2434234D01*
X3225789Y2435901D01*
X3226409Y2437359D01*
X3227339Y2438609D01*
X3228424Y2439443D01*
X3229664Y2439651D01*
X3230904Y2439443D01*
X3231989Y2438609D01*
X3232919Y2437359D01*
X3233539Y2435901D01*
X3233849Y2434234D01*
Y2432568D01*
X3233539Y2430901D01*
X3232919Y2429443D01*
X3231989Y2428192D01*
X3230904Y2427359D01*
X3229664Y2427151D01*
G01X3230904Y2430484D02*
X3232764Y2427151D01*
G01X3242064Y2439651D02*
Y2427151D01*
G01X3238499Y2439651D02*
X3245629D01*
G01X3254464Y2427151D02*
Y2432776D01*
X3251364Y2439651D01*
G01X3257564D02*
X3254464Y2432776D01*
G01X3243391Y2712463D02*
Y2724963D01*
X3241531Y2722463D01*
G01Y2712463D02*
X3245251D01*
G01X3252381Y2714963D02*
X3253311Y2713504D01*
X3254551Y2712671D01*
X3255946Y2712463D01*
X3257186Y2712671D01*
X3258426Y2713713D01*
X3259201Y2714963D01*
X3259356Y2716213D01*
X3259046Y2717671D01*
X3257961Y2718713D01*
X3256876Y2719130D01*
X3255481D01*
G01X3256876D02*
X3257806Y2719755D01*
X3258581Y2720796D01*
X3258891Y2722046D01*
X3258581Y2723296D01*
X3257806Y2724338D01*
X3256411Y2724963D01*
X3255016Y2724755D01*
X3253621Y2723921D01*
G01X3265246Y2722880D02*
X3266176Y2724129D01*
X3267261Y2724755D01*
X3268501Y2724963D01*
X3270051Y2724546D01*
X3271136Y2723505D01*
X3271446Y2722255D01*
X3271291Y2721004D01*
X3270671Y2719963D01*
X3267571Y2717880D01*
X3266176Y2716421D01*
X3265246Y2714338D01*
X3264936Y2712463D01*
X3271446D01*
G01X3249591Y2737463D02*
Y2749963D01*
X3247731Y2747463D01*
G01Y2737463D02*
X3251451D01*
G01X3259046Y2747880D02*
X3259976Y2749129D01*
X3261061Y2749755D01*
X3262301Y2749963D01*
X3263851Y2749546D01*
X3264936Y2748505D01*
X3265246Y2747255D01*
X3265091Y2746004D01*
X3264471Y2744963D01*
X3261371Y2742880D01*
X3259976Y2741421D01*
X3259046Y2739338D01*
X3258736Y2737463D01*
X3265246D01*
G01X3243391Y2762463D02*
Y2774963D01*
X3241531Y2772463D01*
G01Y2762463D02*
X3245251D01*
G01X3252846Y2772880D02*
X3253776Y2774129D01*
X3254861Y2774755D01*
X3256101Y2774963D01*
X3257651Y2774546D01*
X3258736Y2773505D01*
X3259046Y2772255D01*
X3258891Y2771004D01*
X3258271Y2769963D01*
X3255171Y2767880D01*
X3253776Y2766421D01*
X3252846Y2764338D01*
X3252536Y2762463D01*
X3259046D01*
G01X3268191D02*
X3269276Y2762671D01*
X3270516Y2763296D01*
X3271291Y2764338D01*
X3271601Y2765796D01*
X3271291Y2767254D01*
X3270361Y2768505D01*
X3268966Y2769130D01*
X3267416D01*
X3266486Y2769546D01*
X3265711Y2770588D01*
X3265401Y2772046D01*
X3265866Y2773505D01*
X3266951Y2774546D01*
X3268191Y2774963D01*
X3269431Y2774546D01*
X3270516Y2773505D01*
X3270981Y2772046D01*
X3270671Y2770588D01*
X3269896Y2769546D01*
X3268966Y2769130D01*
X3267416D01*
X3266021Y2768505D01*
X3265091Y2767254D01*
X3264781Y2765796D01*
X3265091Y2764338D01*
X3265866Y2763296D01*
X3267106Y2762671D01*
X3268191Y2762463D01*
G01X3243391Y2787463D02*
X3242151Y2787671D01*
X3241066Y2788504D01*
X3240136Y2789755D01*
X3239516Y2791213D01*
X3239206Y2792880D01*
Y2794546D01*
X3239516Y2796213D01*
X3240136Y2797671D01*
X3241066Y2798921D01*
X3242151Y2799755D01*
X3243391Y2799963D01*
X3244631Y2799755D01*
X3245716Y2798921D01*
X3246646Y2797671D01*
X3247266Y2796213D01*
X3247576Y2794546D01*
Y2792880D01*
X3247266Y2791213D01*
X3246646Y2789755D01*
X3245716Y2788504D01*
X3244631Y2787671D01*
X3243391Y2787463D01*
G01X3244631Y2790796D02*
X3246491Y2787463D01*
G01X3255791Y2799963D02*
Y2787463D01*
G01X3252226Y2799963D02*
X3259356D01*
G01X3268191Y2787463D02*
Y2793088D01*
X3265091Y2799963D01*
G01X3271291D02*
X3268191Y2793088D01*
G01X3263980Y1967816D02*
Y1980316D01*
X3262120Y1977816D01*
G01Y1967816D02*
X3265840D01*
G01X3273435Y1978233D02*
X3274365Y1979482D01*
X3275450Y1980108D01*
X3276690Y1980316D01*
X3278240Y1979899D01*
X3279325Y1978858D01*
X3279635Y1977608D01*
X3279480Y1976357D01*
X3278860Y1975316D01*
X3275760Y1973233D01*
X3274365Y1971774D01*
X3273435Y1969691D01*
X3273125Y1967816D01*
X3279635D01*
G01X3288780D02*
X3289865Y1968024D01*
X3291105Y1968649D01*
X3291880Y1969691D01*
X3292190Y1971149D01*
X3291880Y1972607D01*
X3290950Y1973858D01*
X3289555Y1974483D01*
X3288005D01*
X3287075Y1974899D01*
X3286300Y1975941D01*
X3285990Y1977399D01*
X3286455Y1978858D01*
X3287540Y1979899D01*
X3288780Y1980316D01*
X3290020Y1979899D01*
X3291105Y1978858D01*
X3291570Y1977399D01*
X3291260Y1975941D01*
X3290485Y1974899D01*
X3289555Y1974483D01*
X3288005D01*
X3286610Y1973858D01*
X3285680Y1972607D01*
X3285370Y1971149D01*
X3285680Y1969691D01*
X3286455Y1968649D01*
X3287695Y1968024D01*
X3288780Y1967816D01*
G01X3261035Y2003233D02*
X3261965Y2004482D01*
X3263050Y2005108D01*
X3264290Y2005316D01*
X3265840Y2004899D01*
X3266925Y2003858D01*
X3267235Y2002608D01*
X3267080Y2001357D01*
X3266460Y2000316D01*
X3263360Y1998233D01*
X3261965Y1996774D01*
X3261035Y1994691D01*
X3260725Y1992816D01*
X3267235D01*
G01X3276070D02*
X3276380Y1995524D01*
X3276845Y1997816D01*
X3277465Y1999899D01*
X3278240Y2002191D01*
X3279480Y2005316D01*
X3273280D01*
G01X3285835Y1998024D02*
X3286920Y1999483D01*
X3287850Y2000316D01*
X3289090Y2000733D01*
X3290175Y2000316D01*
X3290950Y1999483D01*
X3291570Y1998233D01*
X3291725Y1996774D01*
X3291570Y1995524D01*
X3290950Y1994274D01*
X3290020Y1993233D01*
X3288935Y1992816D01*
X3287695Y1993233D01*
X3286610Y1994482D01*
X3285990Y1996358D01*
X3285835Y1998441D01*
X3286145Y2001149D01*
X3286610Y2002608D01*
X3287385Y2004066D01*
X3288470Y2005108D01*
X3289555Y2005316D01*
X3290640Y2004899D01*
X3291415Y2003858D01*
G01X3260570Y2020316D02*
X3261500Y2018857D01*
X3262740Y2018024D01*
X3264135Y2017816D01*
X3265375Y2018024D01*
X3266615Y2019066D01*
X3267390Y2020316D01*
X3267545Y2021566D01*
X3267235Y2023024D01*
X3266150Y2024066D01*
X3265065Y2024483D01*
X3263670D01*
G01X3265065D02*
X3265995Y2025108D01*
X3266770Y2026149D01*
X3267080Y2027399D01*
X3266770Y2028649D01*
X3265995Y2029691D01*
X3264600Y2030316D01*
X3263205Y2030108D01*
X3261810Y2029274D01*
G01X3276380Y2017816D02*
X3277465Y2018024D01*
X3278705Y2018649D01*
X3279480Y2019691D01*
X3279790Y2021149D01*
X3279480Y2022607D01*
X3278550Y2023858D01*
X3277155Y2024483D01*
X3275605D01*
X3274675Y2024899D01*
X3273900Y2025941D01*
X3273590Y2027399D01*
X3274055Y2028858D01*
X3275140Y2029899D01*
X3276380Y2030316D01*
X3277620Y2029899D01*
X3278705Y2028858D01*
X3279170Y2027399D01*
X3278860Y2025941D01*
X3278085Y2024899D01*
X3277155Y2024483D01*
X3275605D01*
X3274210Y2023858D01*
X3273280Y2022607D01*
X3272970Y2021149D01*
X3273280Y2019691D01*
X3274055Y2018649D01*
X3275295Y2018024D01*
X3276380Y2017816D01*
G01X3290640D02*
Y2030316D01*
X3284905Y2021358D01*
X3292655D01*
G01X3263980Y2042816D02*
X3262740Y2043024D01*
X3261655Y2043857D01*
X3260725Y2045108D01*
X3260105Y2046566D01*
X3259795Y2048233D01*
Y2049899D01*
X3260105Y2051566D01*
X3260725Y2053024D01*
X3261655Y2054274D01*
X3262740Y2055108D01*
X3263980Y2055316D01*
X3265220Y2055108D01*
X3266305Y2054274D01*
X3267235Y2053024D01*
X3267855Y2051566D01*
X3268165Y2049899D01*
Y2048233D01*
X3267855Y2046566D01*
X3267235Y2045108D01*
X3266305Y2043857D01*
X3265220Y2043024D01*
X3263980Y2042816D01*
G01X3265220Y2046149D02*
X3267080Y2042816D01*
G01X3276380Y2055316D02*
Y2042816D01*
G01X3272815Y2055316D02*
X3279945D01*
G01X3288780Y2042816D02*
Y2048441D01*
X3285680Y2055316D01*
G01X3291880D02*
X3288780Y2048441D01*
G01X3298296Y1254053D02*
Y1266553D01*
X3296436Y1264053D01*
G01Y1254053D02*
X3300156D01*
G01X3307286Y1256553D02*
X3308216Y1255094D01*
X3309456Y1254261D01*
X3310851Y1254053D01*
X3312091Y1254261D01*
X3313331Y1255303D01*
X3314106Y1256553D01*
X3314261Y1257803D01*
X3313951Y1259261D01*
X3312866Y1260303D01*
X3311781Y1260720D01*
X3310386D01*
G01X3311781D02*
X3312711Y1261345D01*
X3313486Y1262386D01*
X3313796Y1263636D01*
X3313486Y1264886D01*
X3312711Y1265928D01*
X3311316Y1266553D01*
X3309921Y1266345D01*
X3308526Y1265511D01*
G01X3320151Y1259261D02*
X3321236Y1260720D01*
X3322166Y1261553D01*
X3323406Y1261970D01*
X3324491Y1261553D01*
X3325266Y1260720D01*
X3325886Y1259470D01*
X3326041Y1258011D01*
X3325886Y1256761D01*
X3325266Y1255511D01*
X3324336Y1254470D01*
X3323251Y1254053D01*
X3322011Y1254470D01*
X3320926Y1255719D01*
X3320306Y1257595D01*
X3320151Y1259678D01*
X3320461Y1262386D01*
X3320926Y1263845D01*
X3321701Y1265303D01*
X3322786Y1266345D01*
X3323871Y1266553D01*
X3324956Y1266136D01*
X3325731Y1265095D01*
G01X3294886Y1281553D02*
X3295816Y1280094D01*
X3297056Y1279261D01*
X3298451Y1279053D01*
X3299691Y1279261D01*
X3300931Y1280303D01*
X3301706Y1281553D01*
X3301861Y1282803D01*
X3301551Y1284261D01*
X3300466Y1285303D01*
X3299381Y1285720D01*
X3297986D01*
G01X3299381D02*
X3300311Y1286345D01*
X3301086Y1287386D01*
X3301396Y1288636D01*
X3301086Y1289886D01*
X3300311Y1290928D01*
X3298916Y1291553D01*
X3297521Y1291345D01*
X3296126Y1290511D01*
G01X3310696Y1279053D02*
X3311781Y1279261D01*
X3313021Y1279886D01*
X3313796Y1280928D01*
X3314106Y1282386D01*
X3313796Y1283844D01*
X3312866Y1285095D01*
X3311471Y1285720D01*
X3309921D01*
X3308991Y1286136D01*
X3308216Y1287178D01*
X3307906Y1288636D01*
X3308371Y1290095D01*
X3309456Y1291136D01*
X3310696Y1291553D01*
X3311936Y1291136D01*
X3313021Y1290095D01*
X3313486Y1288636D01*
X3313176Y1287178D01*
X3312401Y1286136D01*
X3311471Y1285720D01*
X3309921D01*
X3308526Y1285095D01*
X3307596Y1283844D01*
X3307286Y1282386D01*
X3307596Y1280928D01*
X3308371Y1279886D01*
X3309611Y1279261D01*
X3310696Y1279053D01*
G01X3324956D02*
Y1291553D01*
X3319221Y1282595D01*
X3326971D01*
G01X3295351Y1314470D02*
X3296281Y1315719D01*
X3297366Y1316345D01*
X3298606Y1316553D01*
X3300156Y1316136D01*
X3301241Y1315095D01*
X3301551Y1313845D01*
X3301396Y1312594D01*
X3300776Y1311553D01*
X3297676Y1309470D01*
X3296281Y1308011D01*
X3295351Y1305928D01*
X3295041Y1304053D01*
X3301551D01*
G01X3307286Y1305928D02*
X3308216Y1304886D01*
X3309301Y1304261D01*
X3310696Y1304053D01*
X3312091Y1304470D01*
X3313176Y1305303D01*
X3313951Y1306761D01*
X3314106Y1308428D01*
X3313796Y1310095D01*
X3313021Y1311136D01*
X3311936Y1311970D01*
X3310851Y1312178D01*
X3309766Y1311970D01*
X3308371Y1311136D01*
X3308836Y1316553D01*
X3313021D01*
G01X3320151Y1309261D02*
X3321236Y1310720D01*
X3322166Y1311553D01*
X3323406Y1311970D01*
X3324491Y1311553D01*
X3325266Y1310720D01*
X3325886Y1309470D01*
X3326041Y1308011D01*
X3325886Y1306761D01*
X3325266Y1305511D01*
X3324336Y1304470D01*
X3323251Y1304053D01*
X3322011Y1304470D01*
X3320926Y1305719D01*
X3320306Y1307595D01*
X3320151Y1309678D01*
X3320461Y1312386D01*
X3320926Y1313845D01*
X3321701Y1315303D01*
X3322786Y1316345D01*
X3323871Y1316553D01*
X3324956Y1316136D01*
X3325731Y1315095D01*
G01X3298296Y1329053D02*
X3297056Y1329261D01*
X3295971Y1330094D01*
X3295041Y1331345D01*
X3294421Y1332803D01*
X3294111Y1334470D01*
Y1336136D01*
X3294421Y1337803D01*
X3295041Y1339261D01*
X3295971Y1340511D01*
X3297056Y1341345D01*
X3298296Y1341553D01*
X3299536Y1341345D01*
X3300621Y1340511D01*
X3301551Y1339261D01*
X3302171Y1337803D01*
X3302481Y1336136D01*
Y1334470D01*
X3302171Y1332803D01*
X3301551Y1331345D01*
X3300621Y1330094D01*
X3299536Y1329261D01*
X3298296Y1329053D01*
G01X3299536Y1332386D02*
X3301396Y1329053D01*
G01X3310696Y1341553D02*
Y1329053D01*
G01X3307131Y1341553D02*
X3314261D01*
G01X3323096Y1329053D02*
Y1334678D01*
X3319996Y1341553D01*
G01X3326196D02*
X3323096Y1334678D01*
G01X3295351Y1614488D02*
X3296281Y1615737D01*
X3297366Y1616363D01*
X3298606Y1616571D01*
X3300156Y1616154D01*
X3301241Y1615113D01*
X3301551Y1613863D01*
X3301396Y1612612D01*
X3300776Y1611571D01*
X3297676Y1609488D01*
X3296281Y1608029D01*
X3295351Y1605946D01*
X3295041Y1604071D01*
X3301551D01*
G01X3307286Y1605946D02*
X3308216Y1604904D01*
X3309301Y1604279D01*
X3310696Y1604071D01*
X3312091Y1604488D01*
X3313176Y1605321D01*
X3313951Y1606779D01*
X3314106Y1608446D01*
X3313796Y1610113D01*
X3313021Y1611154D01*
X3311936Y1611988D01*
X3310851Y1612196D01*
X3309766Y1611988D01*
X3308371Y1611154D01*
X3308836Y1616571D01*
X3313021D01*
G01X3320151Y1609279D02*
X3321236Y1610738D01*
X3322166Y1611571D01*
X3323406Y1611988D01*
X3324491Y1611571D01*
X3325266Y1610738D01*
X3325886Y1609488D01*
X3326041Y1608029D01*
X3325886Y1606779D01*
X3325266Y1605529D01*
X3324336Y1604488D01*
X3323251Y1604071D01*
X3322011Y1604488D01*
X3320926Y1605737D01*
X3320306Y1607613D01*
X3320151Y1609696D01*
X3320461Y1612404D01*
X3320926Y1613863D01*
X3321701Y1615321D01*
X3322786Y1616363D01*
X3323871Y1616571D01*
X3324956Y1616154D01*
X3325731Y1615113D01*
G01X3295351Y1639488D02*
X3296281Y1640737D01*
X3297366Y1641363D01*
X3298606Y1641571D01*
X3300156Y1641154D01*
X3301241Y1640113D01*
X3301551Y1638863D01*
X3301396Y1637612D01*
X3300776Y1636571D01*
X3297676Y1634488D01*
X3296281Y1633029D01*
X3295351Y1630946D01*
X3295041Y1629071D01*
X3301551D01*
G01X3307751Y1634279D02*
X3308836Y1635738D01*
X3309766Y1636571D01*
X3311006Y1636988D01*
X3312091Y1636571D01*
X3312866Y1635738D01*
X3313486Y1634488D01*
X3313641Y1633029D01*
X3313486Y1631779D01*
X3312866Y1630529D01*
X3311936Y1629488D01*
X3310851Y1629071D01*
X3309611Y1629488D01*
X3308526Y1630737D01*
X3307906Y1632613D01*
X3307751Y1634696D01*
X3308061Y1637404D01*
X3308526Y1638863D01*
X3309301Y1640321D01*
X3310386Y1641363D01*
X3311471Y1641571D01*
X3312556Y1641154D01*
X3313331Y1640113D01*
G01X3323096Y1629071D02*
X3324181Y1629279D01*
X3325421Y1629904D01*
X3326196Y1630946D01*
X3326506Y1632404D01*
X3326196Y1633862D01*
X3325266Y1635113D01*
X3323871Y1635738D01*
X3322321D01*
X3321391Y1636154D01*
X3320616Y1637196D01*
X3320306Y1638654D01*
X3320771Y1640113D01*
X3321856Y1641154D01*
X3323096Y1641571D01*
X3324336Y1641154D01*
X3325421Y1640113D01*
X3325886Y1638654D01*
X3325576Y1637196D01*
X3324801Y1636154D01*
X3323871Y1635738D01*
X3322321D01*
X3320926Y1635113D01*
X3319996Y1633862D01*
X3319686Y1632404D01*
X3319996Y1630946D01*
X3320771Y1629904D01*
X3322011Y1629279D01*
X3323096Y1629071D01*
G01X3294886Y1655946D02*
X3295816Y1654904D01*
X3296901Y1654279D01*
X3298296Y1654071D01*
X3299691Y1654488D01*
X3300776Y1655321D01*
X3301551Y1656779D01*
X3301706Y1658446D01*
X3301396Y1660113D01*
X3300621Y1661154D01*
X3299536Y1661988D01*
X3298451Y1662196D01*
X3297366Y1661988D01*
X3295971Y1661154D01*
X3296436Y1666571D01*
X3300621D01*
G01X3310696Y1654071D02*
Y1666571D01*
X3308836Y1664071D01*
G01Y1654071D02*
X3312556D01*
G01X3320151Y1664488D02*
X3321081Y1665737D01*
X3322166Y1666363D01*
X3323406Y1666571D01*
X3324956Y1666154D01*
X3326041Y1665113D01*
X3326351Y1663863D01*
X3326196Y1662612D01*
X3325576Y1661571D01*
X3322476Y1659488D01*
X3321081Y1658029D01*
X3320151Y1655946D01*
X3319841Y1654071D01*
X3326351D01*
G01X3298296Y1679071D02*
X3297056Y1679279D01*
X3295971Y1680112D01*
X3295041Y1681363D01*
X3294421Y1682821D01*
X3294111Y1684488D01*
Y1686154D01*
X3294421Y1687821D01*
X3295041Y1689279D01*
X3295971Y1690529D01*
X3297056Y1691363D01*
X3298296Y1691571D01*
X3299536Y1691363D01*
X3300621Y1690529D01*
X3301551Y1689279D01*
X3302171Y1687821D01*
X3302481Y1686154D01*
Y1684488D01*
X3302171Y1682821D01*
X3301551Y1681363D01*
X3300621Y1680112D01*
X3299536Y1679279D01*
X3298296Y1679071D01*
G01X3299536Y1682404D02*
X3301396Y1679071D01*
G01X3310696Y1691571D02*
Y1679071D01*
G01X3307131Y1691571D02*
X3314261D01*
G01X3323096Y1679071D02*
Y1684696D01*
X3319996Y1691571D01*
G01X3326196D02*
X3323096Y1684696D01*
G01X3367968Y1000438D02*
Y987938D01*
G01X3364403Y1000438D02*
X3371533D01*
G01X3380368Y987938D02*
X3379128Y988146D01*
X3378043Y988979D01*
X3377113Y990230D01*
X3376493Y991688D01*
X3376183Y993355D01*
Y995021D01*
X3376493Y996688D01*
X3377113Y998146D01*
X3378043Y999396D01*
X3379128Y1000230D01*
X3380368Y1000438D01*
X3381608Y1000230D01*
X3382693Y999396D01*
X3383623Y998146D01*
X3384243Y996688D01*
X3384553Y995021D01*
Y993355D01*
X3384243Y991688D01*
X3383623Y990230D01*
X3382693Y988979D01*
X3381608Y988146D01*
X3380368Y987938D01*
G01X3389668Y1000438D02*
Y987938D01*
X3395868D01*
G01X3408268D02*
X3402068D01*
Y1000438D01*
X3408268D01*
G01X3405788Y994396D02*
X3402068D01*
G01X3414468Y987938D02*
Y1000438D01*
X3418343D01*
X3419583Y999813D01*
X3420358Y998980D01*
X3420668Y997313D01*
X3420358Y995646D01*
X3419428Y994605D01*
X3418343Y993980D01*
X3414468D01*
G01X3418343D02*
X3420668Y987938D01*
G01X3426093D02*
X3429968Y1000438D01*
X3433843Y987938D01*
G01X3432448Y992313D02*
X3427488D01*
G01X3438803Y987938D02*
Y1000438D01*
X3445933Y987938D01*
Y1000438D01*
G01X3458178Y999396D02*
X3457248Y1000021D01*
X3456163Y1000438D01*
X3454923D01*
X3453528Y999813D01*
X3452443Y998771D01*
X3451668Y997521D01*
X3451048Y995438D01*
X3450893Y993563D01*
X3451203Y991688D01*
X3451668Y990438D01*
X3452598Y989188D01*
X3453683Y988355D01*
X3454768Y987938D01*
X3455853D01*
X3456938Y988355D01*
X3457868Y988979D01*
X3458643Y989813D01*
G01X3470268Y987938D02*
X3464068D01*
Y1000438D01*
X3470268D01*
G01X3467788Y994396D02*
X3464068D01*
G01X3474918Y983771D02*
X3484218D01*
G01X3491968Y1000438D02*
Y987938D01*
G01X3488403Y1000438D02*
X3495533D01*
G01X3501268Y987938D02*
Y1000438D01*
X3505143D01*
X3506383Y999813D01*
X3507158Y998980D01*
X3507468Y997313D01*
X3507158Y995646D01*
X3506228Y994605D01*
X3505143Y993980D01*
X3501268D01*
G01X3505143D02*
X3507468Y987938D01*
G01X3512893D02*
X3516768Y1000438D01*
X3520643Y987938D01*
G01X3519248Y992313D02*
X3514288D01*
G01X3525293Y1000438D02*
X3529168Y987938D01*
X3533043Y1000438D01*
G01X3544668Y987938D02*
X3538468D01*
Y1000438D01*
X3544668D01*
G01X3542188Y994396D02*
X3538468D01*
G01X3550868Y1000438D02*
Y987938D01*
X3557068D01*
G01X3397263Y1680D02*
X3400983D01*
G01X3398968Y4388D02*
Y-1029D01*
G01X3411368Y-2487D02*
Y10013D01*
X3409508Y7513D01*
G01Y-2487D02*
X3413228D01*
G01X3423768Y-2904D02*
X3423458Y-2695D01*
Y-2279D01*
X3423768Y-2070D01*
X3424078Y-2279D01*
Y-2695D01*
X3423768Y-2904D01*
G01X3433533Y-1029D02*
X3434618Y-2070D01*
X3435858Y-2487D01*
X3437098Y-2070D01*
X3438183Y-821D01*
X3438958Y1055D01*
X3439268Y2930D01*
Y5221D01*
X3438958Y7096D01*
X3438183Y8763D01*
X3437253Y9596D01*
X3436168Y10013D01*
X3434928Y9596D01*
X3433998Y8763D01*
X3433378Y7513D01*
X3433068Y5846D01*
X3433378Y4388D01*
X3434153Y2930D01*
X3435083Y2096D01*
X3436168Y1888D01*
X3437408Y2304D01*
X3438338Y3346D01*
X3439268Y5221D01*
G01X3445623Y2721D02*
X3446708Y4180D01*
X3447638Y5013D01*
X3448878Y5430D01*
X3449963Y5013D01*
X3450738Y4180D01*
X3451358Y2930D01*
X3451513Y1471D01*
X3451358Y221D01*
X3450738Y-1029D01*
X3449808Y-2070D01*
X3448723Y-2487D01*
X3447483Y-2070D01*
X3446398Y-821D01*
X3445778Y1055D01*
X3445623Y3138D01*
X3445933Y5846D01*
X3446398Y7305D01*
X3447173Y8763D01*
X3448258Y9805D01*
X3449343Y10013D01*
X3450428Y9596D01*
X3451203Y8555D01*
G01X3458178Y-2904D02*
X3463758Y10013D01*
G01X3471353Y1680D02*
X3475383D01*
G01X3485768Y-2487D02*
Y10013D01*
X3483908Y7513D01*
G01Y-2487D02*
X3487628D01*
G01X3498168Y-2904D02*
X3497858Y-2695D01*
Y-2279D01*
X3498168Y-2070D01*
X3498478Y-2279D01*
Y-2695D01*
X3498168Y-2904D01*
G01X3507933Y-1029D02*
X3509018Y-2070D01*
X3510258Y-2487D01*
X3511498Y-2070D01*
X3512583Y-821D01*
X3513358Y1055D01*
X3513668Y2930D01*
Y5221D01*
X3513358Y7096D01*
X3512583Y8763D01*
X3511653Y9596D01*
X3510568Y10013D01*
X3509328Y9596D01*
X3508398Y8763D01*
X3507778Y7513D01*
X3507468Y5846D01*
X3507778Y4388D01*
X3508553Y2930D01*
X3509483Y2096D01*
X3510568Y1888D01*
X3511808Y2304D01*
X3512738Y3346D01*
X3513668Y5221D01*
G01X3520023Y2721D02*
X3521108Y4180D01*
X3522038Y5013D01*
X3523278Y5430D01*
X3524363Y5013D01*
X3525138Y4180D01*
X3525758Y2930D01*
X3525913Y1471D01*
X3525758Y221D01*
X3525138Y-1029D01*
X3524208Y-2070D01*
X3523123Y-2487D01*
X3521883Y-2070D01*
X3520798Y-821D01*
X3520178Y1055D01*
X3520023Y3138D01*
X3520333Y5846D01*
X3520798Y7305D01*
X3521573Y8763D01*
X3522658Y9805D01*
X3523743Y10013D01*
X3524828Y9596D01*
X3525603Y8555D01*
G01X3397263Y34830D02*
X3400983D01*
G01X3398968Y37538D02*
Y32121D01*
G01X3411368Y30663D02*
Y43163D01*
X3409508Y40663D01*
G01Y30663D02*
X3413228D01*
G01X3423768Y30246D02*
X3423458Y30455D01*
Y30871D01*
X3423768Y31080D01*
X3424078Y30871D01*
Y30455D01*
X3423768Y30246D01*
G01X3433533Y32121D02*
X3434618Y31080D01*
X3435858Y30663D01*
X3437098Y31080D01*
X3438183Y32329D01*
X3438958Y34205D01*
X3439268Y36080D01*
Y38371D01*
X3438958Y40246D01*
X3438183Y41913D01*
X3437253Y42746D01*
X3436168Y43163D01*
X3434928Y42746D01*
X3433998Y41913D01*
X3433378Y40663D01*
X3433068Y38996D01*
X3433378Y37538D01*
X3434153Y36080D01*
X3435083Y35246D01*
X3436168Y35038D01*
X3437408Y35454D01*
X3438338Y36496D01*
X3439268Y38371D01*
G01X3445623Y35871D02*
X3446708Y37330D01*
X3447638Y38163D01*
X3448878Y38580D01*
X3449963Y38163D01*
X3450738Y37330D01*
X3451358Y36080D01*
X3451513Y34621D01*
X3451358Y33371D01*
X3450738Y32121D01*
X3449808Y31080D01*
X3448723Y30663D01*
X3447483Y31080D01*
X3446398Y32329D01*
X3445778Y34205D01*
X3445623Y36288D01*
X3445933Y38996D01*
X3446398Y40455D01*
X3447173Y41913D01*
X3448258Y42955D01*
X3449343Y43163D01*
X3450428Y42746D01*
X3451203Y41705D01*
G01X3458178Y30246D02*
X3463758Y43163D01*
G01X3471353Y34830D02*
X3475383D01*
G01X3485768Y30663D02*
Y43163D01*
X3483908Y40663D01*
G01Y30663D02*
X3487628D01*
G01X3498168Y30246D02*
X3497858Y30455D01*
Y30871D01*
X3498168Y31080D01*
X3498478Y30871D01*
Y30455D01*
X3498168Y30246D01*
G01X3507933Y32121D02*
X3509018Y31080D01*
X3510258Y30663D01*
X3511498Y31080D01*
X3512583Y32329D01*
X3513358Y34205D01*
X3513668Y36080D01*
Y38371D01*
X3513358Y40246D01*
X3512583Y41913D01*
X3511653Y42746D01*
X3510568Y43163D01*
X3509328Y42746D01*
X3508398Y41913D01*
X3507778Y40663D01*
X3507468Y38996D01*
X3507778Y37538D01*
X3508553Y36080D01*
X3509483Y35246D01*
X3510568Y35038D01*
X3511808Y35454D01*
X3512738Y36496D01*
X3513668Y38371D01*
G01X3520023Y35871D02*
X3521108Y37330D01*
X3522038Y38163D01*
X3523278Y38580D01*
X3524363Y38163D01*
X3525138Y37330D01*
X3525758Y36080D01*
X3525913Y34621D01*
X3525758Y33371D01*
X3525138Y32121D01*
X3524208Y31080D01*
X3523123Y30663D01*
X3521883Y31080D01*
X3520798Y32329D01*
X3520178Y34205D01*
X3520023Y36288D01*
X3520333Y38996D01*
X3520798Y40455D01*
X3521573Y41913D01*
X3522658Y42955D01*
X3523743Y43163D01*
X3524828Y42746D01*
X3525603Y41705D01*
G01X3397263Y67980D02*
X3400983D01*
G01X3398968Y70688D02*
Y65271D01*
G01X3411368Y63813D02*
Y76313D01*
X3409508Y73813D01*
G01Y63813D02*
X3413228D01*
G01X3423768Y63396D02*
X3423458Y63605D01*
Y64021D01*
X3423768Y64230D01*
X3424078Y64021D01*
Y63605D01*
X3423768Y63396D01*
G01X3433533Y65271D02*
X3434618Y64230D01*
X3435858Y63813D01*
X3437098Y64230D01*
X3438183Y65479D01*
X3438958Y67355D01*
X3439268Y69230D01*
Y71521D01*
X3438958Y73396D01*
X3438183Y75063D01*
X3437253Y75896D01*
X3436168Y76313D01*
X3434928Y75896D01*
X3433998Y75063D01*
X3433378Y73813D01*
X3433068Y72146D01*
X3433378Y70688D01*
X3434153Y69230D01*
X3435083Y68396D01*
X3436168Y68188D01*
X3437408Y68604D01*
X3438338Y69646D01*
X3439268Y71521D01*
G01X3445623Y69021D02*
X3446708Y70480D01*
X3447638Y71313D01*
X3448878Y71730D01*
X3449963Y71313D01*
X3450738Y70480D01*
X3451358Y69230D01*
X3451513Y67771D01*
X3451358Y66521D01*
X3450738Y65271D01*
X3449808Y64230D01*
X3448723Y63813D01*
X3447483Y64230D01*
X3446398Y65479D01*
X3445778Y67355D01*
X3445623Y69438D01*
X3445933Y72146D01*
X3446398Y73605D01*
X3447173Y75063D01*
X3448258Y76105D01*
X3449343Y76313D01*
X3450428Y75896D01*
X3451203Y74855D01*
G01X3458178Y63396D02*
X3463758Y76313D01*
G01X3471353Y67980D02*
X3475383D01*
G01X3485768Y63813D02*
Y76313D01*
X3483908Y73813D01*
G01Y63813D02*
X3487628D01*
G01X3498168Y63396D02*
X3497858Y63605D01*
Y64021D01*
X3498168Y64230D01*
X3498478Y64021D01*
Y63605D01*
X3498168Y63396D01*
G01X3507933Y65271D02*
X3509018Y64230D01*
X3510258Y63813D01*
X3511498Y64230D01*
X3512583Y65479D01*
X3513358Y67355D01*
X3513668Y69230D01*
Y71521D01*
X3513358Y73396D01*
X3512583Y75063D01*
X3511653Y75896D01*
X3510568Y76313D01*
X3509328Y75896D01*
X3508398Y75063D01*
X3507778Y73813D01*
X3507468Y72146D01*
X3507778Y70688D01*
X3508553Y69230D01*
X3509483Y68396D01*
X3510568Y68188D01*
X3511808Y68604D01*
X3512738Y69646D01*
X3513668Y71521D01*
G01X3520023Y69021D02*
X3521108Y70480D01*
X3522038Y71313D01*
X3523278Y71730D01*
X3524363Y71313D01*
X3525138Y70480D01*
X3525758Y69230D01*
X3525913Y67771D01*
X3525758Y66521D01*
X3525138Y65271D01*
X3524208Y64230D01*
X3523123Y63813D01*
X3521883Y64230D01*
X3520798Y65479D01*
X3520178Y67355D01*
X3520023Y69438D01*
X3520333Y72146D01*
X3520798Y73605D01*
X3521573Y75063D01*
X3522658Y76105D01*
X3523743Y76313D01*
X3524828Y75896D01*
X3525603Y74855D01*
G01X3409663Y-31470D02*
X3413383D01*
G01X3411368Y-28762D02*
Y-34179D01*
G01X3420823Y-25220D02*
X3421753Y-23971D01*
X3422838Y-23345D01*
X3424078Y-23137D01*
X3425628Y-23554D01*
X3426713Y-24595D01*
X3427023Y-25845D01*
X3426868Y-27096D01*
X3426248Y-28137D01*
X3423148Y-30220D01*
X3421753Y-31679D01*
X3420823Y-33762D01*
X3420513Y-35637D01*
X3427023D01*
G01X3436168Y-36054D02*
X3435858Y-35845D01*
Y-35429D01*
X3436168Y-35220D01*
X3436478Y-35429D01*
Y-35845D01*
X3436168Y-36054D01*
G01X3448568Y-23137D02*
X3447328Y-23554D01*
X3446398Y-24595D01*
X3445778Y-25845D01*
X3445313Y-27512D01*
X3445158Y-29387D01*
X3445313Y-31262D01*
X3445778Y-32929D01*
X3446398Y-34179D01*
X3447328Y-35220D01*
X3448568Y-35637D01*
X3449808Y-35220D01*
X3450738Y-34179D01*
X3451358Y-32929D01*
X3451823Y-31262D01*
X3451978Y-29387D01*
X3451823Y-27512D01*
X3451358Y-25845D01*
X3450738Y-24595D01*
X3449808Y-23554D01*
X3448568Y-23137D01*
G01X3458178Y-36054D02*
X3463758Y-23137D01*
G01X3471353Y-31470D02*
X3475383D01*
G01X3482823Y-25220D02*
X3483753Y-23971D01*
X3484838Y-23345D01*
X3486078Y-23137D01*
X3487628Y-23554D01*
X3488713Y-24595D01*
X3489023Y-25845D01*
X3488868Y-27096D01*
X3488248Y-28137D01*
X3485148Y-30220D01*
X3483753Y-31679D01*
X3482823Y-33762D01*
X3482513Y-35637D01*
X3489023D01*
G01X3498168Y-36054D02*
X3497858Y-35845D01*
Y-35429D01*
X3498168Y-35220D01*
X3498478Y-35429D01*
Y-35845D01*
X3498168Y-36054D01*
G01X3510568Y-23137D02*
X3509328Y-23554D01*
X3508398Y-24595D01*
X3507778Y-25845D01*
X3507313Y-27512D01*
X3507158Y-29387D01*
X3507313Y-31262D01*
X3507778Y-32929D01*
X3508398Y-34179D01*
X3509328Y-35220D01*
X3510568Y-35637D01*
X3511808Y-35220D01*
X3512738Y-34179D01*
X3513358Y-32929D01*
X3513823Y-31262D01*
X3513978Y-29387D01*
X3513823Y-27512D01*
X3513358Y-25845D01*
X3512738Y-24595D01*
X3511808Y-23554D01*
X3510568Y-23137D01*
G01X3580525Y2259583D02*
X3581145Y2260208D01*
X3581610Y2261249D01*
X3581920Y2262708D01*
X3581610Y2263958D01*
X3580990Y2264791D01*
X3579905Y2265416D01*
X3575720D01*
Y2252916D01*
X3580835D01*
X3581920Y2253749D01*
X3582540Y2254999D01*
X3582850Y2256458D01*
X3582540Y2257916D01*
X3581610Y2259166D01*
X3580525Y2259583D01*
X3575720D01*
G01X3587810Y2252916D02*
X3591685Y2265416D01*
X3595560Y2252916D01*
G01X3594165Y2257291D02*
X3589205D01*
G01X3607495Y2264374D02*
X3606565Y2264999D01*
X3605480Y2265416D01*
X3604240D01*
X3602845Y2264791D01*
X3601760Y2263749D01*
X3600985Y2262499D01*
X3600365Y2260416D01*
X3600210Y2258541D01*
X3600520Y2256666D01*
X3600985Y2255416D01*
X3601915Y2254166D01*
X3603000Y2253333D01*
X3604085Y2252916D01*
X3605170D01*
X3606255Y2253333D01*
X3607185Y2253957D01*
X3607960Y2254791D01*
G01X3613075Y2252916D02*
Y2265416D01*
G01X3618965D02*
X3613075Y2257707D01*
G01X3619895Y2252916D02*
X3615710Y2261249D01*
G01X3625475Y2252916D02*
Y2265416D01*
X3628575D01*
X3629815Y2264791D01*
X3630745Y2263958D01*
X3631520Y2262708D01*
X3632140Y2261249D01*
X3632295Y2259166D01*
X3632140Y2257083D01*
X3631520Y2255624D01*
X3630745Y2254374D01*
X3629815Y2253541D01*
X3628575Y2252916D01*
X3625475D01*
G01X3638185D02*
Y2265416D01*
X3642060D01*
X3643300Y2264791D01*
X3644075Y2263958D01*
X3644385Y2262291D01*
X3644075Y2260624D01*
X3643145Y2259583D01*
X3642060Y2258958D01*
X3638185D01*
G01X3642060D02*
X3644385Y2252916D01*
G01X3651825Y2265416D02*
X3655545D01*
G01X3653685D02*
Y2252916D01*
G01X3651825D02*
X3655545D01*
G01X3662985Y2265416D02*
Y2252916D01*
X3669185D01*
G01X3675385Y2265416D02*
Y2252916D01*
X3681585D01*
G01X3700030Y2254582D02*
X3701270Y2253541D01*
X3702665Y2252916D01*
X3703905D01*
X3705145Y2253541D01*
X3706075Y2254582D01*
X3706540Y2256041D01*
X3706230Y2257499D01*
X3705455Y2258749D01*
X3704060Y2259583D01*
X3702200Y2259999D01*
X3701115Y2260833D01*
X3700650Y2262291D01*
X3700960Y2263749D01*
X3701735Y2264791D01*
X3702820Y2265416D01*
X3703905D01*
X3704990Y2264999D01*
X3705920Y2263958D01*
G01X3715685Y2265416D02*
Y2252916D01*
G01X3712120Y2265416D02*
X3719250D01*
G01X3724675D02*
Y2256458D01*
X3725295Y2254582D01*
X3726535Y2253333D01*
X3728085Y2252916D01*
X3729635Y2253333D01*
X3730875Y2254582D01*
X3731495Y2256458D01*
Y2265416D01*
G01X3741725Y2259583D02*
X3742345Y2260208D01*
X3742810Y2261249D01*
X3743120Y2262708D01*
X3742810Y2263958D01*
X3742190Y2264791D01*
X3741105Y2265416D01*
X3736920D01*
Y2252916D01*
X3742035D01*
X3743120Y2253749D01*
X3743740Y2254999D01*
X3744050Y2256458D01*
X3743740Y2257916D01*
X3742810Y2259166D01*
X3741725Y2259583D01*
X3736920D01*
G01X3762185Y2265416D02*
Y2252916D01*
X3768385D01*
G01X3780785D02*
X3774585D01*
Y2265416D01*
X3780785D01*
G01X3778305Y2259374D02*
X3774585D01*
G01X3786520Y2252916D02*
Y2265416D01*
X3793650Y2252916D01*
Y2265416D01*
G01X3803415Y2259166D02*
X3806515D01*
Y2255416D01*
X3805585Y2254166D01*
X3804500Y2253333D01*
X3802950Y2252916D01*
X3801400Y2253333D01*
X3800315Y2254166D01*
X3799385Y2255416D01*
X3798765Y2256874D01*
X3798455Y2258541D01*
Y2259999D01*
X3798765Y2261249D01*
X3799385Y2262708D01*
X3800315Y2263958D01*
X3801245Y2264791D01*
X3802485Y2265416D01*
X3803570D01*
X3804810Y2264999D01*
X3805740Y2264166D01*
G01X3814885Y2265416D02*
Y2252916D01*
G01X3811320Y2265416D02*
X3818450D01*
G01X3824030Y2252916D02*
Y2265416D01*
G01X3830540D02*
Y2252916D01*
G01Y2259166D02*
X3824030D01*
G01X3852085Y2265416D02*
Y2252916D01*
G01X3848520Y2265416D02*
X3855650D01*
G01X3864485Y2252916D02*
X3863245Y2253124D01*
X3862160Y2253957D01*
X3861230Y2255208D01*
X3860610Y2256666D01*
X3860300Y2258333D01*
Y2259999D01*
X3860610Y2261666D01*
X3861230Y2263124D01*
X3862160Y2264374D01*
X3863245Y2265208D01*
X3864485Y2265416D01*
X3865725Y2265208D01*
X3866810Y2264374D01*
X3867740Y2263124D01*
X3868360Y2261666D01*
X3868670Y2259999D01*
Y2258333D01*
X3868360Y2256666D01*
X3867740Y2255208D01*
X3866810Y2253957D01*
X3865725Y2253124D01*
X3864485Y2252916D01*
G01X3873785Y2265416D02*
Y2252916D01*
X3879985D01*
G01X3892385D02*
X3886185D01*
Y2265416D01*
X3892385D01*
G01X3889905Y2259374D02*
X3886185D01*
G01X3898585Y2252916D02*
Y2265416D01*
X3902460D01*
X3903700Y2264791D01*
X3904475Y2263958D01*
X3904785Y2262291D01*
X3904475Y2260624D01*
X3903545Y2259583D01*
X3902460Y2258958D01*
X3898585D01*
G01X3902460D02*
X3904785Y2252916D01*
G01X3910210D02*
X3914085Y2265416D01*
X3917960Y2252916D01*
G01X3916565Y2257291D02*
X3911605D01*
G01X3922920Y2252916D02*
Y2265416D01*
X3930050Y2252916D01*
Y2265416D01*
G01X3942295Y2264374D02*
X3941365Y2264999D01*
X3940280Y2265416D01*
X3939040D01*
X3937645Y2264791D01*
X3936560Y2263749D01*
X3935785Y2262499D01*
X3935165Y2260416D01*
X3935010Y2258541D01*
X3935320Y2256666D01*
X3935785Y2255416D01*
X3936715Y2254166D01*
X3937800Y2253333D01*
X3938885Y2252916D01*
X3939970D01*
X3941055Y2253333D01*
X3941985Y2253957D01*
X3942760Y2254791D01*
G01X3954385Y2252916D02*
X3948185D01*
Y2265416D01*
X3954385D01*
G01X3951905Y2259374D02*
X3948185D01*
G01X3976085Y2265416D02*
Y2252916D01*
G01X3972520Y2265416D02*
X3979650D01*
G01X3988485Y2252916D02*
X3987245Y2253124D01*
X3986160Y2253957D01*
X3985230Y2255208D01*
X3984610Y2256666D01*
X3984300Y2258333D01*
Y2259999D01*
X3984610Y2261666D01*
X3985230Y2263124D01*
X3986160Y2264374D01*
X3987245Y2265208D01*
X3988485Y2265416D01*
X3989725Y2265208D01*
X3990810Y2264374D01*
X3991740Y2263124D01*
X3992360Y2261666D01*
X3992670Y2259999D01*
Y2258333D01*
X3992360Y2256666D01*
X3991740Y2255208D01*
X3990810Y2253957D01*
X3989725Y2253124D01*
X3988485Y2252916D01*
G01X4014525Y2259583D02*
X4015145Y2260208D01*
X4015610Y2261249D01*
X4015920Y2262708D01*
X4015610Y2263958D01*
X4014990Y2264791D01*
X4013905Y2265416D01*
X4009720D01*
Y2252916D01*
X4014835D01*
X4015920Y2253749D01*
X4016540Y2254999D01*
X4016850Y2256458D01*
X4016540Y2257916D01*
X4015610Y2259166D01*
X4014525Y2259583D01*
X4009720D01*
G01X4028785Y2252916D02*
X4022585D01*
Y2265416D01*
X4028785D01*
G01X4026305Y2259374D02*
X4022585D01*
G01X4050175Y2252916D02*
X4050485Y2255624D01*
X4050950Y2257916D01*
X4051570Y2259999D01*
X4052345Y2262291D01*
X4053585Y2265416D01*
X4047385D01*
G01X4073580Y2257083D02*
X4077300D01*
G01X4075285Y2259791D02*
Y2254374D01*
G01X4084895Y2252499D02*
X4090475Y2265416D01*
G01X4098070Y2257083D02*
X4102100D01*
G01X4109075Y2254791D02*
X4110005Y2253749D01*
X4111090Y2253124D01*
X4112485Y2252916D01*
X4113880Y2253333D01*
X4114965Y2254166D01*
X4115740Y2255624D01*
X4115895Y2257291D01*
X4115585Y2258958D01*
X4114810Y2259999D01*
X4113725Y2260833D01*
X4112640Y2261041D01*
X4111555Y2260833D01*
X4110160Y2259999D01*
X4110625Y2265416D01*
X4114810D01*
G01X4133255Y2252916D02*
Y2265416D01*
X4137285Y2254999D01*
X4141315Y2265416D01*
Y2252916D01*
G01X4147825Y2265416D02*
X4151545D01*
G01X4149685D02*
Y2252916D01*
G01X4147825D02*
X4151545D01*
G01X4158985Y2265416D02*
Y2252916D01*
X4165185D01*
G01X4171230Y2254582D02*
X4172470Y2253541D01*
X4173865Y2252916D01*
X4175105D01*
X4176345Y2253541D01*
X4177275Y2254582D01*
X4177740Y2256041D01*
X4177430Y2257499D01*
X4176655Y2258749D01*
X4175260Y2259583D01*
X4173400Y2259999D01*
X4172315Y2260833D01*
X4171850Y2262291D01*
X4172160Y2263749D01*
X4172935Y2264791D01*
X4174020Y2265416D01*
X4175105D01*
X4176190Y2264999D01*
X4177120Y2263958D01*
G01X3416070Y2275833D02*
X3420100D01*
G01X3438855Y2271666D02*
Y2284166D01*
X3442885Y2273749D01*
X3446915Y2284166D01*
Y2271666D01*
G01X3452340D02*
Y2284166D01*
X3458230D01*
G01X3456060Y2278124D02*
X3452340D01*
G01X3468615Y2277916D02*
X3471715D01*
Y2274166D01*
X3470785Y2272916D01*
X3469700Y2272083D01*
X3468150Y2271666D01*
X3466600Y2272083D01*
X3465515Y2272916D01*
X3464585Y2274166D01*
X3463965Y2275624D01*
X3463655Y2277291D01*
Y2278749D01*
X3463965Y2279999D01*
X3464585Y2281458D01*
X3465515Y2282708D01*
X3466445Y2283541D01*
X3467685Y2284166D01*
X3468770D01*
X3470010Y2283749D01*
X3470940Y2282916D01*
G01X3475435Y2267499D02*
X3484735D01*
G01X3489230Y2273332D02*
X3490470Y2272291D01*
X3491865Y2271666D01*
X3493105D01*
X3494345Y2272291D01*
X3495275Y2273332D01*
X3495740Y2274791D01*
X3495430Y2276249D01*
X3494655Y2277499D01*
X3493260Y2278333D01*
X3491400Y2278749D01*
X3490315Y2279583D01*
X3489850Y2281041D01*
X3490160Y2282499D01*
X3490935Y2283541D01*
X3492020Y2284166D01*
X3493105D01*
X3494190Y2283749D01*
X3495120Y2282708D01*
G01X3504885Y2284166D02*
Y2271666D01*
G01X3501320Y2284166D02*
X3508450D01*
G01X3513875D02*
Y2275208D01*
X3514495Y2273332D01*
X3515735Y2272083D01*
X3517285Y2271666D01*
X3518835Y2272083D01*
X3520075Y2273332D01*
X3520695Y2275208D01*
Y2284166D01*
G01X3530925Y2278333D02*
X3531545Y2278958D01*
X3532010Y2279999D01*
X3532320Y2281458D01*
X3532010Y2282708D01*
X3531390Y2283541D01*
X3530305Y2284166D01*
X3526120D01*
Y2271666D01*
X3531235D01*
X3532320Y2272499D01*
X3532940Y2273749D01*
X3533250Y2275208D01*
X3532940Y2276666D01*
X3532010Y2277916D01*
X3530925Y2278333D01*
X3526120D01*
G01X3554485Y2271249D02*
X3554175Y2271458D01*
Y2271874D01*
X3554485Y2272083D01*
X3554795Y2271874D01*
Y2271458D01*
X3554485Y2271249D01*
G01Y2276874D02*
X3554175Y2277083D01*
Y2277499D01*
X3554485Y2277708D01*
X3554795Y2277499D01*
Y2277083D01*
X3554485Y2276874D01*
G01X3575255Y2271666D02*
Y2284166D01*
X3579285Y2273749D01*
X3583315Y2284166D01*
Y2271666D01*
G01X3587810D02*
X3591685Y2284166D01*
X3595560Y2271666D01*
G01X3594165Y2276041D02*
X3589205D01*
G01X3600520Y2271666D02*
Y2284166D01*
X3607650Y2271666D01*
Y2284166D01*
G01X3613075D02*
Y2275208D01*
X3613695Y2273332D01*
X3614935Y2272083D01*
X3616485Y2271666D01*
X3618035Y2272083D01*
X3619275Y2273332D01*
X3619895Y2275208D01*
Y2284166D01*
G01X3625940Y2271666D02*
Y2284166D01*
X3631830D01*
G01X3629660Y2278124D02*
X3625940D01*
G01X3637410Y2271666D02*
X3641285Y2284166D01*
X3645160Y2271666D01*
G01X3643765Y2276041D02*
X3638805D01*
G01X3657095Y2283124D02*
X3656165Y2283749D01*
X3655080Y2284166D01*
X3653840D01*
X3652445Y2283541D01*
X3651360Y2282499D01*
X3650585Y2281249D01*
X3649965Y2279166D01*
X3649810Y2277291D01*
X3650120Y2275416D01*
X3650585Y2274166D01*
X3651515Y2272916D01*
X3652600Y2272083D01*
X3653685Y2271666D01*
X3654770D01*
X3655855Y2272083D01*
X3656785Y2272707D01*
X3657560Y2273541D01*
G01X3666085Y2284166D02*
Y2271666D01*
G01X3662520Y2284166D02*
X3669650D01*
G01X3675075D02*
Y2275208D01*
X3675695Y2273332D01*
X3676935Y2272083D01*
X3678485Y2271666D01*
X3680035Y2272083D01*
X3681275Y2273332D01*
X3681895Y2275208D01*
Y2284166D01*
G01X3687785Y2271666D02*
Y2284166D01*
X3691660D01*
X3692900Y2283541D01*
X3693675Y2282708D01*
X3693985Y2281041D01*
X3693675Y2279374D01*
X3692745Y2278333D01*
X3691660Y2277708D01*
X3687785D01*
G01X3691660D02*
X3693985Y2271666D01*
G01X3701425Y2284166D02*
X3705145D01*
G01X3703285D02*
Y2271666D01*
G01X3701425D02*
X3705145D01*
G01X3712120D02*
Y2284166D01*
X3719250Y2271666D01*
Y2284166D01*
G01X3729015Y2277916D02*
X3732115D01*
Y2274166D01*
X3731185Y2272916D01*
X3730100Y2272083D01*
X3728550Y2271666D01*
X3727000Y2272083D01*
X3725915Y2272916D01*
X3724985Y2274166D01*
X3724365Y2275624D01*
X3724055Y2277291D01*
Y2278749D01*
X3724365Y2279999D01*
X3724985Y2281458D01*
X3725915Y2282708D01*
X3726845Y2283541D01*
X3728085Y2284166D01*
X3729170D01*
X3730410Y2283749D01*
X3731340Y2282916D01*
G01X3749630Y2273332D02*
X3750870Y2272291D01*
X3752265Y2271666D01*
X3753505D01*
X3754745Y2272291D01*
X3755675Y2273332D01*
X3756140Y2274791D01*
X3755830Y2276249D01*
X3755055Y2277499D01*
X3753660Y2278333D01*
X3751800Y2278749D01*
X3750715Y2279583D01*
X3750250Y2281041D01*
X3750560Y2282499D01*
X3751335Y2283541D01*
X3752420Y2284166D01*
X3753505D01*
X3754590Y2283749D01*
X3755520Y2282708D01*
G01X3765285Y2284166D02*
Y2271666D01*
G01X3761720Y2284166D02*
X3768850D01*
G01X3774275D02*
Y2275208D01*
X3774895Y2273332D01*
X3776135Y2272083D01*
X3777685Y2271666D01*
X3779235Y2272083D01*
X3780475Y2273332D01*
X3781095Y2275208D01*
Y2284166D01*
G01X3791325Y2278333D02*
X3791945Y2278958D01*
X3792410Y2279999D01*
X3792720Y2281458D01*
X3792410Y2282708D01*
X3791790Y2283541D01*
X3790705Y2284166D01*
X3786520D01*
Y2271666D01*
X3791635D01*
X3792720Y2272499D01*
X3793340Y2273749D01*
X3793650Y2275208D01*
X3793340Y2276666D01*
X3792410Y2277916D01*
X3791325Y2278333D01*
X3786520D01*
G01X3811785Y2284166D02*
Y2271666D01*
X3817985D01*
G01X3830385D02*
X3824185D01*
Y2284166D01*
X3830385D01*
G01X3827905Y2278124D02*
X3824185D01*
G01X3836120Y2271666D02*
Y2284166D01*
X3843250Y2271666D01*
Y2284166D01*
G01X3853015Y2277916D02*
X3856115D01*
Y2274166D01*
X3855185Y2272916D01*
X3854100Y2272083D01*
X3852550Y2271666D01*
X3851000Y2272083D01*
X3849915Y2272916D01*
X3848985Y2274166D01*
X3848365Y2275624D01*
X3848055Y2277291D01*
Y2278749D01*
X3848365Y2279999D01*
X3848985Y2281458D01*
X3849915Y2282708D01*
X3850845Y2283541D01*
X3852085Y2284166D01*
X3853170D01*
X3854410Y2283749D01*
X3855340Y2282916D01*
G01X3864485Y2284166D02*
Y2271666D01*
G01X3860920Y2284166D02*
X3868050D01*
G01X3873630Y2271666D02*
Y2284166D01*
G01X3880140D02*
Y2271666D01*
G01Y2277916D02*
X3873630D01*
G01X3576030Y2292082D02*
X3577270Y2291041D01*
X3578665Y2290416D01*
X3579905D01*
X3581145Y2291041D01*
X3582075Y2292082D01*
X3582540Y2293541D01*
X3582230Y2294999D01*
X3581455Y2296249D01*
X3580060Y2297083D01*
X3578200Y2297499D01*
X3577115Y2298333D01*
X3576650Y2299791D01*
X3576960Y2301249D01*
X3577735Y2302291D01*
X3578820Y2302916D01*
X3579905D01*
X3580990Y2302499D01*
X3581920Y2301458D01*
G01X3588275Y2302916D02*
Y2293958D01*
X3588895Y2292082D01*
X3590135Y2290833D01*
X3591685Y2290416D01*
X3593235Y2290833D01*
X3594475Y2292082D01*
X3595095Y2293958D01*
Y2302916D01*
G01X3600985Y2290416D02*
Y2302916D01*
X3604860D01*
X3606100Y2302291D01*
X3606875Y2301458D01*
X3607185Y2299791D01*
X3606875Y2298124D01*
X3605945Y2297083D01*
X3604860Y2296458D01*
X3600985D01*
G01X3604860D02*
X3607185Y2290416D01*
G01X3613540D02*
Y2302916D01*
X3619430D01*
G01X3617260Y2296874D02*
X3613540D01*
G01X3625010Y2290416D02*
X3628885Y2302916D01*
X3632760Y2290416D01*
G01X3631365Y2294791D02*
X3626405D01*
G01X3644695Y2301874D02*
X3643765Y2302499D01*
X3642680Y2302916D01*
X3641440D01*
X3640045Y2302291D01*
X3638960Y2301249D01*
X3638185Y2299999D01*
X3637565Y2297916D01*
X3637410Y2296041D01*
X3637720Y2294166D01*
X3638185Y2292916D01*
X3639115Y2291666D01*
X3640200Y2290833D01*
X3641285Y2290416D01*
X3642370D01*
X3643455Y2290833D01*
X3644385Y2291457D01*
X3645160Y2292291D01*
G01X3656785Y2290416D02*
X3650585D01*
Y2302916D01*
X3656785D01*
G01X3654305Y2296874D02*
X3650585D01*
G01X3678485Y2290416D02*
X3677245Y2290624D01*
X3676160Y2291457D01*
X3675230Y2292708D01*
X3674610Y2294166D01*
X3674300Y2295833D01*
Y2297499D01*
X3674610Y2299166D01*
X3675230Y2300624D01*
X3676160Y2301874D01*
X3677245Y2302708D01*
X3678485Y2302916D01*
X3679725Y2302708D01*
X3680810Y2301874D01*
X3681740Y2300624D01*
X3682360Y2299166D01*
X3682670Y2297499D01*
Y2295833D01*
X3682360Y2294166D01*
X3681740Y2292708D01*
X3680810Y2291457D01*
X3679725Y2290624D01*
X3678485Y2290416D01*
G01X3687940D02*
Y2302916D01*
X3693830D01*
G01X3691660Y2296874D02*
X3687940D01*
G01X3711655Y2290416D02*
Y2302916D01*
X3715685Y2292499D01*
X3719715Y2302916D01*
Y2290416D01*
G01X3724675Y2302916D02*
Y2293958D01*
X3725295Y2292082D01*
X3726535Y2290833D01*
X3728085Y2290416D01*
X3729635Y2290833D01*
X3730875Y2292082D01*
X3731495Y2293958D01*
Y2302916D01*
G01X3737230Y2292082D02*
X3738470Y2291041D01*
X3739865Y2290416D01*
X3741105D01*
X3742345Y2291041D01*
X3743275Y2292082D01*
X3743740Y2293541D01*
X3743430Y2294999D01*
X3742655Y2296249D01*
X3741260Y2297083D01*
X3739400Y2297499D01*
X3738315Y2298333D01*
X3737850Y2299791D01*
X3738160Y2301249D01*
X3738935Y2302291D01*
X3740020Y2302916D01*
X3741105D01*
X3742190Y2302499D01*
X3743120Y2301458D01*
G01X3752885Y2302916D02*
Y2290416D01*
G01X3749320Y2302916D02*
X3756450D01*
G01X3763270Y2294583D02*
X3767300D01*
G01X3774120Y2290416D02*
Y2302916D01*
X3781250Y2290416D01*
Y2302916D01*
G01X3790085Y2290416D02*
X3788845Y2290624D01*
X3787760Y2291457D01*
X3786830Y2292708D01*
X3786210Y2294166D01*
X3785900Y2295833D01*
Y2297499D01*
X3786210Y2299166D01*
X3786830Y2300624D01*
X3787760Y2301874D01*
X3788845Y2302708D01*
X3790085Y2302916D01*
X3791325Y2302708D01*
X3792410Y2301874D01*
X3793340Y2300624D01*
X3793960Y2299166D01*
X3794270Y2297499D01*
Y2295833D01*
X3793960Y2294166D01*
X3793340Y2292708D01*
X3792410Y2291457D01*
X3791325Y2290624D01*
X3790085Y2290416D01*
G01X3802485Y2302916D02*
Y2290416D01*
G01X3798920Y2302916D02*
X3806050D01*
G01X3812870Y2294583D02*
X3816900D01*
G01X3830695Y2301874D02*
X3829765Y2302499D01*
X3828680Y2302916D01*
X3827440D01*
X3826045Y2302291D01*
X3824960Y2301249D01*
X3824185Y2299999D01*
X3823565Y2297916D01*
X3823410Y2296041D01*
X3823720Y2294166D01*
X3824185Y2292916D01*
X3825115Y2291666D01*
X3826200Y2290833D01*
X3827285Y2290416D01*
X3828370D01*
X3829455Y2290833D01*
X3830385Y2291457D01*
X3831160Y2292291D01*
G01X3836275Y2302916D02*
Y2293958D01*
X3836895Y2292082D01*
X3838135Y2290833D01*
X3839685Y2290416D01*
X3841235Y2290833D01*
X3842475Y2292082D01*
X3843095Y2293958D01*
Y2302916D01*
G01X3852085D02*
Y2290416D01*
G01X3848520Y2302916D02*
X3855650D01*
G01X3862470Y2294583D02*
X3866500D01*
G01X3873785Y2302916D02*
Y2290416D01*
X3879985D01*
G01X3885410D02*
X3889285Y2302916D01*
X3893160Y2290416D01*
G01X3891765Y2294791D02*
X3886805D01*
G01X3901685Y2290416D02*
Y2296041D01*
X3898585Y2302916D01*
G01X3904785D02*
X3901685Y2296041D01*
G01X3917185Y2290416D02*
X3910985D01*
Y2302916D01*
X3917185D01*
G01X3914705Y2296874D02*
X3910985D01*
G01X3923385Y2290416D02*
Y2302916D01*
X3927260D01*
X3928500Y2302291D01*
X3929275Y2301458D01*
X3929585Y2299791D01*
X3929275Y2298124D01*
X3928345Y2297083D01*
X3927260Y2296458D01*
X3923385D01*
G01X3927260D02*
X3929585Y2290416D01*
G01X3416070Y2313333D02*
X3420100D01*
G01X3438855Y2309166D02*
Y2321666D01*
X3442885Y2311249D01*
X3446915Y2321666D01*
Y2309166D01*
G01X3451410D02*
X3455285Y2321666D01*
X3459160Y2309166D01*
G01X3457765Y2313541D02*
X3452805D01*
G01X3464430Y2309166D02*
X3470940Y2321666D01*
G01X3464430D02*
X3470940Y2309166D01*
G01X3475435Y2304999D02*
X3484735D01*
G01X3489075Y2309166D02*
Y2321666D01*
X3492175D01*
X3493415Y2321041D01*
X3494345Y2320208D01*
X3495120Y2318958D01*
X3495740Y2317499D01*
X3495895Y2315416D01*
X3495740Y2313333D01*
X3495120Y2311874D01*
X3494345Y2310624D01*
X3493415Y2309791D01*
X3492175Y2309166D01*
X3489075D01*
G01X3507985D02*
X3501785D01*
Y2321666D01*
X3507985D01*
G01X3505505Y2315624D02*
X3501785D01*
G01X3514185Y2309166D02*
Y2321666D01*
X3517905D01*
X3519145Y2321041D01*
X3520075Y2319583D01*
X3520385Y2317916D01*
X3520075Y2316249D01*
X3519300Y2314999D01*
X3517905Y2314374D01*
X3514185D01*
G01X3529685Y2321666D02*
Y2309166D01*
G01X3526120Y2321666D02*
X3533250D01*
G01X3538830Y2309166D02*
Y2321666D01*
G01X3545340D02*
Y2309166D01*
G01Y2315416D02*
X3538830D01*
G01X3554485Y2308749D02*
X3554175Y2308958D01*
Y2309374D01*
X3554485Y2309583D01*
X3554795Y2309374D01*
Y2308958D01*
X3554485Y2308749D01*
G01Y2314374D02*
X3554175Y2314583D01*
Y2314999D01*
X3554485Y2315208D01*
X3554795Y2314999D01*
Y2314583D01*
X3554485Y2314374D01*
G01X3575875Y2309166D02*
Y2321666D01*
X3578975D01*
X3580215Y2321041D01*
X3581145Y2320208D01*
X3581920Y2318958D01*
X3582540Y2317499D01*
X3582695Y2315416D01*
X3582540Y2313333D01*
X3581920Y2311874D01*
X3581145Y2310624D01*
X3580215Y2309791D01*
X3578975Y2309166D01*
X3575875D01*
G01X3594785D02*
X3588585D01*
Y2321666D01*
X3594785D01*
G01X3592305Y2315624D02*
X3588585D01*
G01X3600985Y2309166D02*
Y2321666D01*
X3604705D01*
X3605945Y2321041D01*
X3606875Y2319583D01*
X3607185Y2317916D01*
X3606875Y2316249D01*
X3606100Y2314999D01*
X3604705Y2314374D01*
X3600985D01*
G01X3616485Y2321666D02*
Y2309166D01*
G01X3612920Y2321666D02*
X3620050D01*
G01X3625630Y2309166D02*
Y2321666D01*
G01X3632140D02*
Y2309166D01*
G01Y2315416D02*
X3625630D01*
G01X3650740Y2309166D02*
Y2321666D01*
X3656630D01*
G01X3654460Y2315624D02*
X3650740D01*
G01X3662985Y2309166D02*
Y2321666D01*
X3666860D01*
X3668100Y2321041D01*
X3668875Y2320208D01*
X3669185Y2318541D01*
X3668875Y2316874D01*
X3667945Y2315833D01*
X3666860Y2315208D01*
X3662985D01*
G01X3666860D02*
X3669185Y2309166D01*
G01X3678485D02*
X3677245Y2309374D01*
X3676160Y2310207D01*
X3675230Y2311458D01*
X3674610Y2312916D01*
X3674300Y2314583D01*
Y2316249D01*
X3674610Y2317916D01*
X3675230Y2319374D01*
X3676160Y2320624D01*
X3677245Y2321458D01*
X3678485Y2321666D01*
X3679725Y2321458D01*
X3680810Y2320624D01*
X3681740Y2319374D01*
X3682360Y2317916D01*
X3682670Y2316249D01*
Y2314583D01*
X3682360Y2312916D01*
X3681740Y2311458D01*
X3680810Y2310207D01*
X3679725Y2309374D01*
X3678485Y2309166D01*
G01X3686855D02*
Y2321666D01*
X3690885Y2311249D01*
X3694915Y2321666D01*
Y2309166D01*
G01X3712430Y2310832D02*
X3713670Y2309791D01*
X3715065Y2309166D01*
X3716305D01*
X3717545Y2309791D01*
X3718475Y2310832D01*
X3718940Y2312291D01*
X3718630Y2313749D01*
X3717855Y2314999D01*
X3716460Y2315833D01*
X3714600Y2316249D01*
X3713515Y2317083D01*
X3713050Y2318541D01*
X3713360Y2319999D01*
X3714135Y2321041D01*
X3715220Y2321666D01*
X3716305D01*
X3717390Y2321249D01*
X3718320Y2320208D01*
G01X3728085Y2321666D02*
Y2309166D01*
G01X3724520Y2321666D02*
X3731650D01*
G01X3736610Y2309166D02*
X3740485Y2321666D01*
X3744360Y2309166D01*
G01X3742965Y2313541D02*
X3738005D01*
G01X3749785Y2309166D02*
Y2321666D01*
X3753660D01*
X3754900Y2321041D01*
X3755675Y2320208D01*
X3755985Y2318541D01*
X3755675Y2316874D01*
X3754745Y2315833D01*
X3753660Y2315208D01*
X3749785D01*
G01X3753660D02*
X3755985Y2309166D01*
G01X3765285Y2321666D02*
Y2309166D01*
G01X3761720Y2321666D02*
X3768850D01*
G01X3786985D02*
Y2309166D01*
X3793185D01*
G01X3798610D02*
X3802485Y2321666D01*
X3806360Y2309166D01*
G01X3804965Y2313541D02*
X3800005D01*
G01X3814885Y2309166D02*
Y2314791D01*
X3811785Y2321666D01*
G01X3817985D02*
X3814885Y2314791D01*
G01X3830385Y2309166D02*
X3824185D01*
Y2321666D01*
X3830385D01*
G01X3827905Y2315624D02*
X3824185D01*
G01X3836585Y2309166D02*
Y2321666D01*
X3840460D01*
X3841700Y2321041D01*
X3842475Y2320208D01*
X3842785Y2318541D01*
X3842475Y2316874D01*
X3841545Y2315833D01*
X3840460Y2315208D01*
X3836585D01*
G01X3840460D02*
X3842785Y2309166D01*
G01X3864485Y2321666D02*
Y2309166D01*
G01X3860920Y2321666D02*
X3868050D01*
G01X3876885Y2309166D02*
X3875645Y2309374D01*
X3874560Y2310207D01*
X3873630Y2311458D01*
X3873010Y2312916D01*
X3872700Y2314583D01*
Y2316249D01*
X3873010Y2317916D01*
X3873630Y2319374D01*
X3874560Y2320624D01*
X3875645Y2321458D01*
X3876885Y2321666D01*
X3878125Y2321458D01*
X3879210Y2320624D01*
X3880140Y2319374D01*
X3880760Y2317916D01*
X3881070Y2316249D01*
Y2314583D01*
X3880760Y2312916D01*
X3880140Y2311458D01*
X3879210Y2310207D01*
X3878125Y2309374D01*
X3876885Y2309166D01*
G01X3901685Y2321666D02*
Y2309166D01*
G01X3898120Y2321666D02*
X3905250D01*
G01X3910830Y2309166D02*
Y2321666D01*
G01X3917340D02*
Y2309166D01*
G01Y2315416D02*
X3910830D01*
G01X3929585Y2309166D02*
X3923385D01*
Y2321666D01*
X3929585D01*
G01X3927105Y2315624D02*
X3923385D01*
G01X3416070Y2332083D02*
X3420100D01*
G01X3438855Y2327916D02*
Y2340416D01*
X3442885Y2329999D01*
X3446915Y2340416D01*
Y2327916D01*
G01X3451720D02*
Y2340416D01*
X3458850Y2327916D01*
Y2340416D01*
G01X3471095Y2339374D02*
X3470165Y2339999D01*
X3469080Y2340416D01*
X3467840D01*
X3466445Y2339791D01*
X3465360Y2338749D01*
X3464585Y2337499D01*
X3463965Y2335416D01*
X3463810Y2333541D01*
X3464120Y2331666D01*
X3464585Y2330416D01*
X3465515Y2329166D01*
X3466600Y2328333D01*
X3467685Y2327916D01*
X3468770D01*
X3469855Y2328333D01*
X3470785Y2328957D01*
X3471560Y2329791D01*
G01X3475435Y2323749D02*
X3484735D01*
G01X3489385Y2340416D02*
Y2327916D01*
X3495585D01*
G01X3501010D02*
X3504885Y2340416D01*
X3508760Y2327916D01*
G01X3507365Y2332291D02*
X3502405D01*
G01X3517285Y2327916D02*
Y2333541D01*
X3514185Y2340416D01*
G01X3520385D02*
X3517285Y2333541D01*
G01X3532785Y2327916D02*
X3526585D01*
Y2340416D01*
X3532785D01*
G01X3530305Y2334374D02*
X3526585D01*
G01X3538985Y2327916D02*
Y2340416D01*
X3542860D01*
X3544100Y2339791D01*
X3544875Y2338958D01*
X3545185Y2337291D01*
X3544875Y2335624D01*
X3543945Y2334583D01*
X3542860Y2333958D01*
X3538985D01*
G01X3542860D02*
X3545185Y2327916D01*
G01X3554485Y2327499D02*
X3554175Y2327708D01*
Y2328124D01*
X3554485Y2328333D01*
X3554795Y2328124D01*
Y2327708D01*
X3554485Y2327499D01*
G01Y2333124D02*
X3554175Y2333333D01*
Y2333749D01*
X3554485Y2333958D01*
X3554795Y2333749D01*
Y2333333D01*
X3554485Y2333124D01*
G01X3575255Y2327916D02*
Y2340416D01*
X3579285Y2329999D01*
X3583315Y2340416D01*
Y2327916D01*
G01X3588275Y2340416D02*
Y2331458D01*
X3588895Y2329582D01*
X3590135Y2328333D01*
X3591685Y2327916D01*
X3593235Y2328333D01*
X3594475Y2329582D01*
X3595095Y2331458D01*
Y2340416D01*
G01X3600830Y2329582D02*
X3602070Y2328541D01*
X3603465Y2327916D01*
X3604705D01*
X3605945Y2328541D01*
X3606875Y2329582D01*
X3607340Y2331041D01*
X3607030Y2332499D01*
X3606255Y2333749D01*
X3604860Y2334583D01*
X3603000Y2334999D01*
X3601915Y2335833D01*
X3601450Y2337291D01*
X3601760Y2338749D01*
X3602535Y2339791D01*
X3603620Y2340416D01*
X3604705D01*
X3605790Y2339999D01*
X3606720Y2338958D01*
G01X3616485Y2340416D02*
Y2327916D01*
G01X3612920Y2340416D02*
X3620050D01*
G01X3626870Y2332083D02*
X3630900D01*
G01X3637720Y2327916D02*
Y2340416D01*
X3644850Y2327916D01*
Y2340416D01*
G01X3653685Y2327916D02*
X3652445Y2328124D01*
X3651360Y2328957D01*
X3650430Y2330208D01*
X3649810Y2331666D01*
X3649500Y2333333D01*
Y2334999D01*
X3649810Y2336666D01*
X3650430Y2338124D01*
X3651360Y2339374D01*
X3652445Y2340208D01*
X3653685Y2340416D01*
X3654925Y2340208D01*
X3656010Y2339374D01*
X3656940Y2338124D01*
X3657560Y2336666D01*
X3657870Y2334999D01*
Y2333333D01*
X3657560Y2331666D01*
X3656940Y2330208D01*
X3656010Y2328957D01*
X3654925Y2328124D01*
X3653685Y2327916D01*
G01X3666085Y2340416D02*
Y2327916D01*
G01X3662520Y2340416D02*
X3669650D01*
G01X3676470Y2332083D02*
X3680500D01*
G01X3694295Y2339374D02*
X3693365Y2339999D01*
X3692280Y2340416D01*
X3691040D01*
X3689645Y2339791D01*
X3688560Y2338749D01*
X3687785Y2337499D01*
X3687165Y2335416D01*
X3687010Y2333541D01*
X3687320Y2331666D01*
X3687785Y2330416D01*
X3688715Y2329166D01*
X3689800Y2328333D01*
X3690885Y2327916D01*
X3691970D01*
X3693055Y2328333D01*
X3693985Y2328957D01*
X3694760Y2329791D01*
G01X3699875Y2340416D02*
Y2331458D01*
X3700495Y2329582D01*
X3701735Y2328333D01*
X3703285Y2327916D01*
X3704835Y2328333D01*
X3706075Y2329582D01*
X3706695Y2331458D01*
Y2340416D01*
G01X3715685D02*
Y2327916D01*
G01X3712120Y2340416D02*
X3719250D01*
G01X3726070Y2332083D02*
X3730100D01*
G01X3737385Y2340416D02*
Y2327916D01*
X3743585D01*
G01X3749010D02*
X3752885Y2340416D01*
X3756760Y2327916D01*
G01X3755365Y2332291D02*
X3750405D01*
G01X3765285Y2327916D02*
Y2333541D01*
X3762185Y2340416D01*
G01X3768385D02*
X3765285Y2333541D01*
G01X3780785Y2327916D02*
X3774585D01*
Y2340416D01*
X3780785D01*
G01X3778305Y2334374D02*
X3774585D01*
G01X3786985Y2327916D02*
Y2340416D01*
X3790860D01*
X3792100Y2339791D01*
X3792875Y2338958D01*
X3793185Y2337291D01*
X3792875Y2335624D01*
X3791945Y2334583D01*
X3790860Y2333958D01*
X3786985D01*
G01X3790860D02*
X3793185Y2327916D01*
G01X3414520Y2346666D02*
Y2359166D01*
X3421650Y2346666D01*
Y2359166D01*
G01X3430485Y2346666D02*
X3429245Y2346874D01*
X3428160Y2347707D01*
X3427230Y2348958D01*
X3426610Y2350416D01*
X3426300Y2352083D01*
Y2353749D01*
X3426610Y2355416D01*
X3427230Y2356874D01*
X3428160Y2358124D01*
X3429245Y2358958D01*
X3430485Y2359166D01*
X3431725Y2358958D01*
X3432810Y2358124D01*
X3433740Y2356874D01*
X3434360Y2355416D01*
X3434670Y2353749D01*
Y2352083D01*
X3434360Y2350416D01*
X3433740Y2348958D01*
X3432810Y2347707D01*
X3431725Y2346874D01*
X3430485Y2346666D01*
G01X3442885Y2359166D02*
Y2346666D01*
G01X3439320Y2359166D02*
X3446450D01*
G01X3458385Y2346666D02*
X3452185D01*
Y2359166D01*
X3458385D01*
G01X3455905Y2353124D02*
X3452185D01*
G01X3464430Y2348332D02*
X3465670Y2347291D01*
X3467065Y2346666D01*
X3468305D01*
X3469545Y2347291D01*
X3470475Y2348332D01*
X3470940Y2349791D01*
X3470630Y2351249D01*
X3469855Y2352499D01*
X3468460Y2353333D01*
X3466600Y2353749D01*
X3465515Y2354583D01*
X3465050Y2356041D01*
X3465360Y2357499D01*
X3466135Y2358541D01*
X3467220Y2359166D01*
X3468305D01*
X3469390Y2358749D01*
X3470320Y2357708D01*
G01X3480085Y2346249D02*
X3479775Y2346458D01*
Y2346874D01*
X3480085Y2347083D01*
X3480395Y2346874D01*
Y2346458D01*
X3480085Y2346249D01*
G01Y2351874D02*
X3479775Y2352083D01*
Y2352499D01*
X3480085Y2352708D01*
X3480395Y2352499D01*
Y2352083D01*
X3480085Y2351874D01*
G01X3585604Y1888903D02*
X3586224Y1889528D01*
X3586689Y1890569D01*
X3586999Y1892028D01*
X3586689Y1893278D01*
X3586069Y1894111D01*
X3584984Y1894736D01*
X3580799D01*
Y1882236D01*
X3585914D01*
X3586999Y1883069D01*
X3587619Y1884319D01*
X3587929Y1885778D01*
X3587619Y1887236D01*
X3586689Y1888486D01*
X3585604Y1888903D01*
X3580799D01*
G01X3592889Y1882236D02*
X3596764Y1894736D01*
X3600639Y1882236D01*
G01X3599244Y1886611D02*
X3594284D01*
G01X3612574Y1893694D02*
X3611644Y1894319D01*
X3610559Y1894736D01*
X3609319D01*
X3607924Y1894111D01*
X3606839Y1893069D01*
X3606064Y1891819D01*
X3605444Y1889736D01*
X3605289Y1887861D01*
X3605599Y1885986D01*
X3606064Y1884736D01*
X3606994Y1883486D01*
X3608079Y1882653D01*
X3609164Y1882236D01*
X3610249D01*
X3611334Y1882653D01*
X3612264Y1883277D01*
X3613039Y1884111D01*
G01X3618154Y1882236D02*
Y1894736D01*
G01X3624044D02*
X3618154Y1887027D01*
G01X3624974Y1882236D02*
X3620789Y1890569D01*
G01X3630554Y1882236D02*
Y1894736D01*
X3633654D01*
X3634894Y1894111D01*
X3635824Y1893278D01*
X3636599Y1892028D01*
X3637219Y1890569D01*
X3637374Y1888486D01*
X3637219Y1886403D01*
X3636599Y1884944D01*
X3635824Y1883694D01*
X3634894Y1882861D01*
X3633654Y1882236D01*
X3630554D01*
G01X3643264D02*
Y1894736D01*
X3647139D01*
X3648379Y1894111D01*
X3649154Y1893278D01*
X3649464Y1891611D01*
X3649154Y1889944D01*
X3648224Y1888903D01*
X3647139Y1888278D01*
X3643264D01*
G01X3647139D02*
X3649464Y1882236D01*
G01X3656904Y1894736D02*
X3660624D01*
G01X3658764D02*
Y1882236D01*
G01X3656904D02*
X3660624D01*
G01X3668064Y1894736D02*
Y1882236D01*
X3674264D01*
G01X3680464Y1894736D02*
Y1882236D01*
X3686664D01*
G01X3705109Y1883902D02*
X3706349Y1882861D01*
X3707744Y1882236D01*
X3708984D01*
X3710224Y1882861D01*
X3711154Y1883902D01*
X3711619Y1885361D01*
X3711309Y1886819D01*
X3710534Y1888069D01*
X3709139Y1888903D01*
X3707279Y1889319D01*
X3706194Y1890153D01*
X3705729Y1891611D01*
X3706039Y1893069D01*
X3706814Y1894111D01*
X3707899Y1894736D01*
X3708984D01*
X3710069Y1894319D01*
X3710999Y1893278D01*
G01X3720764Y1894736D02*
Y1882236D01*
G01X3717199Y1894736D02*
X3724329D01*
G01X3729754D02*
Y1885778D01*
X3730374Y1883902D01*
X3731614Y1882653D01*
X3733164Y1882236D01*
X3734714Y1882653D01*
X3735954Y1883902D01*
X3736574Y1885778D01*
Y1894736D01*
G01X3746804Y1888903D02*
X3747424Y1889528D01*
X3747889Y1890569D01*
X3748199Y1892028D01*
X3747889Y1893278D01*
X3747269Y1894111D01*
X3746184Y1894736D01*
X3741999D01*
Y1882236D01*
X3747114D01*
X3748199Y1883069D01*
X3748819Y1884319D01*
X3749129Y1885778D01*
X3748819Y1887236D01*
X3747889Y1888486D01*
X3746804Y1888903D01*
X3741999D01*
G01X3767264Y1894736D02*
Y1882236D01*
X3773464D01*
G01X3785864D02*
X3779664D01*
Y1894736D01*
X3785864D01*
G01X3783384Y1888694D02*
X3779664D01*
G01X3791599Y1882236D02*
Y1894736D01*
X3798729Y1882236D01*
Y1894736D01*
G01X3808494Y1888486D02*
X3811594D01*
Y1884736D01*
X3810664Y1883486D01*
X3809579Y1882653D01*
X3808029Y1882236D01*
X3806479Y1882653D01*
X3805394Y1883486D01*
X3804464Y1884736D01*
X3803844Y1886194D01*
X3803534Y1887861D01*
Y1889319D01*
X3803844Y1890569D01*
X3804464Y1892028D01*
X3805394Y1893278D01*
X3806324Y1894111D01*
X3807564Y1894736D01*
X3808649D01*
X3809889Y1894319D01*
X3810819Y1893486D01*
G01X3819964Y1894736D02*
Y1882236D01*
G01X3816399Y1894736D02*
X3823529D01*
G01X3829109Y1882236D02*
Y1894736D01*
G01X3835619D02*
Y1882236D01*
G01Y1888486D02*
X3829109D01*
G01X3857164Y1894736D02*
Y1882236D01*
G01X3853599Y1894736D02*
X3860729D01*
G01X3869564Y1882236D02*
X3868324Y1882444D01*
X3867239Y1883277D01*
X3866309Y1884528D01*
X3865689Y1885986D01*
X3865379Y1887653D01*
Y1889319D01*
X3865689Y1890986D01*
X3866309Y1892444D01*
X3867239Y1893694D01*
X3868324Y1894528D01*
X3869564Y1894736D01*
X3870804Y1894528D01*
X3871889Y1893694D01*
X3872819Y1892444D01*
X3873439Y1890986D01*
X3873749Y1889319D01*
Y1887653D01*
X3873439Y1885986D01*
X3872819Y1884528D01*
X3871889Y1883277D01*
X3870804Y1882444D01*
X3869564Y1882236D01*
G01X3878864Y1894736D02*
Y1882236D01*
X3885064D01*
G01X3897464D02*
X3891264D01*
Y1894736D01*
X3897464D01*
G01X3894984Y1888694D02*
X3891264D01*
G01X3903664Y1882236D02*
Y1894736D01*
X3907539D01*
X3908779Y1894111D01*
X3909554Y1893278D01*
X3909864Y1891611D01*
X3909554Y1889944D01*
X3908624Y1888903D01*
X3907539Y1888278D01*
X3903664D01*
G01X3907539D02*
X3909864Y1882236D01*
G01X3915289D02*
X3919164Y1894736D01*
X3923039Y1882236D01*
G01X3921644Y1886611D02*
X3916684D01*
G01X3927999Y1882236D02*
Y1894736D01*
X3935129Y1882236D01*
Y1894736D01*
G01X3947374Y1893694D02*
X3946444Y1894319D01*
X3945359Y1894736D01*
X3944119D01*
X3942724Y1894111D01*
X3941639Y1893069D01*
X3940864Y1891819D01*
X3940244Y1889736D01*
X3940089Y1887861D01*
X3940399Y1885986D01*
X3940864Y1884736D01*
X3941794Y1883486D01*
X3942879Y1882653D01*
X3943964Y1882236D01*
X3945049D01*
X3946134Y1882653D01*
X3947064Y1883277D01*
X3947839Y1884111D01*
G01X3959464Y1882236D02*
X3953264D01*
Y1894736D01*
X3959464D01*
G01X3956984Y1888694D02*
X3953264D01*
G01X3981164Y1894736D02*
Y1882236D01*
G01X3977599Y1894736D02*
X3984729D01*
G01X3993564Y1882236D02*
X3992324Y1882444D01*
X3991239Y1883277D01*
X3990309Y1884528D01*
X3989689Y1885986D01*
X3989379Y1887653D01*
Y1889319D01*
X3989689Y1890986D01*
X3990309Y1892444D01*
X3991239Y1893694D01*
X3992324Y1894528D01*
X3993564Y1894736D01*
X3994804Y1894528D01*
X3995889Y1893694D01*
X3996819Y1892444D01*
X3997439Y1890986D01*
X3997749Y1889319D01*
Y1887653D01*
X3997439Y1885986D01*
X3996819Y1884528D01*
X3995889Y1883277D01*
X3994804Y1882444D01*
X3993564Y1882236D01*
G01X4019604Y1888903D02*
X4020224Y1889528D01*
X4020689Y1890569D01*
X4020999Y1892028D01*
X4020689Y1893278D01*
X4020069Y1894111D01*
X4018984Y1894736D01*
X4014799D01*
Y1882236D01*
X4019914D01*
X4020999Y1883069D01*
X4021619Y1884319D01*
X4021929Y1885778D01*
X4021619Y1887236D01*
X4020689Y1888486D01*
X4019604Y1888903D01*
X4014799D01*
G01X4033864Y1882236D02*
X4027664D01*
Y1894736D01*
X4033864D01*
G01X4031384Y1888694D02*
X4027664D01*
G01X4055254Y1882236D02*
X4055564Y1884944D01*
X4056029Y1887236D01*
X4056649Y1889319D01*
X4057424Y1891611D01*
X4058664Y1894736D01*
X4052464D01*
G01X4078659Y1886403D02*
X4082379D01*
G01X4080364Y1889111D02*
Y1883694D01*
G01X4089974Y1881819D02*
X4095554Y1894736D01*
G01X4103149Y1886403D02*
X4107179D01*
G01X4114154Y1884111D02*
X4115084Y1883069D01*
X4116169Y1882444D01*
X4117564Y1882236D01*
X4118959Y1882653D01*
X4120044Y1883486D01*
X4120819Y1884944D01*
X4120974Y1886611D01*
X4120664Y1888278D01*
X4119889Y1889319D01*
X4118804Y1890153D01*
X4117719Y1890361D01*
X4116634Y1890153D01*
X4115239Y1889319D01*
X4115704Y1894736D01*
X4119889D01*
G01X4138334Y1882236D02*
Y1894736D01*
X4142364Y1884319D01*
X4146394Y1894736D01*
Y1882236D01*
G01X4152904Y1894736D02*
X4156624D01*
G01X4154764D02*
Y1882236D01*
G01X4152904D02*
X4156624D01*
G01X4164064Y1894736D02*
Y1882236D01*
X4170264D01*
G01X4176309Y1883902D02*
X4177549Y1882861D01*
X4178944Y1882236D01*
X4180184D01*
X4181424Y1882861D01*
X4182354Y1883902D01*
X4182819Y1885361D01*
X4182509Y1886819D01*
X4181734Y1888069D01*
X4180339Y1888903D01*
X4178479Y1889319D01*
X4177394Y1890153D01*
X4176929Y1891611D01*
X4177239Y1893069D01*
X4178014Y1894111D01*
X4179099Y1894736D01*
X4180184D01*
X4181269Y1894319D01*
X4182199Y1893278D01*
G01X3421149Y1905153D02*
X3425179D01*
G01X3443934Y1900986D02*
Y1913486D01*
X3447964Y1903069D01*
X3451994Y1913486D01*
Y1900986D01*
G01X3457419D02*
Y1913486D01*
X3463309D01*
G01X3461139Y1907444D02*
X3457419D01*
G01X3473694Y1907236D02*
X3476794D01*
Y1903486D01*
X3475864Y1902236D01*
X3474779Y1901403D01*
X3473229Y1900986D01*
X3471679Y1901403D01*
X3470594Y1902236D01*
X3469664Y1903486D01*
X3469044Y1904944D01*
X3468734Y1906611D01*
Y1908069D01*
X3469044Y1909319D01*
X3469664Y1910778D01*
X3470594Y1912028D01*
X3471524Y1912861D01*
X3472764Y1913486D01*
X3473849D01*
X3475089Y1913069D01*
X3476019Y1912236D01*
G01X3480514Y1896819D02*
X3489814D01*
G01X3494309Y1902652D02*
X3495549Y1901611D01*
X3496944Y1900986D01*
X3498184D01*
X3499424Y1901611D01*
X3500354Y1902652D01*
X3500819Y1904111D01*
X3500509Y1905569D01*
X3499734Y1906819D01*
X3498339Y1907653D01*
X3496479Y1908069D01*
X3495394Y1908903D01*
X3494929Y1910361D01*
X3495239Y1911819D01*
X3496014Y1912861D01*
X3497099Y1913486D01*
X3498184D01*
X3499269Y1913069D01*
X3500199Y1912028D01*
G01X3509964Y1913486D02*
Y1900986D01*
G01X3506399Y1913486D02*
X3513529D01*
G01X3518954D02*
Y1904528D01*
X3519574Y1902652D01*
X3520814Y1901403D01*
X3522364Y1900986D01*
X3523914Y1901403D01*
X3525154Y1902652D01*
X3525774Y1904528D01*
Y1913486D01*
G01X3536004Y1907653D02*
X3536624Y1908278D01*
X3537089Y1909319D01*
X3537399Y1910778D01*
X3537089Y1912028D01*
X3536469Y1912861D01*
X3535384Y1913486D01*
X3531199D01*
Y1900986D01*
X3536314D01*
X3537399Y1901819D01*
X3538019Y1903069D01*
X3538329Y1904528D01*
X3538019Y1905986D01*
X3537089Y1907236D01*
X3536004Y1907653D01*
X3531199D01*
G01X3559564Y1900569D02*
X3559254Y1900778D01*
Y1901194D01*
X3559564Y1901403D01*
X3559874Y1901194D01*
Y1900778D01*
X3559564Y1900569D01*
G01Y1906194D02*
X3559254Y1906403D01*
Y1906819D01*
X3559564Y1907028D01*
X3559874Y1906819D01*
Y1906403D01*
X3559564Y1906194D01*
G01X3580334Y1900986D02*
Y1913486D01*
X3584364Y1903069D01*
X3588394Y1913486D01*
Y1900986D01*
G01X3592889D02*
X3596764Y1913486D01*
X3600639Y1900986D01*
G01X3599244Y1905361D02*
X3594284D01*
G01X3605599Y1900986D02*
Y1913486D01*
X3612729Y1900986D01*
Y1913486D01*
G01X3618154D02*
Y1904528D01*
X3618774Y1902652D01*
X3620014Y1901403D01*
X3621564Y1900986D01*
X3623114Y1901403D01*
X3624354Y1902652D01*
X3624974Y1904528D01*
Y1913486D01*
G01X3631019Y1900986D02*
Y1913486D01*
X3636909D01*
G01X3634739Y1907444D02*
X3631019D01*
G01X3642489Y1900986D02*
X3646364Y1913486D01*
X3650239Y1900986D01*
G01X3648844Y1905361D02*
X3643884D01*
G01X3662174Y1912444D02*
X3661244Y1913069D01*
X3660159Y1913486D01*
X3658919D01*
X3657524Y1912861D01*
X3656439Y1911819D01*
X3655664Y1910569D01*
X3655044Y1908486D01*
X3654889Y1906611D01*
X3655199Y1904736D01*
X3655664Y1903486D01*
X3656594Y1902236D01*
X3657679Y1901403D01*
X3658764Y1900986D01*
X3659849D01*
X3660934Y1901403D01*
X3661864Y1902027D01*
X3662639Y1902861D01*
G01X3671164Y1913486D02*
Y1900986D01*
G01X3667599Y1913486D02*
X3674729D01*
G01X3680154D02*
Y1904528D01*
X3680774Y1902652D01*
X3682014Y1901403D01*
X3683564Y1900986D01*
X3685114Y1901403D01*
X3686354Y1902652D01*
X3686974Y1904528D01*
Y1913486D01*
G01X3692864Y1900986D02*
Y1913486D01*
X3696739D01*
X3697979Y1912861D01*
X3698754Y1912028D01*
X3699064Y1910361D01*
X3698754Y1908694D01*
X3697824Y1907653D01*
X3696739Y1907028D01*
X3692864D01*
G01X3696739D02*
X3699064Y1900986D01*
G01X3706504Y1913486D02*
X3710224D01*
G01X3708364D02*
Y1900986D01*
G01X3706504D02*
X3710224D01*
G01X3717199D02*
Y1913486D01*
X3724329Y1900986D01*
Y1913486D01*
G01X3734094Y1907236D02*
X3737194D01*
Y1903486D01*
X3736264Y1902236D01*
X3735179Y1901403D01*
X3733629Y1900986D01*
X3732079Y1901403D01*
X3730994Y1902236D01*
X3730064Y1903486D01*
X3729444Y1904944D01*
X3729134Y1906611D01*
Y1908069D01*
X3729444Y1909319D01*
X3730064Y1910778D01*
X3730994Y1912028D01*
X3731924Y1912861D01*
X3733164Y1913486D01*
X3734249D01*
X3735489Y1913069D01*
X3736419Y1912236D01*
G01X3754709Y1902652D02*
X3755949Y1901611D01*
X3757344Y1900986D01*
X3758584D01*
X3759824Y1901611D01*
X3760754Y1902652D01*
X3761219Y1904111D01*
X3760909Y1905569D01*
X3760134Y1906819D01*
X3758739Y1907653D01*
X3756879Y1908069D01*
X3755794Y1908903D01*
X3755329Y1910361D01*
X3755639Y1911819D01*
X3756414Y1912861D01*
X3757499Y1913486D01*
X3758584D01*
X3759669Y1913069D01*
X3760599Y1912028D01*
G01X3770364Y1913486D02*
Y1900986D01*
G01X3766799Y1913486D02*
X3773929D01*
G01X3779354D02*
Y1904528D01*
X3779974Y1902652D01*
X3781214Y1901403D01*
X3782764Y1900986D01*
X3784314Y1901403D01*
X3785554Y1902652D01*
X3786174Y1904528D01*
Y1913486D01*
G01X3796404Y1907653D02*
X3797024Y1908278D01*
X3797489Y1909319D01*
X3797799Y1910778D01*
X3797489Y1912028D01*
X3796869Y1912861D01*
X3795784Y1913486D01*
X3791599D01*
Y1900986D01*
X3796714D01*
X3797799Y1901819D01*
X3798419Y1903069D01*
X3798729Y1904528D01*
X3798419Y1905986D01*
X3797489Y1907236D01*
X3796404Y1907653D01*
X3791599D01*
G01X3816864Y1913486D02*
Y1900986D01*
X3823064D01*
G01X3835464D02*
X3829264D01*
Y1913486D01*
X3835464D01*
G01X3832984Y1907444D02*
X3829264D01*
G01X3841199Y1900986D02*
Y1913486D01*
X3848329Y1900986D01*
Y1913486D01*
G01X3858094Y1907236D02*
X3861194D01*
Y1903486D01*
X3860264Y1902236D01*
X3859179Y1901403D01*
X3857629Y1900986D01*
X3856079Y1901403D01*
X3854994Y1902236D01*
X3854064Y1903486D01*
X3853444Y1904944D01*
X3853134Y1906611D01*
Y1908069D01*
X3853444Y1909319D01*
X3854064Y1910778D01*
X3854994Y1912028D01*
X3855924Y1912861D01*
X3857164Y1913486D01*
X3858249D01*
X3859489Y1913069D01*
X3860419Y1912236D01*
G01X3869564Y1913486D02*
Y1900986D01*
G01X3865999Y1913486D02*
X3873129D01*
G01X3878709Y1900986D02*
Y1913486D01*
G01X3885219D02*
Y1900986D01*
G01Y1907236D02*
X3878709D01*
G01X3581109Y1921402D02*
X3582349Y1920361D01*
X3583744Y1919736D01*
X3584984D01*
X3586224Y1920361D01*
X3587154Y1921402D01*
X3587619Y1922861D01*
X3587309Y1924319D01*
X3586534Y1925569D01*
X3585139Y1926403D01*
X3583279Y1926819D01*
X3582194Y1927653D01*
X3581729Y1929111D01*
X3582039Y1930569D01*
X3582814Y1931611D01*
X3583899Y1932236D01*
X3584984D01*
X3586069Y1931819D01*
X3586999Y1930778D01*
G01X3593354Y1932236D02*
Y1923278D01*
X3593974Y1921402D01*
X3595214Y1920153D01*
X3596764Y1919736D01*
X3598314Y1920153D01*
X3599554Y1921402D01*
X3600174Y1923278D01*
Y1932236D01*
G01X3606064Y1919736D02*
Y1932236D01*
X3609939D01*
X3611179Y1931611D01*
X3611954Y1930778D01*
X3612264Y1929111D01*
X3611954Y1927444D01*
X3611024Y1926403D01*
X3609939Y1925778D01*
X3606064D01*
G01X3609939D02*
X3612264Y1919736D01*
G01X3618619D02*
Y1932236D01*
X3624509D01*
G01X3622339Y1926194D02*
X3618619D01*
G01X3630089Y1919736D02*
X3633964Y1932236D01*
X3637839Y1919736D01*
G01X3636444Y1924111D02*
X3631484D01*
G01X3649774Y1931194D02*
X3648844Y1931819D01*
X3647759Y1932236D01*
X3646519D01*
X3645124Y1931611D01*
X3644039Y1930569D01*
X3643264Y1929319D01*
X3642644Y1927236D01*
X3642489Y1925361D01*
X3642799Y1923486D01*
X3643264Y1922236D01*
X3644194Y1920986D01*
X3645279Y1920153D01*
X3646364Y1919736D01*
X3647449D01*
X3648534Y1920153D01*
X3649464Y1920777D01*
X3650239Y1921611D01*
G01X3661864Y1919736D02*
X3655664D01*
Y1932236D01*
X3661864D01*
G01X3659384Y1926194D02*
X3655664D01*
G01X3683564Y1919736D02*
X3682324Y1919944D01*
X3681239Y1920777D01*
X3680309Y1922028D01*
X3679689Y1923486D01*
X3679379Y1925153D01*
Y1926819D01*
X3679689Y1928486D01*
X3680309Y1929944D01*
X3681239Y1931194D01*
X3682324Y1932028D01*
X3683564Y1932236D01*
X3684804Y1932028D01*
X3685889Y1931194D01*
X3686819Y1929944D01*
X3687439Y1928486D01*
X3687749Y1926819D01*
Y1925153D01*
X3687439Y1923486D01*
X3686819Y1922028D01*
X3685889Y1920777D01*
X3684804Y1919944D01*
X3683564Y1919736D01*
G01X3693019D02*
Y1932236D01*
X3698909D01*
G01X3696739Y1926194D02*
X3693019D01*
G01X3716734Y1919736D02*
Y1932236D01*
X3720764Y1921819D01*
X3724794Y1932236D01*
Y1919736D01*
G01X3729754Y1932236D02*
Y1923278D01*
X3730374Y1921402D01*
X3731614Y1920153D01*
X3733164Y1919736D01*
X3734714Y1920153D01*
X3735954Y1921402D01*
X3736574Y1923278D01*
Y1932236D01*
G01X3742309Y1921402D02*
X3743549Y1920361D01*
X3744944Y1919736D01*
X3746184D01*
X3747424Y1920361D01*
X3748354Y1921402D01*
X3748819Y1922861D01*
X3748509Y1924319D01*
X3747734Y1925569D01*
X3746339Y1926403D01*
X3744479Y1926819D01*
X3743394Y1927653D01*
X3742929Y1929111D01*
X3743239Y1930569D01*
X3744014Y1931611D01*
X3745099Y1932236D01*
X3746184D01*
X3747269Y1931819D01*
X3748199Y1930778D01*
G01X3757964Y1932236D02*
Y1919736D01*
G01X3754399Y1932236D02*
X3761529D01*
G01X3768349Y1923903D02*
X3772379D01*
G01X3779199Y1919736D02*
Y1932236D01*
X3786329Y1919736D01*
Y1932236D01*
G01X3795164Y1919736D02*
X3793924Y1919944D01*
X3792839Y1920777D01*
X3791909Y1922028D01*
X3791289Y1923486D01*
X3790979Y1925153D01*
Y1926819D01*
X3791289Y1928486D01*
X3791909Y1929944D01*
X3792839Y1931194D01*
X3793924Y1932028D01*
X3795164Y1932236D01*
X3796404Y1932028D01*
X3797489Y1931194D01*
X3798419Y1929944D01*
X3799039Y1928486D01*
X3799349Y1926819D01*
Y1925153D01*
X3799039Y1923486D01*
X3798419Y1922028D01*
X3797489Y1920777D01*
X3796404Y1919944D01*
X3795164Y1919736D01*
G01X3807564Y1932236D02*
Y1919736D01*
G01X3803999Y1932236D02*
X3811129D01*
G01X3817949Y1923903D02*
X3821979D01*
G01X3835774Y1931194D02*
X3834844Y1931819D01*
X3833759Y1932236D01*
X3832519D01*
X3831124Y1931611D01*
X3830039Y1930569D01*
X3829264Y1929319D01*
X3828644Y1927236D01*
X3828489Y1925361D01*
X3828799Y1923486D01*
X3829264Y1922236D01*
X3830194Y1920986D01*
X3831279Y1920153D01*
X3832364Y1919736D01*
X3833449D01*
X3834534Y1920153D01*
X3835464Y1920777D01*
X3836239Y1921611D01*
G01X3841354Y1932236D02*
Y1923278D01*
X3841974Y1921402D01*
X3843214Y1920153D01*
X3844764Y1919736D01*
X3846314Y1920153D01*
X3847554Y1921402D01*
X3848174Y1923278D01*
Y1932236D01*
G01X3857164D02*
Y1919736D01*
G01X3853599Y1932236D02*
X3860729D01*
G01X3867549Y1923903D02*
X3871579D01*
G01X3878864Y1932236D02*
Y1919736D01*
X3885064D01*
G01X3890489D02*
X3894364Y1932236D01*
X3898239Y1919736D01*
G01X3896844Y1924111D02*
X3891884D01*
G01X3906764Y1919736D02*
Y1925361D01*
X3903664Y1932236D01*
G01X3909864D02*
X3906764Y1925361D01*
G01X3922264Y1919736D02*
X3916064D01*
Y1932236D01*
X3922264D01*
G01X3919784Y1926194D02*
X3916064D01*
G01X3928464Y1919736D02*
Y1932236D01*
X3932339D01*
X3933579Y1931611D01*
X3934354Y1930778D01*
X3934664Y1929111D01*
X3934354Y1927444D01*
X3933424Y1926403D01*
X3932339Y1925778D01*
X3928464D01*
G01X3932339D02*
X3934664Y1919736D01*
G01X3421149Y1942653D02*
X3425179D01*
G01X3443934Y1938486D02*
Y1950986D01*
X3447964Y1940569D01*
X3451994Y1950986D01*
Y1938486D01*
G01X3456489D02*
X3460364Y1950986D01*
X3464239Y1938486D01*
G01X3462844Y1942861D02*
X3457884D01*
G01X3469509Y1938486D02*
X3476019Y1950986D01*
G01X3469509D02*
X3476019Y1938486D01*
G01X3480514Y1934319D02*
X3489814D01*
G01X3494154Y1938486D02*
Y1950986D01*
X3497254D01*
X3498494Y1950361D01*
X3499424Y1949528D01*
X3500199Y1948278D01*
X3500819Y1946819D01*
X3500974Y1944736D01*
X3500819Y1942653D01*
X3500199Y1941194D01*
X3499424Y1939944D01*
X3498494Y1939111D01*
X3497254Y1938486D01*
X3494154D01*
G01X3513064D02*
X3506864D01*
Y1950986D01*
X3513064D01*
G01X3510584Y1944944D02*
X3506864D01*
G01X3519264Y1938486D02*
Y1950986D01*
X3522984D01*
X3524224Y1950361D01*
X3525154Y1948903D01*
X3525464Y1947236D01*
X3525154Y1945569D01*
X3524379Y1944319D01*
X3522984Y1943694D01*
X3519264D01*
G01X3534764Y1950986D02*
Y1938486D01*
G01X3531199Y1950986D02*
X3538329D01*
G01X3543909Y1938486D02*
Y1950986D01*
G01X3550419D02*
Y1938486D01*
G01Y1944736D02*
X3543909D01*
G01X3559564Y1938069D02*
X3559254Y1938278D01*
Y1938694D01*
X3559564Y1938903D01*
X3559874Y1938694D01*
Y1938278D01*
X3559564Y1938069D01*
G01Y1943694D02*
X3559254Y1943903D01*
Y1944319D01*
X3559564Y1944528D01*
X3559874Y1944319D01*
Y1943903D01*
X3559564Y1943694D01*
G01X3580954Y1938486D02*
Y1950986D01*
X3584054D01*
X3585294Y1950361D01*
X3586224Y1949528D01*
X3586999Y1948278D01*
X3587619Y1946819D01*
X3587774Y1944736D01*
X3587619Y1942653D01*
X3586999Y1941194D01*
X3586224Y1939944D01*
X3585294Y1939111D01*
X3584054Y1938486D01*
X3580954D01*
G01X3599864D02*
X3593664D01*
Y1950986D01*
X3599864D01*
G01X3597384Y1944944D02*
X3593664D01*
G01X3606064Y1938486D02*
Y1950986D01*
X3609784D01*
X3611024Y1950361D01*
X3611954Y1948903D01*
X3612264Y1947236D01*
X3611954Y1945569D01*
X3611179Y1944319D01*
X3609784Y1943694D01*
X3606064D01*
G01X3621564Y1950986D02*
Y1938486D01*
G01X3617999Y1950986D02*
X3625129D01*
G01X3630709Y1938486D02*
Y1950986D01*
G01X3637219D02*
Y1938486D01*
G01Y1944736D02*
X3630709D01*
G01X3655819Y1938486D02*
Y1950986D01*
X3661709D01*
G01X3659539Y1944944D02*
X3655819D01*
G01X3668064Y1938486D02*
Y1950986D01*
X3671939D01*
X3673179Y1950361D01*
X3673954Y1949528D01*
X3674264Y1947861D01*
X3673954Y1946194D01*
X3673024Y1945153D01*
X3671939Y1944528D01*
X3668064D01*
G01X3671939D02*
X3674264Y1938486D01*
G01X3683564D02*
X3682324Y1938694D01*
X3681239Y1939527D01*
X3680309Y1940778D01*
X3679689Y1942236D01*
X3679379Y1943903D01*
Y1945569D01*
X3679689Y1947236D01*
X3680309Y1948694D01*
X3681239Y1949944D01*
X3682324Y1950778D01*
X3683564Y1950986D01*
X3684804Y1950778D01*
X3685889Y1949944D01*
X3686819Y1948694D01*
X3687439Y1947236D01*
X3687749Y1945569D01*
Y1943903D01*
X3687439Y1942236D01*
X3686819Y1940778D01*
X3685889Y1939527D01*
X3684804Y1938694D01*
X3683564Y1938486D01*
G01X3691934D02*
Y1950986D01*
X3695964Y1940569D01*
X3699994Y1950986D01*
Y1938486D01*
G01X3717509Y1940152D02*
X3718749Y1939111D01*
X3720144Y1938486D01*
X3721384D01*
X3722624Y1939111D01*
X3723554Y1940152D01*
X3724019Y1941611D01*
X3723709Y1943069D01*
X3722934Y1944319D01*
X3721539Y1945153D01*
X3719679Y1945569D01*
X3718594Y1946403D01*
X3718129Y1947861D01*
X3718439Y1949319D01*
X3719214Y1950361D01*
X3720299Y1950986D01*
X3721384D01*
X3722469Y1950569D01*
X3723399Y1949528D01*
G01X3733164Y1950986D02*
Y1938486D01*
G01X3729599Y1950986D02*
X3736729D01*
G01X3741689Y1938486D02*
X3745564Y1950986D01*
X3749439Y1938486D01*
G01X3748044Y1942861D02*
X3743084D01*
G01X3754864Y1938486D02*
Y1950986D01*
X3758739D01*
X3759979Y1950361D01*
X3760754Y1949528D01*
X3761064Y1947861D01*
X3760754Y1946194D01*
X3759824Y1945153D01*
X3758739Y1944528D01*
X3754864D01*
G01X3758739D02*
X3761064Y1938486D01*
G01X3770364Y1950986D02*
Y1938486D01*
G01X3766799Y1950986D02*
X3773929D01*
G01X3792064D02*
Y1938486D01*
X3798264D01*
G01X3803689D02*
X3807564Y1950986D01*
X3811439Y1938486D01*
G01X3810044Y1942861D02*
X3805084D01*
G01X3819964Y1938486D02*
Y1944111D01*
X3816864Y1950986D01*
G01X3823064D02*
X3819964Y1944111D01*
G01X3835464Y1938486D02*
X3829264D01*
Y1950986D01*
X3835464D01*
G01X3832984Y1944944D02*
X3829264D01*
G01X3841664Y1938486D02*
Y1950986D01*
X3845539D01*
X3846779Y1950361D01*
X3847554Y1949528D01*
X3847864Y1947861D01*
X3847554Y1946194D01*
X3846624Y1945153D01*
X3845539Y1944528D01*
X3841664D01*
G01X3845539D02*
X3847864Y1938486D01*
G01X3869564Y1950986D02*
Y1938486D01*
G01X3865999Y1950986D02*
X3873129D01*
G01X3881964Y1938486D02*
X3880724Y1938694D01*
X3879639Y1939527D01*
X3878709Y1940778D01*
X3878089Y1942236D01*
X3877779Y1943903D01*
Y1945569D01*
X3878089Y1947236D01*
X3878709Y1948694D01*
X3879639Y1949944D01*
X3880724Y1950778D01*
X3881964Y1950986D01*
X3883204Y1950778D01*
X3884289Y1949944D01*
X3885219Y1948694D01*
X3885839Y1947236D01*
X3886149Y1945569D01*
Y1943903D01*
X3885839Y1942236D01*
X3885219Y1940778D01*
X3884289Y1939527D01*
X3883204Y1938694D01*
X3881964Y1938486D01*
G01X3906764Y1950986D02*
Y1938486D01*
G01X3903199Y1950986D02*
X3910329D01*
G01X3915909Y1938486D02*
Y1950986D01*
G01X3922419D02*
Y1938486D01*
G01Y1944736D02*
X3915909D01*
G01X3934664Y1938486D02*
X3928464D01*
Y1950986D01*
X3934664D01*
G01X3932184Y1944944D02*
X3928464D01*
G01X3421149Y1961403D02*
X3425179D01*
G01X3443934Y1957236D02*
Y1969736D01*
X3447964Y1959319D01*
X3451994Y1969736D01*
Y1957236D01*
G01X3456799D02*
Y1969736D01*
X3463929Y1957236D01*
Y1969736D01*
G01X3476174Y1968694D02*
X3475244Y1969319D01*
X3474159Y1969736D01*
X3472919D01*
X3471524Y1969111D01*
X3470439Y1968069D01*
X3469664Y1966819D01*
X3469044Y1964736D01*
X3468889Y1962861D01*
X3469199Y1960986D01*
X3469664Y1959736D01*
X3470594Y1958486D01*
X3471679Y1957653D01*
X3472764Y1957236D01*
X3473849D01*
X3474934Y1957653D01*
X3475864Y1958277D01*
X3476639Y1959111D01*
G01X3480514Y1953069D02*
X3489814D01*
G01X3494464Y1969736D02*
Y1957236D01*
X3500664D01*
G01X3506089D02*
X3509964Y1969736D01*
X3513839Y1957236D01*
G01X3512444Y1961611D02*
X3507484D01*
G01X3522364Y1957236D02*
Y1962861D01*
X3519264Y1969736D01*
G01X3525464D02*
X3522364Y1962861D01*
G01X3537864Y1957236D02*
X3531664D01*
Y1969736D01*
X3537864D01*
G01X3535384Y1963694D02*
X3531664D01*
G01X3544064Y1957236D02*
Y1969736D01*
X3547939D01*
X3549179Y1969111D01*
X3549954Y1968278D01*
X3550264Y1966611D01*
X3549954Y1964944D01*
X3549024Y1963903D01*
X3547939Y1963278D01*
X3544064D01*
G01X3547939D02*
X3550264Y1957236D01*
G01X3559564Y1956819D02*
X3559254Y1957028D01*
Y1957444D01*
X3559564Y1957653D01*
X3559874Y1957444D01*
Y1957028D01*
X3559564Y1956819D01*
G01Y1962444D02*
X3559254Y1962653D01*
Y1963069D01*
X3559564Y1963278D01*
X3559874Y1963069D01*
Y1962653D01*
X3559564Y1962444D01*
G01X3580334Y1957236D02*
Y1969736D01*
X3584364Y1959319D01*
X3588394Y1969736D01*
Y1957236D01*
G01X3593354Y1969736D02*
Y1960778D01*
X3593974Y1958902D01*
X3595214Y1957653D01*
X3596764Y1957236D01*
X3598314Y1957653D01*
X3599554Y1958902D01*
X3600174Y1960778D01*
Y1969736D01*
G01X3605909Y1958902D02*
X3607149Y1957861D01*
X3608544Y1957236D01*
X3609784D01*
X3611024Y1957861D01*
X3611954Y1958902D01*
X3612419Y1960361D01*
X3612109Y1961819D01*
X3611334Y1963069D01*
X3609939Y1963903D01*
X3608079Y1964319D01*
X3606994Y1965153D01*
X3606529Y1966611D01*
X3606839Y1968069D01*
X3607614Y1969111D01*
X3608699Y1969736D01*
X3609784D01*
X3610869Y1969319D01*
X3611799Y1968278D01*
G01X3621564Y1969736D02*
Y1957236D01*
G01X3617999Y1969736D02*
X3625129D01*
G01X3631949Y1961403D02*
X3635979D01*
G01X3642799Y1957236D02*
Y1969736D01*
X3649929Y1957236D01*
Y1969736D01*
G01X3658764Y1957236D02*
X3657524Y1957444D01*
X3656439Y1958277D01*
X3655509Y1959528D01*
X3654889Y1960986D01*
X3654579Y1962653D01*
Y1964319D01*
X3654889Y1965986D01*
X3655509Y1967444D01*
X3656439Y1968694D01*
X3657524Y1969528D01*
X3658764Y1969736D01*
X3660004Y1969528D01*
X3661089Y1968694D01*
X3662019Y1967444D01*
X3662639Y1965986D01*
X3662949Y1964319D01*
Y1962653D01*
X3662639Y1960986D01*
X3662019Y1959528D01*
X3661089Y1958277D01*
X3660004Y1957444D01*
X3658764Y1957236D01*
G01X3671164Y1969736D02*
Y1957236D01*
G01X3667599Y1969736D02*
X3674729D01*
G01X3681549Y1961403D02*
X3685579D01*
G01X3699374Y1968694D02*
X3698444Y1969319D01*
X3697359Y1969736D01*
X3696119D01*
X3694724Y1969111D01*
X3693639Y1968069D01*
X3692864Y1966819D01*
X3692244Y1964736D01*
X3692089Y1962861D01*
X3692399Y1960986D01*
X3692864Y1959736D01*
X3693794Y1958486D01*
X3694879Y1957653D01*
X3695964Y1957236D01*
X3697049D01*
X3698134Y1957653D01*
X3699064Y1958277D01*
X3699839Y1959111D01*
G01X3704954Y1969736D02*
Y1960778D01*
X3705574Y1958902D01*
X3706814Y1957653D01*
X3708364Y1957236D01*
X3709914Y1957653D01*
X3711154Y1958902D01*
X3711774Y1960778D01*
Y1969736D01*
G01X3720764D02*
Y1957236D01*
G01X3717199Y1969736D02*
X3724329D01*
G01X3731149Y1961403D02*
X3735179D01*
G01X3742464Y1969736D02*
Y1957236D01*
X3748664D01*
G01X3754089D02*
X3757964Y1969736D01*
X3761839Y1957236D01*
G01X3760444Y1961611D02*
X3755484D01*
G01X3770364Y1957236D02*
Y1962861D01*
X3767264Y1969736D01*
G01X3773464D02*
X3770364Y1962861D01*
G01X3785864Y1957236D02*
X3779664D01*
Y1969736D01*
X3785864D01*
G01X3783384Y1963694D02*
X3779664D01*
G01X3792064Y1957236D02*
Y1969736D01*
X3795939D01*
X3797179Y1969111D01*
X3797954Y1968278D01*
X3798264Y1966611D01*
X3797954Y1964944D01*
X3797024Y1963903D01*
X3795939Y1963278D01*
X3792064D01*
G01X3795939D02*
X3798264Y1957236D01*
G01X3419599Y1975986D02*
Y1988486D01*
X3426729Y1975986D01*
Y1988486D01*
G01X3435564Y1975986D02*
X3434324Y1976194D01*
X3433239Y1977027D01*
X3432309Y1978278D01*
X3431689Y1979736D01*
X3431379Y1981403D01*
Y1983069D01*
X3431689Y1984736D01*
X3432309Y1986194D01*
X3433239Y1987444D01*
X3434324Y1988278D01*
X3435564Y1988486D01*
X3436804Y1988278D01*
X3437889Y1987444D01*
X3438819Y1986194D01*
X3439439Y1984736D01*
X3439749Y1983069D01*
Y1981403D01*
X3439439Y1979736D01*
X3438819Y1978278D01*
X3437889Y1977027D01*
X3436804Y1976194D01*
X3435564Y1975986D01*
G01X3447964Y1988486D02*
Y1975986D01*
G01X3444399Y1988486D02*
X3451529D01*
G01X3463464Y1975986D02*
X3457264D01*
Y1988486D01*
X3463464D01*
G01X3460984Y1982444D02*
X3457264D01*
G01X3469509Y1977652D02*
X3470749Y1976611D01*
X3472144Y1975986D01*
X3473384D01*
X3474624Y1976611D01*
X3475554Y1977652D01*
X3476019Y1979111D01*
X3475709Y1980569D01*
X3474934Y1981819D01*
X3473539Y1982653D01*
X3471679Y1983069D01*
X3470594Y1983903D01*
X3470129Y1985361D01*
X3470439Y1986819D01*
X3471214Y1987861D01*
X3472299Y1988486D01*
X3473384D01*
X3474469Y1988069D01*
X3475399Y1987028D01*
G01X3485164Y1975569D02*
X3484854Y1975778D01*
Y1976194D01*
X3485164Y1976403D01*
X3485474Y1976194D01*
Y1975778D01*
X3485164Y1975569D01*
G01Y1981194D02*
X3484854Y1981403D01*
Y1981819D01*
X3485164Y1982028D01*
X3485474Y1981819D01*
Y1981403D01*
X3485164Y1981194D01*
G01X3429519Y2025986D02*
Y2038486D01*
X3435409D01*
G01X3433239Y2032444D02*
X3429519D01*
G01X3443004Y2038486D02*
X3446724D01*
G01X3444864D02*
Y2025986D01*
G01X3443004D02*
X3446724D01*
G01X3458194Y2032236D02*
X3461294D01*
Y2028486D01*
X3460364Y2027236D01*
X3459279Y2026403D01*
X3457729Y2025986D01*
X3456179Y2026403D01*
X3455094Y2027236D01*
X3454164Y2028486D01*
X3453544Y2029944D01*
X3453234Y2031611D01*
Y2033069D01*
X3453544Y2034319D01*
X3454164Y2035778D01*
X3455094Y2037028D01*
X3456024Y2037861D01*
X3457264Y2038486D01*
X3458349D01*
X3459589Y2038069D01*
X3460519Y2037236D01*
G01X3466254Y2038486D02*
Y2029528D01*
X3466874Y2027652D01*
X3468114Y2026403D01*
X3469664Y2025986D01*
X3471214Y2026403D01*
X3472454Y2027652D01*
X3473074Y2029528D01*
Y2038486D01*
G01X3478964Y2025986D02*
Y2038486D01*
X3482839D01*
X3484079Y2037861D01*
X3484854Y2037028D01*
X3485164Y2035361D01*
X3484854Y2033694D01*
X3483924Y2032653D01*
X3482839Y2032028D01*
X3478964D01*
G01X3482839D02*
X3485164Y2025986D01*
G01X3497564D02*
X3491364D01*
Y2038486D01*
X3497564D01*
G01X3495084Y2032444D02*
X3491364D01*
G01X3424440Y2396666D02*
Y2409166D01*
X3430330D01*
G01X3428160Y2403124D02*
X3424440D01*
G01X3437925Y2409166D02*
X3441645D01*
G01X3439785D02*
Y2396666D01*
G01X3437925D02*
X3441645D01*
G01X3453115Y2402916D02*
X3456215D01*
Y2399166D01*
X3455285Y2397916D01*
X3454200Y2397083D01*
X3452650Y2396666D01*
X3451100Y2397083D01*
X3450015Y2397916D01*
X3449085Y2399166D01*
X3448465Y2400624D01*
X3448155Y2402291D01*
Y2403749D01*
X3448465Y2404999D01*
X3449085Y2406458D01*
X3450015Y2407708D01*
X3450945Y2408541D01*
X3452185Y2409166D01*
X3453270D01*
X3454510Y2408749D01*
X3455440Y2407916D01*
G01X3461175Y2409166D02*
Y2400208D01*
X3461795Y2398332D01*
X3463035Y2397083D01*
X3464585Y2396666D01*
X3466135Y2397083D01*
X3467375Y2398332D01*
X3467995Y2400208D01*
Y2409166D01*
G01X3473885Y2396666D02*
Y2409166D01*
X3477760D01*
X3479000Y2408541D01*
X3479775Y2407708D01*
X3480085Y2406041D01*
X3479775Y2404374D01*
X3478845Y2403333D01*
X3477760Y2402708D01*
X3473885D01*
G01X3477760D02*
X3480085Y2396666D01*
G01X3492485D02*
X3486285D01*
Y2409166D01*
X3492485D01*
G01X3490005Y2403124D02*
X3486285D01*
G01X3603636Y2631265D02*
X3604256Y2631890D01*
X3604721Y2632931D01*
X3605031Y2634390D01*
X3604721Y2635640D01*
X3604101Y2636473D01*
X3603016Y2637098D01*
X3598831D01*
Y2624598D01*
X3603946D01*
X3605031Y2625431D01*
X3605651Y2626681D01*
X3605961Y2628140D01*
X3605651Y2629598D01*
X3604721Y2630848D01*
X3603636Y2631265D01*
X3598831D01*
G01X3610921Y2624598D02*
X3614796Y2637098D01*
X3618671Y2624598D01*
G01X3617276Y2628973D02*
X3612316D01*
G01X3630606Y2636056D02*
X3629676Y2636681D01*
X3628591Y2637098D01*
X3627351D01*
X3625956Y2636473D01*
X3624871Y2635431D01*
X3624096Y2634181D01*
X3623476Y2632098D01*
X3623321Y2630223D01*
X3623631Y2628348D01*
X3624096Y2627098D01*
X3625026Y2625848D01*
X3626111Y2625015D01*
X3627196Y2624598D01*
X3628281D01*
X3629366Y2625015D01*
X3630296Y2625639D01*
X3631071Y2626473D01*
G01X3636186Y2624598D02*
Y2637098D01*
G01X3642076D02*
X3636186Y2629389D01*
G01X3643006Y2624598D02*
X3638821Y2632931D01*
G01X3648586Y2624598D02*
Y2637098D01*
X3651686D01*
X3652926Y2636473D01*
X3653856Y2635640D01*
X3654631Y2634390D01*
X3655251Y2632931D01*
X3655406Y2630848D01*
X3655251Y2628765D01*
X3654631Y2627306D01*
X3653856Y2626056D01*
X3652926Y2625223D01*
X3651686Y2624598D01*
X3648586D01*
G01X3661296D02*
Y2637098D01*
X3665171D01*
X3666411Y2636473D01*
X3667186Y2635640D01*
X3667496Y2633973D01*
X3667186Y2632306D01*
X3666256Y2631265D01*
X3665171Y2630640D01*
X3661296D01*
G01X3665171D02*
X3667496Y2624598D01*
G01X3674936Y2637098D02*
X3678656D01*
G01X3676796D02*
Y2624598D01*
G01X3674936D02*
X3678656D01*
G01X3686096Y2637098D02*
Y2624598D01*
X3692296D01*
G01X3698496Y2637098D02*
Y2624598D01*
X3704696D01*
G01X3723141Y2626264D02*
X3724381Y2625223D01*
X3725776Y2624598D01*
X3727016D01*
X3728256Y2625223D01*
X3729186Y2626264D01*
X3729651Y2627723D01*
X3729341Y2629181D01*
X3728566Y2630431D01*
X3727171Y2631265D01*
X3725311Y2631681D01*
X3724226Y2632515D01*
X3723761Y2633973D01*
X3724071Y2635431D01*
X3724846Y2636473D01*
X3725931Y2637098D01*
X3727016D01*
X3728101Y2636681D01*
X3729031Y2635640D01*
G01X3738796Y2637098D02*
Y2624598D01*
G01X3735231Y2637098D02*
X3742361D01*
G01X3747786D02*
Y2628140D01*
X3748406Y2626264D01*
X3749646Y2625015D01*
X3751196Y2624598D01*
X3752746Y2625015D01*
X3753986Y2626264D01*
X3754606Y2628140D01*
Y2637098D01*
G01X3764836Y2631265D02*
X3765456Y2631890D01*
X3765921Y2632931D01*
X3766231Y2634390D01*
X3765921Y2635640D01*
X3765301Y2636473D01*
X3764216Y2637098D01*
X3760031D01*
Y2624598D01*
X3765146D01*
X3766231Y2625431D01*
X3766851Y2626681D01*
X3767161Y2628140D01*
X3766851Y2629598D01*
X3765921Y2630848D01*
X3764836Y2631265D01*
X3760031D01*
G01X3785296Y2637098D02*
Y2624598D01*
X3791496D01*
G01X3803896D02*
X3797696D01*
Y2637098D01*
X3803896D01*
G01X3801416Y2631056D02*
X3797696D01*
G01X3809631Y2624598D02*
Y2637098D01*
X3816761Y2624598D01*
Y2637098D01*
G01X3826526Y2630848D02*
X3829626D01*
Y2627098D01*
X3828696Y2625848D01*
X3827611Y2625015D01*
X3826061Y2624598D01*
X3824511Y2625015D01*
X3823426Y2625848D01*
X3822496Y2627098D01*
X3821876Y2628556D01*
X3821566Y2630223D01*
Y2631681D01*
X3821876Y2632931D01*
X3822496Y2634390D01*
X3823426Y2635640D01*
X3824356Y2636473D01*
X3825596Y2637098D01*
X3826681D01*
X3827921Y2636681D01*
X3828851Y2635848D01*
G01X3837996Y2637098D02*
Y2624598D01*
G01X3834431Y2637098D02*
X3841561D01*
G01X3847141Y2624598D02*
Y2637098D01*
G01X3853651D02*
Y2624598D01*
G01Y2630848D02*
X3847141D01*
G01X3875196Y2637098D02*
Y2624598D01*
G01X3871631Y2637098D02*
X3878761D01*
G01X3887596Y2624598D02*
X3886356Y2624806D01*
X3885271Y2625639D01*
X3884341Y2626890D01*
X3883721Y2628348D01*
X3883411Y2630015D01*
Y2631681D01*
X3883721Y2633348D01*
X3884341Y2634806D01*
X3885271Y2636056D01*
X3886356Y2636890D01*
X3887596Y2637098D01*
X3888836Y2636890D01*
X3889921Y2636056D01*
X3890851Y2634806D01*
X3891471Y2633348D01*
X3891781Y2631681D01*
Y2630015D01*
X3891471Y2628348D01*
X3890851Y2626890D01*
X3889921Y2625639D01*
X3888836Y2624806D01*
X3887596Y2624598D01*
G01X3896896Y2637098D02*
Y2624598D01*
X3903096D01*
G01X3915496D02*
X3909296D01*
Y2637098D01*
X3915496D01*
G01X3913016Y2631056D02*
X3909296D01*
G01X3921696Y2624598D02*
Y2637098D01*
X3925571D01*
X3926811Y2636473D01*
X3927586Y2635640D01*
X3927896Y2633973D01*
X3927586Y2632306D01*
X3926656Y2631265D01*
X3925571Y2630640D01*
X3921696D01*
G01X3925571D02*
X3927896Y2624598D01*
G01X3933321D02*
X3937196Y2637098D01*
X3941071Y2624598D01*
G01X3939676Y2628973D02*
X3934716D01*
G01X3946031Y2624598D02*
Y2637098D01*
X3953161Y2624598D01*
Y2637098D01*
G01X3965406Y2636056D02*
X3964476Y2636681D01*
X3963391Y2637098D01*
X3962151D01*
X3960756Y2636473D01*
X3959671Y2635431D01*
X3958896Y2634181D01*
X3958276Y2632098D01*
X3958121Y2630223D01*
X3958431Y2628348D01*
X3958896Y2627098D01*
X3959826Y2625848D01*
X3960911Y2625015D01*
X3961996Y2624598D01*
X3963081D01*
X3964166Y2625015D01*
X3965096Y2625639D01*
X3965871Y2626473D01*
G01X3977496Y2624598D02*
X3971296D01*
Y2637098D01*
X3977496D01*
G01X3975016Y2631056D02*
X3971296D01*
G01X3999196Y2637098D02*
Y2624598D01*
G01X3995631Y2637098D02*
X4002761D01*
G01X4011596Y2624598D02*
X4010356Y2624806D01*
X4009271Y2625639D01*
X4008341Y2626890D01*
X4007721Y2628348D01*
X4007411Y2630015D01*
Y2631681D01*
X4007721Y2633348D01*
X4008341Y2634806D01*
X4009271Y2636056D01*
X4010356Y2636890D01*
X4011596Y2637098D01*
X4012836Y2636890D01*
X4013921Y2636056D01*
X4014851Y2634806D01*
X4015471Y2633348D01*
X4015781Y2631681D01*
Y2630015D01*
X4015471Y2628348D01*
X4014851Y2626890D01*
X4013921Y2625639D01*
X4012836Y2624806D01*
X4011596Y2624598D01*
G01X4037636Y2631265D02*
X4038256Y2631890D01*
X4038721Y2632931D01*
X4039031Y2634390D01*
X4038721Y2635640D01*
X4038101Y2636473D01*
X4037016Y2637098D01*
X4032831D01*
Y2624598D01*
X4037946D01*
X4039031Y2625431D01*
X4039651Y2626681D01*
X4039961Y2628140D01*
X4039651Y2629598D01*
X4038721Y2630848D01*
X4037636Y2631265D01*
X4032831D01*
G01X4051896Y2624598D02*
X4045696D01*
Y2637098D01*
X4051896D01*
G01X4049416Y2631056D02*
X4045696D01*
G01X4073286Y2624598D02*
X4073596Y2627306D01*
X4074061Y2629598D01*
X4074681Y2631681D01*
X4075456Y2633973D01*
X4076696Y2637098D01*
X4070496D01*
G01X4096691Y2628765D02*
X4100411D01*
G01X4098396Y2631473D02*
Y2626056D01*
G01X4108006Y2624181D02*
X4113586Y2637098D01*
G01X4121181Y2628765D02*
X4125211D01*
G01X4132186Y2626473D02*
X4133116Y2625431D01*
X4134201Y2624806D01*
X4135596Y2624598D01*
X4136991Y2625015D01*
X4138076Y2625848D01*
X4138851Y2627306D01*
X4139006Y2628973D01*
X4138696Y2630640D01*
X4137921Y2631681D01*
X4136836Y2632515D01*
X4135751Y2632723D01*
X4134666Y2632515D01*
X4133271Y2631681D01*
X4133736Y2637098D01*
X4137921D01*
G01X4156366Y2624598D02*
Y2637098D01*
X4160396Y2626681D01*
X4164426Y2637098D01*
Y2624598D01*
G01X4170936Y2637098D02*
X4174656D01*
G01X4172796D02*
Y2624598D01*
G01X4170936D02*
X4174656D01*
G01X4182096Y2637098D02*
Y2624598D01*
X4188296D01*
G01X4194341Y2626264D02*
X4195581Y2625223D01*
X4196976Y2624598D01*
X4198216D01*
X4199456Y2625223D01*
X4200386Y2626264D01*
X4200851Y2627723D01*
X4200541Y2629181D01*
X4199766Y2630431D01*
X4198371Y2631265D01*
X4196511Y2631681D01*
X4195426Y2632515D01*
X4194961Y2633973D01*
X4195271Y2635431D01*
X4196046Y2636473D01*
X4197131Y2637098D01*
X4198216D01*
X4199301Y2636681D01*
X4200231Y2635640D01*
G01X3439181Y2647515D02*
X3443211D01*
G01X3461966Y2643348D02*
Y2655848D01*
X3465996Y2645431D01*
X3470026Y2655848D01*
Y2643348D01*
G01X3475451D02*
Y2655848D01*
X3481341D01*
G01X3479171Y2649806D02*
X3475451D01*
G01X3491726Y2649598D02*
X3494826D01*
Y2645848D01*
X3493896Y2644598D01*
X3492811Y2643765D01*
X3491261Y2643348D01*
X3489711Y2643765D01*
X3488626Y2644598D01*
X3487696Y2645848D01*
X3487076Y2647306D01*
X3486766Y2648973D01*
Y2650431D01*
X3487076Y2651681D01*
X3487696Y2653140D01*
X3488626Y2654390D01*
X3489556Y2655223D01*
X3490796Y2655848D01*
X3491881D01*
X3493121Y2655431D01*
X3494051Y2654598D01*
G01X3498546Y2639181D02*
X3507846D01*
G01X3512341Y2645014D02*
X3513581Y2643973D01*
X3514976Y2643348D01*
X3516216D01*
X3517456Y2643973D01*
X3518386Y2645014D01*
X3518851Y2646473D01*
X3518541Y2647931D01*
X3517766Y2649181D01*
X3516371Y2650015D01*
X3514511Y2650431D01*
X3513426Y2651265D01*
X3512961Y2652723D01*
X3513271Y2654181D01*
X3514046Y2655223D01*
X3515131Y2655848D01*
X3516216D01*
X3517301Y2655431D01*
X3518231Y2654390D01*
G01X3527996Y2655848D02*
Y2643348D01*
G01X3524431Y2655848D02*
X3531561D01*
G01X3536986D02*
Y2646890D01*
X3537606Y2645014D01*
X3538846Y2643765D01*
X3540396Y2643348D01*
X3541946Y2643765D01*
X3543186Y2645014D01*
X3543806Y2646890D01*
Y2655848D01*
G01X3554036Y2650015D02*
X3554656Y2650640D01*
X3555121Y2651681D01*
X3555431Y2653140D01*
X3555121Y2654390D01*
X3554501Y2655223D01*
X3553416Y2655848D01*
X3549231D01*
Y2643348D01*
X3554346D01*
X3555431Y2644181D01*
X3556051Y2645431D01*
X3556361Y2646890D01*
X3556051Y2648348D01*
X3555121Y2649598D01*
X3554036Y2650015D01*
X3549231D01*
G01X3577596Y2642931D02*
X3577286Y2643140D01*
Y2643556D01*
X3577596Y2643765D01*
X3577906Y2643556D01*
Y2643140D01*
X3577596Y2642931D01*
G01Y2648556D02*
X3577286Y2648765D01*
Y2649181D01*
X3577596Y2649390D01*
X3577906Y2649181D01*
Y2648765D01*
X3577596Y2648556D01*
G01X3598366Y2643348D02*
Y2655848D01*
X3602396Y2645431D01*
X3606426Y2655848D01*
Y2643348D01*
G01X3610921D02*
X3614796Y2655848D01*
X3618671Y2643348D01*
G01X3617276Y2647723D02*
X3612316D01*
G01X3623631Y2643348D02*
Y2655848D01*
X3630761Y2643348D01*
Y2655848D01*
G01X3636186D02*
Y2646890D01*
X3636806Y2645014D01*
X3638046Y2643765D01*
X3639596Y2643348D01*
X3641146Y2643765D01*
X3642386Y2645014D01*
X3643006Y2646890D01*
Y2655848D01*
G01X3649051Y2643348D02*
Y2655848D01*
X3654941D01*
G01X3652771Y2649806D02*
X3649051D01*
G01X3660521Y2643348D02*
X3664396Y2655848D01*
X3668271Y2643348D01*
G01X3666876Y2647723D02*
X3661916D01*
G01X3680206Y2654806D02*
X3679276Y2655431D01*
X3678191Y2655848D01*
X3676951D01*
X3675556Y2655223D01*
X3674471Y2654181D01*
X3673696Y2652931D01*
X3673076Y2650848D01*
X3672921Y2648973D01*
X3673231Y2647098D01*
X3673696Y2645848D01*
X3674626Y2644598D01*
X3675711Y2643765D01*
X3676796Y2643348D01*
X3677881D01*
X3678966Y2643765D01*
X3679896Y2644389D01*
X3680671Y2645223D01*
G01X3689196Y2655848D02*
Y2643348D01*
G01X3685631Y2655848D02*
X3692761D01*
G01X3698186D02*
Y2646890D01*
X3698806Y2645014D01*
X3700046Y2643765D01*
X3701596Y2643348D01*
X3703146Y2643765D01*
X3704386Y2645014D01*
X3705006Y2646890D01*
Y2655848D01*
G01X3710896Y2643348D02*
Y2655848D01*
X3714771D01*
X3716011Y2655223D01*
X3716786Y2654390D01*
X3717096Y2652723D01*
X3716786Y2651056D01*
X3715856Y2650015D01*
X3714771Y2649390D01*
X3710896D01*
G01X3714771D02*
X3717096Y2643348D01*
G01X3724536Y2655848D02*
X3728256D01*
G01X3726396D02*
Y2643348D01*
G01X3724536D02*
X3728256D01*
G01X3735231D02*
Y2655848D01*
X3742361Y2643348D01*
Y2655848D01*
G01X3752126Y2649598D02*
X3755226D01*
Y2645848D01*
X3754296Y2644598D01*
X3753211Y2643765D01*
X3751661Y2643348D01*
X3750111Y2643765D01*
X3749026Y2644598D01*
X3748096Y2645848D01*
X3747476Y2647306D01*
X3747166Y2648973D01*
Y2650431D01*
X3747476Y2651681D01*
X3748096Y2653140D01*
X3749026Y2654390D01*
X3749956Y2655223D01*
X3751196Y2655848D01*
X3752281D01*
X3753521Y2655431D01*
X3754451Y2654598D01*
G01X3772741Y2645014D02*
X3773981Y2643973D01*
X3775376Y2643348D01*
X3776616D01*
X3777856Y2643973D01*
X3778786Y2645014D01*
X3779251Y2646473D01*
X3778941Y2647931D01*
X3778166Y2649181D01*
X3776771Y2650015D01*
X3774911Y2650431D01*
X3773826Y2651265D01*
X3773361Y2652723D01*
X3773671Y2654181D01*
X3774446Y2655223D01*
X3775531Y2655848D01*
X3776616D01*
X3777701Y2655431D01*
X3778631Y2654390D01*
G01X3788396Y2655848D02*
Y2643348D01*
G01X3784831Y2655848D02*
X3791961D01*
G01X3797386D02*
Y2646890D01*
X3798006Y2645014D01*
X3799246Y2643765D01*
X3800796Y2643348D01*
X3802346Y2643765D01*
X3803586Y2645014D01*
X3804206Y2646890D01*
Y2655848D01*
G01X3814436Y2650015D02*
X3815056Y2650640D01*
X3815521Y2651681D01*
X3815831Y2653140D01*
X3815521Y2654390D01*
X3814901Y2655223D01*
X3813816Y2655848D01*
X3809631D01*
Y2643348D01*
X3814746D01*
X3815831Y2644181D01*
X3816451Y2645431D01*
X3816761Y2646890D01*
X3816451Y2648348D01*
X3815521Y2649598D01*
X3814436Y2650015D01*
X3809631D01*
G01X3834896Y2655848D02*
Y2643348D01*
X3841096D01*
G01X3853496D02*
X3847296D01*
Y2655848D01*
X3853496D01*
G01X3851016Y2649806D02*
X3847296D01*
G01X3859231Y2643348D02*
Y2655848D01*
X3866361Y2643348D01*
Y2655848D01*
G01X3876126Y2649598D02*
X3879226D01*
Y2645848D01*
X3878296Y2644598D01*
X3877211Y2643765D01*
X3875661Y2643348D01*
X3874111Y2643765D01*
X3873026Y2644598D01*
X3872096Y2645848D01*
X3871476Y2647306D01*
X3871166Y2648973D01*
Y2650431D01*
X3871476Y2651681D01*
X3872096Y2653140D01*
X3873026Y2654390D01*
X3873956Y2655223D01*
X3875196Y2655848D01*
X3876281D01*
X3877521Y2655431D01*
X3878451Y2654598D01*
G01X3887596Y2655848D02*
Y2643348D01*
G01X3884031Y2655848D02*
X3891161D01*
G01X3896741Y2643348D02*
Y2655848D01*
G01X3903251D02*
Y2643348D01*
G01Y2649598D02*
X3896741D01*
G01X3599141Y2663764D02*
X3600381Y2662723D01*
X3601776Y2662098D01*
X3603016D01*
X3604256Y2662723D01*
X3605186Y2663764D01*
X3605651Y2665223D01*
X3605341Y2666681D01*
X3604566Y2667931D01*
X3603171Y2668765D01*
X3601311Y2669181D01*
X3600226Y2670015D01*
X3599761Y2671473D01*
X3600071Y2672931D01*
X3600846Y2673973D01*
X3601931Y2674598D01*
X3603016D01*
X3604101Y2674181D01*
X3605031Y2673140D01*
G01X3611386Y2674598D02*
Y2665640D01*
X3612006Y2663764D01*
X3613246Y2662515D01*
X3614796Y2662098D01*
X3616346Y2662515D01*
X3617586Y2663764D01*
X3618206Y2665640D01*
Y2674598D01*
G01X3624096Y2662098D02*
Y2674598D01*
X3627971D01*
X3629211Y2673973D01*
X3629986Y2673140D01*
X3630296Y2671473D01*
X3629986Y2669806D01*
X3629056Y2668765D01*
X3627971Y2668140D01*
X3624096D01*
G01X3627971D02*
X3630296Y2662098D01*
G01X3636651D02*
Y2674598D01*
X3642541D01*
G01X3640371Y2668556D02*
X3636651D01*
G01X3648121Y2662098D02*
X3651996Y2674598D01*
X3655871Y2662098D01*
G01X3654476Y2666473D02*
X3649516D01*
G01X3667806Y2673556D02*
X3666876Y2674181D01*
X3665791Y2674598D01*
X3664551D01*
X3663156Y2673973D01*
X3662071Y2672931D01*
X3661296Y2671681D01*
X3660676Y2669598D01*
X3660521Y2667723D01*
X3660831Y2665848D01*
X3661296Y2664598D01*
X3662226Y2663348D01*
X3663311Y2662515D01*
X3664396Y2662098D01*
X3665481D01*
X3666566Y2662515D01*
X3667496Y2663139D01*
X3668271Y2663973D01*
G01X3679896Y2662098D02*
X3673696D01*
Y2674598D01*
X3679896D01*
G01X3677416Y2668556D02*
X3673696D01*
G01X3701596Y2662098D02*
X3700356Y2662306D01*
X3699271Y2663139D01*
X3698341Y2664390D01*
X3697721Y2665848D01*
X3697411Y2667515D01*
Y2669181D01*
X3697721Y2670848D01*
X3698341Y2672306D01*
X3699271Y2673556D01*
X3700356Y2674390D01*
X3701596Y2674598D01*
X3702836Y2674390D01*
X3703921Y2673556D01*
X3704851Y2672306D01*
X3705471Y2670848D01*
X3705781Y2669181D01*
Y2667515D01*
X3705471Y2665848D01*
X3704851Y2664390D01*
X3703921Y2663139D01*
X3702836Y2662306D01*
X3701596Y2662098D01*
G01X3711051D02*
Y2674598D01*
X3716941D01*
G01X3714771Y2668556D02*
X3711051D01*
G01X3734766Y2662098D02*
Y2674598D01*
X3738796Y2664181D01*
X3742826Y2674598D01*
Y2662098D01*
G01X3747786Y2674598D02*
Y2665640D01*
X3748406Y2663764D01*
X3749646Y2662515D01*
X3751196Y2662098D01*
X3752746Y2662515D01*
X3753986Y2663764D01*
X3754606Y2665640D01*
Y2674598D01*
G01X3760341Y2663764D02*
X3761581Y2662723D01*
X3762976Y2662098D01*
X3764216D01*
X3765456Y2662723D01*
X3766386Y2663764D01*
X3766851Y2665223D01*
X3766541Y2666681D01*
X3765766Y2667931D01*
X3764371Y2668765D01*
X3762511Y2669181D01*
X3761426Y2670015D01*
X3760961Y2671473D01*
X3761271Y2672931D01*
X3762046Y2673973D01*
X3763131Y2674598D01*
X3764216D01*
X3765301Y2674181D01*
X3766231Y2673140D01*
G01X3775996Y2674598D02*
Y2662098D01*
G01X3772431Y2674598D02*
X3779561D01*
G01X3786381Y2666265D02*
X3790411D01*
G01X3797231Y2662098D02*
Y2674598D01*
X3804361Y2662098D01*
Y2674598D01*
G01X3813196Y2662098D02*
X3811956Y2662306D01*
X3810871Y2663139D01*
X3809941Y2664390D01*
X3809321Y2665848D01*
X3809011Y2667515D01*
Y2669181D01*
X3809321Y2670848D01*
X3809941Y2672306D01*
X3810871Y2673556D01*
X3811956Y2674390D01*
X3813196Y2674598D01*
X3814436Y2674390D01*
X3815521Y2673556D01*
X3816451Y2672306D01*
X3817071Y2670848D01*
X3817381Y2669181D01*
Y2667515D01*
X3817071Y2665848D01*
X3816451Y2664390D01*
X3815521Y2663139D01*
X3814436Y2662306D01*
X3813196Y2662098D01*
G01X3825596Y2674598D02*
Y2662098D01*
G01X3822031Y2674598D02*
X3829161D01*
G01X3835981Y2666265D02*
X3840011D01*
G01X3853806Y2673556D02*
X3852876Y2674181D01*
X3851791Y2674598D01*
X3850551D01*
X3849156Y2673973D01*
X3848071Y2672931D01*
X3847296Y2671681D01*
X3846676Y2669598D01*
X3846521Y2667723D01*
X3846831Y2665848D01*
X3847296Y2664598D01*
X3848226Y2663348D01*
X3849311Y2662515D01*
X3850396Y2662098D01*
X3851481D01*
X3852566Y2662515D01*
X3853496Y2663139D01*
X3854271Y2663973D01*
G01X3859386Y2674598D02*
Y2665640D01*
X3860006Y2663764D01*
X3861246Y2662515D01*
X3862796Y2662098D01*
X3864346Y2662515D01*
X3865586Y2663764D01*
X3866206Y2665640D01*
Y2674598D01*
G01X3875196D02*
Y2662098D01*
G01X3871631Y2674598D02*
X3878761D01*
G01X3885581Y2666265D02*
X3889611D01*
G01X3896896Y2674598D02*
Y2662098D01*
X3903096D01*
G01X3908521D02*
X3912396Y2674598D01*
X3916271Y2662098D01*
G01X3914876Y2666473D02*
X3909916D01*
G01X3924796Y2662098D02*
Y2667723D01*
X3921696Y2674598D01*
G01X3927896D02*
X3924796Y2667723D01*
G01X3940296Y2662098D02*
X3934096D01*
Y2674598D01*
X3940296D01*
G01X3937816Y2668556D02*
X3934096D01*
G01X3946496Y2662098D02*
Y2674598D01*
X3950371D01*
X3951611Y2673973D01*
X3952386Y2673140D01*
X3952696Y2671473D01*
X3952386Y2669806D01*
X3951456Y2668765D01*
X3950371Y2668140D01*
X3946496D01*
G01X3950371D02*
X3952696Y2662098D01*
G01X3439181Y2685015D02*
X3443211D01*
G01X3461966Y2680848D02*
Y2693348D01*
X3465996Y2682931D01*
X3470026Y2693348D01*
Y2680848D01*
G01X3474521D02*
X3478396Y2693348D01*
X3482271Y2680848D01*
G01X3480876Y2685223D02*
X3475916D01*
G01X3487541Y2680848D02*
X3494051Y2693348D01*
G01X3487541D02*
X3494051Y2680848D01*
G01X3498546Y2676681D02*
X3507846D01*
G01X3512186Y2680848D02*
Y2693348D01*
X3515286D01*
X3516526Y2692723D01*
X3517456Y2691890D01*
X3518231Y2690640D01*
X3518851Y2689181D01*
X3519006Y2687098D01*
X3518851Y2685015D01*
X3518231Y2683556D01*
X3517456Y2682306D01*
X3516526Y2681473D01*
X3515286Y2680848D01*
X3512186D01*
G01X3531096D02*
X3524896D01*
Y2693348D01*
X3531096D01*
G01X3528616Y2687306D02*
X3524896D01*
G01X3537296Y2680848D02*
Y2693348D01*
X3541016D01*
X3542256Y2692723D01*
X3543186Y2691265D01*
X3543496Y2689598D01*
X3543186Y2687931D01*
X3542411Y2686681D01*
X3541016Y2686056D01*
X3537296D01*
G01X3552796Y2693348D02*
Y2680848D01*
G01X3549231Y2693348D02*
X3556361D01*
G01X3561941Y2680848D02*
Y2693348D01*
G01X3568451D02*
Y2680848D01*
G01Y2687098D02*
X3561941D01*
G01X3577596Y2680431D02*
X3577286Y2680640D01*
Y2681056D01*
X3577596Y2681265D01*
X3577906Y2681056D01*
Y2680640D01*
X3577596Y2680431D01*
G01Y2686056D02*
X3577286Y2686265D01*
Y2686681D01*
X3577596Y2686890D01*
X3577906Y2686681D01*
Y2686265D01*
X3577596Y2686056D01*
G01X3598986Y2680848D02*
Y2693348D01*
X3602086D01*
X3603326Y2692723D01*
X3604256Y2691890D01*
X3605031Y2690640D01*
X3605651Y2689181D01*
X3605806Y2687098D01*
X3605651Y2685015D01*
X3605031Y2683556D01*
X3604256Y2682306D01*
X3603326Y2681473D01*
X3602086Y2680848D01*
X3598986D01*
G01X3617896D02*
X3611696D01*
Y2693348D01*
X3617896D01*
G01X3615416Y2687306D02*
X3611696D01*
G01X3624096Y2680848D02*
Y2693348D01*
X3627816D01*
X3629056Y2692723D01*
X3629986Y2691265D01*
X3630296Y2689598D01*
X3629986Y2687931D01*
X3629211Y2686681D01*
X3627816Y2686056D01*
X3624096D01*
G01X3639596Y2693348D02*
Y2680848D01*
G01X3636031Y2693348D02*
X3643161D01*
G01X3648741Y2680848D02*
Y2693348D01*
G01X3655251D02*
Y2680848D01*
G01Y2687098D02*
X3648741D01*
G01X3673851Y2680848D02*
Y2693348D01*
X3679741D01*
G01X3677571Y2687306D02*
X3673851D01*
G01X3686096Y2680848D02*
Y2693348D01*
X3689971D01*
X3691211Y2692723D01*
X3691986Y2691890D01*
X3692296Y2690223D01*
X3691986Y2688556D01*
X3691056Y2687515D01*
X3689971Y2686890D01*
X3686096D01*
G01X3689971D02*
X3692296Y2680848D01*
G01X3701596D02*
X3700356Y2681056D01*
X3699271Y2681889D01*
X3698341Y2683140D01*
X3697721Y2684598D01*
X3697411Y2686265D01*
Y2687931D01*
X3697721Y2689598D01*
X3698341Y2691056D01*
X3699271Y2692306D01*
X3700356Y2693140D01*
X3701596Y2693348D01*
X3702836Y2693140D01*
X3703921Y2692306D01*
X3704851Y2691056D01*
X3705471Y2689598D01*
X3705781Y2687931D01*
Y2686265D01*
X3705471Y2684598D01*
X3704851Y2683140D01*
X3703921Y2681889D01*
X3702836Y2681056D01*
X3701596Y2680848D01*
G01X3709966D02*
Y2693348D01*
X3713996Y2682931D01*
X3718026Y2693348D01*
Y2680848D01*
G01X3735541Y2682514D02*
X3736781Y2681473D01*
X3738176Y2680848D01*
X3739416D01*
X3740656Y2681473D01*
X3741586Y2682514D01*
X3742051Y2683973D01*
X3741741Y2685431D01*
X3740966Y2686681D01*
X3739571Y2687515D01*
X3737711Y2687931D01*
X3736626Y2688765D01*
X3736161Y2690223D01*
X3736471Y2691681D01*
X3737246Y2692723D01*
X3738331Y2693348D01*
X3739416D01*
X3740501Y2692931D01*
X3741431Y2691890D01*
G01X3751196Y2693348D02*
Y2680848D01*
G01X3747631Y2693348D02*
X3754761D01*
G01X3759721Y2680848D02*
X3763596Y2693348D01*
X3767471Y2680848D01*
G01X3766076Y2685223D02*
X3761116D01*
G01X3772896Y2680848D02*
Y2693348D01*
X3776771D01*
X3778011Y2692723D01*
X3778786Y2691890D01*
X3779096Y2690223D01*
X3778786Y2688556D01*
X3777856Y2687515D01*
X3776771Y2686890D01*
X3772896D01*
G01X3776771D02*
X3779096Y2680848D01*
G01X3788396Y2693348D02*
Y2680848D01*
G01X3784831Y2693348D02*
X3791961D01*
G01X3810096D02*
Y2680848D01*
X3816296D01*
G01X3821721D02*
X3825596Y2693348D01*
X3829471Y2680848D01*
G01X3828076Y2685223D02*
X3823116D01*
G01X3837996Y2680848D02*
Y2686473D01*
X3834896Y2693348D01*
G01X3841096D02*
X3837996Y2686473D01*
G01X3853496Y2680848D02*
X3847296D01*
Y2693348D01*
X3853496D01*
G01X3851016Y2687306D02*
X3847296D01*
G01X3859696Y2680848D02*
Y2693348D01*
X3863571D01*
X3864811Y2692723D01*
X3865586Y2691890D01*
X3865896Y2690223D01*
X3865586Y2688556D01*
X3864656Y2687515D01*
X3863571Y2686890D01*
X3859696D01*
G01X3863571D02*
X3865896Y2680848D01*
G01X3887596Y2693348D02*
Y2680848D01*
G01X3884031Y2693348D02*
X3891161D01*
G01X3899996Y2680848D02*
X3898756Y2681056D01*
X3897671Y2681889D01*
X3896741Y2683140D01*
X3896121Y2684598D01*
X3895811Y2686265D01*
Y2687931D01*
X3896121Y2689598D01*
X3896741Y2691056D01*
X3897671Y2692306D01*
X3898756Y2693140D01*
X3899996Y2693348D01*
X3901236Y2693140D01*
X3902321Y2692306D01*
X3903251Y2691056D01*
X3903871Y2689598D01*
X3904181Y2687931D01*
Y2686265D01*
X3903871Y2684598D01*
X3903251Y2683140D01*
X3902321Y2681889D01*
X3901236Y2681056D01*
X3899996Y2680848D01*
G01X3924796Y2693348D02*
Y2680848D01*
G01X3921231Y2693348D02*
X3928361D01*
G01X3933941Y2680848D02*
Y2693348D01*
G01X3940451D02*
Y2680848D01*
G01Y2687098D02*
X3933941D01*
G01X3952696Y2680848D02*
X3946496D01*
Y2693348D01*
X3952696D01*
G01X3950216Y2687306D02*
X3946496D01*
G01X3439181Y2703765D02*
X3443211D01*
G01X3461966Y2699598D02*
Y2712098D01*
X3465996Y2701681D01*
X3470026Y2712098D01*
Y2699598D01*
G01X3474831D02*
Y2712098D01*
X3481961Y2699598D01*
Y2712098D01*
G01X3494206Y2711056D02*
X3493276Y2711681D01*
X3492191Y2712098D01*
X3490951D01*
X3489556Y2711473D01*
X3488471Y2710431D01*
X3487696Y2709181D01*
X3487076Y2707098D01*
X3486921Y2705223D01*
X3487231Y2703348D01*
X3487696Y2702098D01*
X3488626Y2700848D01*
X3489711Y2700015D01*
X3490796Y2699598D01*
X3491881D01*
X3492966Y2700015D01*
X3493896Y2700639D01*
X3494671Y2701473D01*
G01X3498546Y2695431D02*
X3507846D01*
G01X3512496Y2712098D02*
Y2699598D01*
X3518696D01*
G01X3524121D02*
X3527996Y2712098D01*
X3531871Y2699598D01*
G01X3530476Y2703973D02*
X3525516D01*
G01X3540396Y2699598D02*
Y2705223D01*
X3537296Y2712098D01*
G01X3543496D02*
X3540396Y2705223D01*
G01X3555896Y2699598D02*
X3549696D01*
Y2712098D01*
X3555896D01*
G01X3553416Y2706056D02*
X3549696D01*
G01X3562096Y2699598D02*
Y2712098D01*
X3565971D01*
X3567211Y2711473D01*
X3567986Y2710640D01*
X3568296Y2708973D01*
X3567986Y2707306D01*
X3567056Y2706265D01*
X3565971Y2705640D01*
X3562096D01*
G01X3565971D02*
X3568296Y2699598D01*
G01X3577596Y2699181D02*
X3577286Y2699390D01*
Y2699806D01*
X3577596Y2700015D01*
X3577906Y2699806D01*
Y2699390D01*
X3577596Y2699181D01*
G01Y2704806D02*
X3577286Y2705015D01*
Y2705431D01*
X3577596Y2705640D01*
X3577906Y2705431D01*
Y2705015D01*
X3577596Y2704806D01*
G01X3598366Y2699598D02*
Y2712098D01*
X3602396Y2701681D01*
X3606426Y2712098D01*
Y2699598D01*
G01X3611386Y2712098D02*
Y2703140D01*
X3612006Y2701264D01*
X3613246Y2700015D01*
X3614796Y2699598D01*
X3616346Y2700015D01*
X3617586Y2701264D01*
X3618206Y2703140D01*
Y2712098D01*
G01X3623941Y2701264D02*
X3625181Y2700223D01*
X3626576Y2699598D01*
X3627816D01*
X3629056Y2700223D01*
X3629986Y2701264D01*
X3630451Y2702723D01*
X3630141Y2704181D01*
X3629366Y2705431D01*
X3627971Y2706265D01*
X3626111Y2706681D01*
X3625026Y2707515D01*
X3624561Y2708973D01*
X3624871Y2710431D01*
X3625646Y2711473D01*
X3626731Y2712098D01*
X3627816D01*
X3628901Y2711681D01*
X3629831Y2710640D01*
G01X3639596Y2712098D02*
Y2699598D01*
G01X3636031Y2712098D02*
X3643161D01*
G01X3649981Y2703765D02*
X3654011D01*
G01X3660831Y2699598D02*
Y2712098D01*
X3667961Y2699598D01*
Y2712098D01*
G01X3676796Y2699598D02*
X3675556Y2699806D01*
X3674471Y2700639D01*
X3673541Y2701890D01*
X3672921Y2703348D01*
X3672611Y2705015D01*
Y2706681D01*
X3672921Y2708348D01*
X3673541Y2709806D01*
X3674471Y2711056D01*
X3675556Y2711890D01*
X3676796Y2712098D01*
X3678036Y2711890D01*
X3679121Y2711056D01*
X3680051Y2709806D01*
X3680671Y2708348D01*
X3680981Y2706681D01*
Y2705015D01*
X3680671Y2703348D01*
X3680051Y2701890D01*
X3679121Y2700639D01*
X3678036Y2699806D01*
X3676796Y2699598D01*
G01X3689196Y2712098D02*
Y2699598D01*
G01X3685631Y2712098D02*
X3692761D01*
G01X3699581Y2703765D02*
X3703611D01*
G01X3717406Y2711056D02*
X3716476Y2711681D01*
X3715391Y2712098D01*
X3714151D01*
X3712756Y2711473D01*
X3711671Y2710431D01*
X3710896Y2709181D01*
X3710276Y2707098D01*
X3710121Y2705223D01*
X3710431Y2703348D01*
X3710896Y2702098D01*
X3711826Y2700848D01*
X3712911Y2700015D01*
X3713996Y2699598D01*
X3715081D01*
X3716166Y2700015D01*
X3717096Y2700639D01*
X3717871Y2701473D01*
G01X3722986Y2712098D02*
Y2703140D01*
X3723606Y2701264D01*
X3724846Y2700015D01*
X3726396Y2699598D01*
X3727946Y2700015D01*
X3729186Y2701264D01*
X3729806Y2703140D01*
Y2712098D01*
G01X3738796D02*
Y2699598D01*
G01X3735231Y2712098D02*
X3742361D01*
G01X3749181Y2703765D02*
X3753211D01*
G01X3760496Y2712098D02*
Y2699598D01*
X3766696D01*
G01X3772121D02*
X3775996Y2712098D01*
X3779871Y2699598D01*
G01X3778476Y2703973D02*
X3773516D01*
G01X3788396Y2699598D02*
Y2705223D01*
X3785296Y2712098D01*
G01X3791496D02*
X3788396Y2705223D01*
G01X3803896Y2699598D02*
X3797696D01*
Y2712098D01*
X3803896D01*
G01X3801416Y2706056D02*
X3797696D01*
G01X3810096Y2699598D02*
Y2712098D01*
X3813971D01*
X3815211Y2711473D01*
X3815986Y2710640D01*
X3816296Y2708973D01*
X3815986Y2707306D01*
X3815056Y2706265D01*
X3813971Y2705640D01*
X3810096D01*
G01X3813971D02*
X3816296Y2699598D01*
G01X3437631Y2718348D02*
Y2730848D01*
X3444761Y2718348D01*
Y2730848D01*
G01X3453596Y2718348D02*
X3452356Y2718556D01*
X3451271Y2719389D01*
X3450341Y2720640D01*
X3449721Y2722098D01*
X3449411Y2723765D01*
Y2725431D01*
X3449721Y2727098D01*
X3450341Y2728556D01*
X3451271Y2729806D01*
X3452356Y2730640D01*
X3453596Y2730848D01*
X3454836Y2730640D01*
X3455921Y2729806D01*
X3456851Y2728556D01*
X3457471Y2727098D01*
X3457781Y2725431D01*
Y2723765D01*
X3457471Y2722098D01*
X3456851Y2720640D01*
X3455921Y2719389D01*
X3454836Y2718556D01*
X3453596Y2718348D01*
G01X3465996Y2730848D02*
Y2718348D01*
G01X3462431Y2730848D02*
X3469561D01*
G01X3481496Y2718348D02*
X3475296D01*
Y2730848D01*
X3481496D01*
G01X3479016Y2724806D02*
X3475296D01*
G01X3487541Y2720014D02*
X3488781Y2718973D01*
X3490176Y2718348D01*
X3491416D01*
X3492656Y2718973D01*
X3493586Y2720014D01*
X3494051Y2721473D01*
X3493741Y2722931D01*
X3492966Y2724181D01*
X3491571Y2725015D01*
X3489711Y2725431D01*
X3488626Y2726265D01*
X3488161Y2727723D01*
X3488471Y2729181D01*
X3489246Y2730223D01*
X3490331Y2730848D01*
X3491416D01*
X3492501Y2730431D01*
X3493431Y2729390D01*
G01X3503196Y2717931D02*
X3502886Y2718140D01*
Y2718556D01*
X3503196Y2718765D01*
X3503506Y2718556D01*
Y2718140D01*
X3503196Y2717931D01*
G01Y2723556D02*
X3502886Y2723765D01*
Y2724181D01*
X3503196Y2724390D01*
X3503506Y2724181D01*
Y2723765D01*
X3503196Y2723556D01*
G01X3447551Y2818348D02*
Y2830848D01*
X3453441D01*
G01X3451271Y2824806D02*
X3447551D01*
G01X3461036Y2830848D02*
X3464756D01*
G01X3462896D02*
Y2818348D01*
G01X3461036D02*
X3464756D01*
G01X3476226Y2824598D02*
X3479326D01*
Y2820848D01*
X3478396Y2819598D01*
X3477311Y2818765D01*
X3475761Y2818348D01*
X3474211Y2818765D01*
X3473126Y2819598D01*
X3472196Y2820848D01*
X3471576Y2822306D01*
X3471266Y2823973D01*
Y2825431D01*
X3471576Y2826681D01*
X3472196Y2828140D01*
X3473126Y2829390D01*
X3474056Y2830223D01*
X3475296Y2830848D01*
X3476381D01*
X3477621Y2830431D01*
X3478551Y2829598D01*
G01X3484286Y2830848D02*
Y2821890D01*
X3484906Y2820014D01*
X3486146Y2818765D01*
X3487696Y2818348D01*
X3489246Y2818765D01*
X3490486Y2820014D01*
X3491106Y2821890D01*
Y2830848D01*
G01X3496996Y2818348D02*
Y2830848D01*
X3500871D01*
X3502111Y2830223D01*
X3502886Y2829390D01*
X3503196Y2827723D01*
X3502886Y2826056D01*
X3501956Y2825015D01*
X3500871Y2824390D01*
X3496996D01*
G01X3500871D02*
X3503196Y2818348D01*
G01X3515596D02*
X3509396D01*
Y2830848D01*
X3515596D01*
G01X3513116Y2824806D02*
X3509396D01*
G01X3458953Y101130D02*
X3462983D01*
G01X3458953Y134280D02*
X3462983D01*
G01X3458953Y167430D02*
X3462983D01*
G01X3458953Y200580D02*
X3462983D01*
G01X3458953Y233730D02*
X3462983D01*
G01X3458953Y266880D02*
X3462983D01*
G01X3458953Y300030D02*
X3462983D01*
G01X3458953Y333180D02*
X3462983D01*
G01X3458953Y366330D02*
X3462983D01*
G01X3458953Y399480D02*
X3462983D01*
G01X3458953Y432630D02*
X3462983D01*
G01X3458953Y465780D02*
X3462983D01*
G01X3458953Y498930D02*
X3462983D01*
G01X3458953Y532080D02*
X3462983D01*
G01X3458953Y565230D02*
X3462983D01*
G01X3458953Y598380D02*
X3462983D01*
G01X3458953Y631530D02*
X3462983D01*
G01X3458953Y664680D02*
X3462983D01*
G01X3458953Y697830D02*
X3462983D01*
G01X3458953Y730980D02*
X3462983D01*
G01X3458953Y764130D02*
X3462983D01*
G01X3458953Y797280D02*
X3462983D01*
G01X3458953Y830430D02*
X3462983D01*
G01X3458953Y863580D02*
X3462983D01*
G01X3458953Y896730D02*
X3462983D01*
G01X3458953Y929880D02*
X3462983D01*
G01X3458953Y963030D02*
X3462983D01*
G01X3616071Y1528379D02*
X3616691Y1529004D01*
X3617156Y1530045D01*
X3617466Y1531504D01*
X3617156Y1532754D01*
X3616536Y1533587D01*
X3615451Y1534212D01*
X3611266D01*
Y1521712D01*
X3616381D01*
X3617466Y1522545D01*
X3618086Y1523795D01*
X3618396Y1525254D01*
X3618086Y1526712D01*
X3617156Y1527962D01*
X3616071Y1528379D01*
X3611266D01*
G01X3623356Y1521712D02*
X3627231Y1534212D01*
X3631106Y1521712D01*
G01X3629711Y1526087D02*
X3624751D01*
G01X3643041Y1533170D02*
X3642111Y1533795D01*
X3641026Y1534212D01*
X3639786D01*
X3638391Y1533587D01*
X3637306Y1532545D01*
X3636531Y1531295D01*
X3635911Y1529212D01*
X3635756Y1527337D01*
X3636066Y1525462D01*
X3636531Y1524212D01*
X3637461Y1522962D01*
X3638546Y1522129D01*
X3639631Y1521712D01*
X3640716D01*
X3641801Y1522129D01*
X3642731Y1522753D01*
X3643506Y1523587D01*
G01X3648621Y1521712D02*
Y1534212D01*
G01X3654511D02*
X3648621Y1526503D01*
G01X3655441Y1521712D02*
X3651256Y1530045D01*
G01X3661021Y1521712D02*
Y1534212D01*
X3664121D01*
X3665361Y1533587D01*
X3666291Y1532754D01*
X3667066Y1531504D01*
X3667686Y1530045D01*
X3667841Y1527962D01*
X3667686Y1525879D01*
X3667066Y1524420D01*
X3666291Y1523170D01*
X3665361Y1522337D01*
X3664121Y1521712D01*
X3661021D01*
G01X3673731D02*
Y1534212D01*
X3677606D01*
X3678846Y1533587D01*
X3679621Y1532754D01*
X3679931Y1531087D01*
X3679621Y1529420D01*
X3678691Y1528379D01*
X3677606Y1527754D01*
X3673731D01*
G01X3677606D02*
X3679931Y1521712D01*
G01X3687371Y1534212D02*
X3691091D01*
G01X3689231D02*
Y1521712D01*
G01X3687371D02*
X3691091D01*
G01X3698531Y1534212D02*
Y1521712D01*
X3704731D01*
G01X3710931Y1534212D02*
Y1521712D01*
X3717131D01*
G01X3735576Y1523378D02*
X3736816Y1522337D01*
X3738211Y1521712D01*
X3739451D01*
X3740691Y1522337D01*
X3741621Y1523378D01*
X3742086Y1524837D01*
X3741776Y1526295D01*
X3741001Y1527545D01*
X3739606Y1528379D01*
X3737746Y1528795D01*
X3736661Y1529629D01*
X3736196Y1531087D01*
X3736506Y1532545D01*
X3737281Y1533587D01*
X3738366Y1534212D01*
X3739451D01*
X3740536Y1533795D01*
X3741466Y1532754D01*
G01X3751231Y1534212D02*
Y1521712D01*
G01X3747666Y1534212D02*
X3754796D01*
G01X3760221D02*
Y1525254D01*
X3760841Y1523378D01*
X3762081Y1522129D01*
X3763631Y1521712D01*
X3765181Y1522129D01*
X3766421Y1523378D01*
X3767041Y1525254D01*
Y1534212D01*
G01X3777271Y1528379D02*
X3777891Y1529004D01*
X3778356Y1530045D01*
X3778666Y1531504D01*
X3778356Y1532754D01*
X3777736Y1533587D01*
X3776651Y1534212D01*
X3772466D01*
Y1521712D01*
X3777581D01*
X3778666Y1522545D01*
X3779286Y1523795D01*
X3779596Y1525254D01*
X3779286Y1526712D01*
X3778356Y1527962D01*
X3777271Y1528379D01*
X3772466D01*
G01X3797731Y1534212D02*
Y1521712D01*
X3803931D01*
G01X3816331D02*
X3810131D01*
Y1534212D01*
X3816331D01*
G01X3813851Y1528170D02*
X3810131D01*
G01X3822066Y1521712D02*
Y1534212D01*
X3829196Y1521712D01*
Y1534212D01*
G01X3838961Y1527962D02*
X3842061D01*
Y1524212D01*
X3841131Y1522962D01*
X3840046Y1522129D01*
X3838496Y1521712D01*
X3836946Y1522129D01*
X3835861Y1522962D01*
X3834931Y1524212D01*
X3834311Y1525670D01*
X3834001Y1527337D01*
Y1528795D01*
X3834311Y1530045D01*
X3834931Y1531504D01*
X3835861Y1532754D01*
X3836791Y1533587D01*
X3838031Y1534212D01*
X3839116D01*
X3840356Y1533795D01*
X3841286Y1532962D01*
G01X3850431Y1534212D02*
Y1521712D01*
G01X3846866Y1534212D02*
X3853996D01*
G01X3859576Y1521712D02*
Y1534212D01*
G01X3866086D02*
Y1521712D01*
G01Y1527962D02*
X3859576D01*
G01X3887631Y1534212D02*
Y1521712D01*
G01X3884066Y1534212D02*
X3891196D01*
G01X3900031Y1521712D02*
X3898791Y1521920D01*
X3897706Y1522753D01*
X3896776Y1524004D01*
X3896156Y1525462D01*
X3895846Y1527129D01*
Y1528795D01*
X3896156Y1530462D01*
X3896776Y1531920D01*
X3897706Y1533170D01*
X3898791Y1534004D01*
X3900031Y1534212D01*
X3901271Y1534004D01*
X3902356Y1533170D01*
X3903286Y1531920D01*
X3903906Y1530462D01*
X3904216Y1528795D01*
Y1527129D01*
X3903906Y1525462D01*
X3903286Y1524004D01*
X3902356Y1522753D01*
X3901271Y1521920D01*
X3900031Y1521712D01*
G01X3909331Y1534212D02*
Y1521712D01*
X3915531D01*
G01X3927931D02*
X3921731D01*
Y1534212D01*
X3927931D01*
G01X3925451Y1528170D02*
X3921731D01*
G01X3934131Y1521712D02*
Y1534212D01*
X3938006D01*
X3939246Y1533587D01*
X3940021Y1532754D01*
X3940331Y1531087D01*
X3940021Y1529420D01*
X3939091Y1528379D01*
X3938006Y1527754D01*
X3934131D01*
G01X3938006D02*
X3940331Y1521712D01*
G01X3945756D02*
X3949631Y1534212D01*
X3953506Y1521712D01*
G01X3952111Y1526087D02*
X3947151D01*
G01X3958466Y1521712D02*
Y1534212D01*
X3965596Y1521712D01*
Y1534212D01*
G01X3977841Y1533170D02*
X3976911Y1533795D01*
X3975826Y1534212D01*
X3974586D01*
X3973191Y1533587D01*
X3972106Y1532545D01*
X3971331Y1531295D01*
X3970711Y1529212D01*
X3970556Y1527337D01*
X3970866Y1525462D01*
X3971331Y1524212D01*
X3972261Y1522962D01*
X3973346Y1522129D01*
X3974431Y1521712D01*
X3975516D01*
X3976601Y1522129D01*
X3977531Y1522753D01*
X3978306Y1523587D01*
G01X3989931Y1521712D02*
X3983731D01*
Y1534212D01*
X3989931D01*
G01X3987451Y1528170D02*
X3983731D01*
G01X4011631Y1534212D02*
Y1521712D01*
G01X4008066Y1534212D02*
X4015196D01*
G01X4024031Y1521712D02*
X4022791Y1521920D01*
X4021706Y1522753D01*
X4020776Y1524004D01*
X4020156Y1525462D01*
X4019846Y1527129D01*
Y1528795D01*
X4020156Y1530462D01*
X4020776Y1531920D01*
X4021706Y1533170D01*
X4022791Y1534004D01*
X4024031Y1534212D01*
X4025271Y1534004D01*
X4026356Y1533170D01*
X4027286Y1531920D01*
X4027906Y1530462D01*
X4028216Y1528795D01*
Y1527129D01*
X4027906Y1525462D01*
X4027286Y1524004D01*
X4026356Y1522753D01*
X4025271Y1521920D01*
X4024031Y1521712D01*
G01X4050071Y1528379D02*
X4050691Y1529004D01*
X4051156Y1530045D01*
X4051466Y1531504D01*
X4051156Y1532754D01*
X4050536Y1533587D01*
X4049451Y1534212D01*
X4045266D01*
Y1521712D01*
X4050381D01*
X4051466Y1522545D01*
X4052086Y1523795D01*
X4052396Y1525254D01*
X4052086Y1526712D01*
X4051156Y1527962D01*
X4050071Y1528379D01*
X4045266D01*
G01X4064331Y1521712D02*
X4058131D01*
Y1534212D01*
X4064331D01*
G01X4061851Y1528170D02*
X4058131D01*
G01X4085721Y1521712D02*
X4086031Y1524420D01*
X4086496Y1526712D01*
X4087116Y1528795D01*
X4087891Y1531087D01*
X4089131Y1534212D01*
X4082931D01*
G01X4109126Y1525879D02*
X4112846D01*
G01X4110831Y1528587D02*
Y1523170D01*
G01X4120441Y1521295D02*
X4126021Y1534212D01*
G01X4133616Y1525879D02*
X4137646D01*
G01X4144621Y1523587D02*
X4145551Y1522545D01*
X4146636Y1521920D01*
X4148031Y1521712D01*
X4149426Y1522129D01*
X4150511Y1522962D01*
X4151286Y1524420D01*
X4151441Y1526087D01*
X4151131Y1527754D01*
X4150356Y1528795D01*
X4149271Y1529629D01*
X4148186Y1529837D01*
X4147101Y1529629D01*
X4145706Y1528795D01*
X4146171Y1534212D01*
X4150356D01*
G01X4168801Y1521712D02*
Y1534212D01*
X4172831Y1523795D01*
X4176861Y1534212D01*
Y1521712D01*
G01X4183371Y1534212D02*
X4187091D01*
G01X4185231D02*
Y1521712D01*
G01X4183371D02*
X4187091D01*
G01X4194531Y1534212D02*
Y1521712D01*
X4200731D01*
G01X4206776Y1523378D02*
X4208016Y1522337D01*
X4209411Y1521712D01*
X4210651D01*
X4211891Y1522337D01*
X4212821Y1523378D01*
X4213286Y1524837D01*
X4212976Y1526295D01*
X4212201Y1527545D01*
X4210806Y1528379D01*
X4208946Y1528795D01*
X4207861Y1529629D01*
X4207396Y1531087D01*
X4207706Y1532545D01*
X4208481Y1533587D01*
X4209566Y1534212D01*
X4210651D01*
X4211736Y1533795D01*
X4212666Y1532754D01*
G01X3451616Y1544629D02*
X3455646D01*
G01X3474401Y1540462D02*
Y1552962D01*
X3478431Y1542545D01*
X3482461Y1552962D01*
Y1540462D01*
G01X3487886D02*
Y1552962D01*
X3493776D01*
G01X3491606Y1546920D02*
X3487886D01*
G01X3504161Y1546712D02*
X3507261D01*
Y1542962D01*
X3506331Y1541712D01*
X3505246Y1540879D01*
X3503696Y1540462D01*
X3502146Y1540879D01*
X3501061Y1541712D01*
X3500131Y1542962D01*
X3499511Y1544420D01*
X3499201Y1546087D01*
Y1547545D01*
X3499511Y1548795D01*
X3500131Y1550254D01*
X3501061Y1551504D01*
X3501991Y1552337D01*
X3503231Y1552962D01*
X3504316D01*
X3505556Y1552545D01*
X3506486Y1551712D01*
G01X3510981Y1536295D02*
X3520281D01*
G01X3524776Y1542128D02*
X3526016Y1541087D01*
X3527411Y1540462D01*
X3528651D01*
X3529891Y1541087D01*
X3530821Y1542128D01*
X3531286Y1543587D01*
X3530976Y1545045D01*
X3530201Y1546295D01*
X3528806Y1547129D01*
X3526946Y1547545D01*
X3525861Y1548379D01*
X3525396Y1549837D01*
X3525706Y1551295D01*
X3526481Y1552337D01*
X3527566Y1552962D01*
X3528651D01*
X3529736Y1552545D01*
X3530666Y1551504D01*
G01X3540431Y1552962D02*
Y1540462D01*
G01X3536866Y1552962D02*
X3543996D01*
G01X3549421D02*
Y1544004D01*
X3550041Y1542128D01*
X3551281Y1540879D01*
X3552831Y1540462D01*
X3554381Y1540879D01*
X3555621Y1542128D01*
X3556241Y1544004D01*
Y1552962D01*
G01X3566471Y1547129D02*
X3567091Y1547754D01*
X3567556Y1548795D01*
X3567866Y1550254D01*
X3567556Y1551504D01*
X3566936Y1552337D01*
X3565851Y1552962D01*
X3561666D01*
Y1540462D01*
X3566781D01*
X3567866Y1541295D01*
X3568486Y1542545D01*
X3568796Y1544004D01*
X3568486Y1545462D01*
X3567556Y1546712D01*
X3566471Y1547129D01*
X3561666D01*
G01X3590031Y1540045D02*
X3589721Y1540254D01*
Y1540670D01*
X3590031Y1540879D01*
X3590341Y1540670D01*
Y1540254D01*
X3590031Y1540045D01*
G01Y1545670D02*
X3589721Y1545879D01*
Y1546295D01*
X3590031Y1546504D01*
X3590341Y1546295D01*
Y1545879D01*
X3590031Y1545670D01*
G01X3610801Y1540462D02*
Y1552962D01*
X3614831Y1542545D01*
X3618861Y1552962D01*
Y1540462D01*
G01X3623356D02*
X3627231Y1552962D01*
X3631106Y1540462D01*
G01X3629711Y1544837D02*
X3624751D01*
G01X3636066Y1540462D02*
Y1552962D01*
X3643196Y1540462D01*
Y1552962D01*
G01X3648621D02*
Y1544004D01*
X3649241Y1542128D01*
X3650481Y1540879D01*
X3652031Y1540462D01*
X3653581Y1540879D01*
X3654821Y1542128D01*
X3655441Y1544004D01*
Y1552962D01*
G01X3661486Y1540462D02*
Y1552962D01*
X3667376D01*
G01X3665206Y1546920D02*
X3661486D01*
G01X3672956Y1540462D02*
X3676831Y1552962D01*
X3680706Y1540462D01*
G01X3679311Y1544837D02*
X3674351D01*
G01X3692641Y1551920D02*
X3691711Y1552545D01*
X3690626Y1552962D01*
X3689386D01*
X3687991Y1552337D01*
X3686906Y1551295D01*
X3686131Y1550045D01*
X3685511Y1547962D01*
X3685356Y1546087D01*
X3685666Y1544212D01*
X3686131Y1542962D01*
X3687061Y1541712D01*
X3688146Y1540879D01*
X3689231Y1540462D01*
X3690316D01*
X3691401Y1540879D01*
X3692331Y1541503D01*
X3693106Y1542337D01*
G01X3701631Y1552962D02*
Y1540462D01*
G01X3698066Y1552962D02*
X3705196D01*
G01X3710621D02*
Y1544004D01*
X3711241Y1542128D01*
X3712481Y1540879D01*
X3714031Y1540462D01*
X3715581Y1540879D01*
X3716821Y1542128D01*
X3717441Y1544004D01*
Y1552962D01*
G01X3723331Y1540462D02*
Y1552962D01*
X3727206D01*
X3728446Y1552337D01*
X3729221Y1551504D01*
X3729531Y1549837D01*
X3729221Y1548170D01*
X3728291Y1547129D01*
X3727206Y1546504D01*
X3723331D01*
G01X3727206D02*
X3729531Y1540462D01*
G01X3736971Y1552962D02*
X3740691D01*
G01X3738831D02*
Y1540462D01*
G01X3736971D02*
X3740691D01*
G01X3747666D02*
Y1552962D01*
X3754796Y1540462D01*
Y1552962D01*
G01X3764561Y1546712D02*
X3767661D01*
Y1542962D01*
X3766731Y1541712D01*
X3765646Y1540879D01*
X3764096Y1540462D01*
X3762546Y1540879D01*
X3761461Y1541712D01*
X3760531Y1542962D01*
X3759911Y1544420D01*
X3759601Y1546087D01*
Y1547545D01*
X3759911Y1548795D01*
X3760531Y1550254D01*
X3761461Y1551504D01*
X3762391Y1552337D01*
X3763631Y1552962D01*
X3764716D01*
X3765956Y1552545D01*
X3766886Y1551712D01*
G01X3785176Y1542128D02*
X3786416Y1541087D01*
X3787811Y1540462D01*
X3789051D01*
X3790291Y1541087D01*
X3791221Y1542128D01*
X3791686Y1543587D01*
X3791376Y1545045D01*
X3790601Y1546295D01*
X3789206Y1547129D01*
X3787346Y1547545D01*
X3786261Y1548379D01*
X3785796Y1549837D01*
X3786106Y1551295D01*
X3786881Y1552337D01*
X3787966Y1552962D01*
X3789051D01*
X3790136Y1552545D01*
X3791066Y1551504D01*
G01X3800831Y1552962D02*
Y1540462D01*
G01X3797266Y1552962D02*
X3804396D01*
G01X3809821D02*
Y1544004D01*
X3810441Y1542128D01*
X3811681Y1540879D01*
X3813231Y1540462D01*
X3814781Y1540879D01*
X3816021Y1542128D01*
X3816641Y1544004D01*
Y1552962D01*
G01X3826871Y1547129D02*
X3827491Y1547754D01*
X3827956Y1548795D01*
X3828266Y1550254D01*
X3827956Y1551504D01*
X3827336Y1552337D01*
X3826251Y1552962D01*
X3822066D01*
Y1540462D01*
X3827181D01*
X3828266Y1541295D01*
X3828886Y1542545D01*
X3829196Y1544004D01*
X3828886Y1545462D01*
X3827956Y1546712D01*
X3826871Y1547129D01*
X3822066D01*
G01X3847331Y1552962D02*
Y1540462D01*
X3853531D01*
G01X3865931D02*
X3859731D01*
Y1552962D01*
X3865931D01*
G01X3863451Y1546920D02*
X3859731D01*
G01X3871666Y1540462D02*
Y1552962D01*
X3878796Y1540462D01*
Y1552962D01*
G01X3888561Y1546712D02*
X3891661D01*
Y1542962D01*
X3890731Y1541712D01*
X3889646Y1540879D01*
X3888096Y1540462D01*
X3886546Y1540879D01*
X3885461Y1541712D01*
X3884531Y1542962D01*
X3883911Y1544420D01*
X3883601Y1546087D01*
Y1547545D01*
X3883911Y1548795D01*
X3884531Y1550254D01*
X3885461Y1551504D01*
X3886391Y1552337D01*
X3887631Y1552962D01*
X3888716D01*
X3889956Y1552545D01*
X3890886Y1551712D01*
G01X3900031Y1552962D02*
Y1540462D01*
G01X3896466Y1552962D02*
X3903596D01*
G01X3909176Y1540462D02*
Y1552962D01*
G01X3915686D02*
Y1540462D01*
G01Y1546712D02*
X3909176D01*
G01X3611576Y1560878D02*
X3612816Y1559837D01*
X3614211Y1559212D01*
X3615451D01*
X3616691Y1559837D01*
X3617621Y1560878D01*
X3618086Y1562337D01*
X3617776Y1563795D01*
X3617001Y1565045D01*
X3615606Y1565879D01*
X3613746Y1566295D01*
X3612661Y1567129D01*
X3612196Y1568587D01*
X3612506Y1570045D01*
X3613281Y1571087D01*
X3614366Y1571712D01*
X3615451D01*
X3616536Y1571295D01*
X3617466Y1570254D01*
G01X3623821Y1571712D02*
Y1562754D01*
X3624441Y1560878D01*
X3625681Y1559629D01*
X3627231Y1559212D01*
X3628781Y1559629D01*
X3630021Y1560878D01*
X3630641Y1562754D01*
Y1571712D01*
G01X3636531Y1559212D02*
Y1571712D01*
X3640406D01*
X3641646Y1571087D01*
X3642421Y1570254D01*
X3642731Y1568587D01*
X3642421Y1566920D01*
X3641491Y1565879D01*
X3640406Y1565254D01*
X3636531D01*
G01X3640406D02*
X3642731Y1559212D01*
G01X3649086D02*
Y1571712D01*
X3654976D01*
G01X3652806Y1565670D02*
X3649086D01*
G01X3660556Y1559212D02*
X3664431Y1571712D01*
X3668306Y1559212D01*
G01X3666911Y1563587D02*
X3661951D01*
G01X3680241Y1570670D02*
X3679311Y1571295D01*
X3678226Y1571712D01*
X3676986D01*
X3675591Y1571087D01*
X3674506Y1570045D01*
X3673731Y1568795D01*
X3673111Y1566712D01*
X3672956Y1564837D01*
X3673266Y1562962D01*
X3673731Y1561712D01*
X3674661Y1560462D01*
X3675746Y1559629D01*
X3676831Y1559212D01*
X3677916D01*
X3679001Y1559629D01*
X3679931Y1560253D01*
X3680706Y1561087D01*
G01X3692331Y1559212D02*
X3686131D01*
Y1571712D01*
X3692331D01*
G01X3689851Y1565670D02*
X3686131D01*
G01X3714031Y1559212D02*
X3712791Y1559420D01*
X3711706Y1560253D01*
X3710776Y1561504D01*
X3710156Y1562962D01*
X3709846Y1564629D01*
Y1566295D01*
X3710156Y1567962D01*
X3710776Y1569420D01*
X3711706Y1570670D01*
X3712791Y1571504D01*
X3714031Y1571712D01*
X3715271Y1571504D01*
X3716356Y1570670D01*
X3717286Y1569420D01*
X3717906Y1567962D01*
X3718216Y1566295D01*
Y1564629D01*
X3717906Y1562962D01*
X3717286Y1561504D01*
X3716356Y1560253D01*
X3715271Y1559420D01*
X3714031Y1559212D01*
G01X3723486D02*
Y1571712D01*
X3729376D01*
G01X3727206Y1565670D02*
X3723486D01*
G01X3747201Y1559212D02*
Y1571712D01*
X3751231Y1561295D01*
X3755261Y1571712D01*
Y1559212D01*
G01X3760221Y1571712D02*
Y1562754D01*
X3760841Y1560878D01*
X3762081Y1559629D01*
X3763631Y1559212D01*
X3765181Y1559629D01*
X3766421Y1560878D01*
X3767041Y1562754D01*
Y1571712D01*
G01X3772776Y1560878D02*
X3774016Y1559837D01*
X3775411Y1559212D01*
X3776651D01*
X3777891Y1559837D01*
X3778821Y1560878D01*
X3779286Y1562337D01*
X3778976Y1563795D01*
X3778201Y1565045D01*
X3776806Y1565879D01*
X3774946Y1566295D01*
X3773861Y1567129D01*
X3773396Y1568587D01*
X3773706Y1570045D01*
X3774481Y1571087D01*
X3775566Y1571712D01*
X3776651D01*
X3777736Y1571295D01*
X3778666Y1570254D01*
G01X3788431Y1571712D02*
Y1559212D01*
G01X3784866Y1571712D02*
X3791996D01*
G01X3798816Y1563379D02*
X3802846D01*
G01X3809666Y1559212D02*
Y1571712D01*
X3816796Y1559212D01*
Y1571712D01*
G01X3825631Y1559212D02*
X3824391Y1559420D01*
X3823306Y1560253D01*
X3822376Y1561504D01*
X3821756Y1562962D01*
X3821446Y1564629D01*
Y1566295D01*
X3821756Y1567962D01*
X3822376Y1569420D01*
X3823306Y1570670D01*
X3824391Y1571504D01*
X3825631Y1571712D01*
X3826871Y1571504D01*
X3827956Y1570670D01*
X3828886Y1569420D01*
X3829506Y1567962D01*
X3829816Y1566295D01*
Y1564629D01*
X3829506Y1562962D01*
X3828886Y1561504D01*
X3827956Y1560253D01*
X3826871Y1559420D01*
X3825631Y1559212D01*
G01X3838031Y1571712D02*
Y1559212D01*
G01X3834466Y1571712D02*
X3841596D01*
G01X3848416Y1563379D02*
X3852446D01*
G01X3866241Y1570670D02*
X3865311Y1571295D01*
X3864226Y1571712D01*
X3862986D01*
X3861591Y1571087D01*
X3860506Y1570045D01*
X3859731Y1568795D01*
X3859111Y1566712D01*
X3858956Y1564837D01*
X3859266Y1562962D01*
X3859731Y1561712D01*
X3860661Y1560462D01*
X3861746Y1559629D01*
X3862831Y1559212D01*
X3863916D01*
X3865001Y1559629D01*
X3865931Y1560253D01*
X3866706Y1561087D01*
G01X3871821Y1571712D02*
Y1562754D01*
X3872441Y1560878D01*
X3873681Y1559629D01*
X3875231Y1559212D01*
X3876781Y1559629D01*
X3878021Y1560878D01*
X3878641Y1562754D01*
Y1571712D01*
G01X3887631D02*
Y1559212D01*
G01X3884066Y1571712D02*
X3891196D01*
G01X3898016Y1563379D02*
X3902046D01*
G01X3909331Y1571712D02*
Y1559212D01*
X3915531D01*
G01X3920956D02*
X3924831Y1571712D01*
X3928706Y1559212D01*
G01X3927311Y1563587D02*
X3922351D01*
G01X3937231Y1559212D02*
Y1564837D01*
X3934131Y1571712D01*
G01X3940331D02*
X3937231Y1564837D01*
G01X3952731Y1559212D02*
X3946531D01*
Y1571712D01*
X3952731D01*
G01X3950251Y1565670D02*
X3946531D01*
G01X3958931Y1559212D02*
Y1571712D01*
X3962806D01*
X3964046Y1571087D01*
X3964821Y1570254D01*
X3965131Y1568587D01*
X3964821Y1566920D01*
X3963891Y1565879D01*
X3962806Y1565254D01*
X3958931D01*
G01X3962806D02*
X3965131Y1559212D01*
G01X3451616Y1582129D02*
X3455646D01*
G01X3474401Y1577962D02*
Y1590462D01*
X3478431Y1580045D01*
X3482461Y1590462D01*
Y1577962D01*
G01X3486956D02*
X3490831Y1590462D01*
X3494706Y1577962D01*
G01X3493311Y1582337D02*
X3488351D01*
G01X3499976Y1577962D02*
X3506486Y1590462D01*
G01X3499976D02*
X3506486Y1577962D01*
G01X3510981Y1573795D02*
X3520281D01*
G01X3524621Y1577962D02*
Y1590462D01*
X3527721D01*
X3528961Y1589837D01*
X3529891Y1589004D01*
X3530666Y1587754D01*
X3531286Y1586295D01*
X3531441Y1584212D01*
X3531286Y1582129D01*
X3530666Y1580670D01*
X3529891Y1579420D01*
X3528961Y1578587D01*
X3527721Y1577962D01*
X3524621D01*
G01X3543531D02*
X3537331D01*
Y1590462D01*
X3543531D01*
G01X3541051Y1584420D02*
X3537331D01*
G01X3549731Y1577962D02*
Y1590462D01*
X3553451D01*
X3554691Y1589837D01*
X3555621Y1588379D01*
X3555931Y1586712D01*
X3555621Y1585045D01*
X3554846Y1583795D01*
X3553451Y1583170D01*
X3549731D01*
G01X3565231Y1590462D02*
Y1577962D01*
G01X3561666Y1590462D02*
X3568796D01*
G01X3574376Y1577962D02*
Y1590462D01*
G01X3580886D02*
Y1577962D01*
G01Y1584212D02*
X3574376D01*
G01X3590031Y1577545D02*
X3589721Y1577754D01*
Y1578170D01*
X3590031Y1578379D01*
X3590341Y1578170D01*
Y1577754D01*
X3590031Y1577545D01*
G01Y1583170D02*
X3589721Y1583379D01*
Y1583795D01*
X3590031Y1584004D01*
X3590341Y1583795D01*
Y1583379D01*
X3590031Y1583170D01*
G01X3611421Y1577962D02*
Y1590462D01*
X3614521D01*
X3615761Y1589837D01*
X3616691Y1589004D01*
X3617466Y1587754D01*
X3618086Y1586295D01*
X3618241Y1584212D01*
X3618086Y1582129D01*
X3617466Y1580670D01*
X3616691Y1579420D01*
X3615761Y1578587D01*
X3614521Y1577962D01*
X3611421D01*
G01X3630331D02*
X3624131D01*
Y1590462D01*
X3630331D01*
G01X3627851Y1584420D02*
X3624131D01*
G01X3636531Y1577962D02*
Y1590462D01*
X3640251D01*
X3641491Y1589837D01*
X3642421Y1588379D01*
X3642731Y1586712D01*
X3642421Y1585045D01*
X3641646Y1583795D01*
X3640251Y1583170D01*
X3636531D01*
G01X3652031Y1590462D02*
Y1577962D01*
G01X3648466Y1590462D02*
X3655596D01*
G01X3661176Y1577962D02*
Y1590462D01*
G01X3667686D02*
Y1577962D01*
G01Y1584212D02*
X3661176D01*
G01X3686286Y1577962D02*
Y1590462D01*
X3692176D01*
G01X3690006Y1584420D02*
X3686286D01*
G01X3698531Y1577962D02*
Y1590462D01*
X3702406D01*
X3703646Y1589837D01*
X3704421Y1589004D01*
X3704731Y1587337D01*
X3704421Y1585670D01*
X3703491Y1584629D01*
X3702406Y1584004D01*
X3698531D01*
G01X3702406D02*
X3704731Y1577962D01*
G01X3714031D02*
X3712791Y1578170D01*
X3711706Y1579003D01*
X3710776Y1580254D01*
X3710156Y1581712D01*
X3709846Y1583379D01*
Y1585045D01*
X3710156Y1586712D01*
X3710776Y1588170D01*
X3711706Y1589420D01*
X3712791Y1590254D01*
X3714031Y1590462D01*
X3715271Y1590254D01*
X3716356Y1589420D01*
X3717286Y1588170D01*
X3717906Y1586712D01*
X3718216Y1585045D01*
Y1583379D01*
X3717906Y1581712D01*
X3717286Y1580254D01*
X3716356Y1579003D01*
X3715271Y1578170D01*
X3714031Y1577962D01*
G01X3722401D02*
Y1590462D01*
X3726431Y1580045D01*
X3730461Y1590462D01*
Y1577962D01*
G01X3747976Y1579628D02*
X3749216Y1578587D01*
X3750611Y1577962D01*
X3751851D01*
X3753091Y1578587D01*
X3754021Y1579628D01*
X3754486Y1581087D01*
X3754176Y1582545D01*
X3753401Y1583795D01*
X3752006Y1584629D01*
X3750146Y1585045D01*
X3749061Y1585879D01*
X3748596Y1587337D01*
X3748906Y1588795D01*
X3749681Y1589837D01*
X3750766Y1590462D01*
X3751851D01*
X3752936Y1590045D01*
X3753866Y1589004D01*
G01X3763631Y1590462D02*
Y1577962D01*
G01X3760066Y1590462D02*
X3767196D01*
G01X3772156Y1577962D02*
X3776031Y1590462D01*
X3779906Y1577962D01*
G01X3778511Y1582337D02*
X3773551D01*
G01X3785331Y1577962D02*
Y1590462D01*
X3789206D01*
X3790446Y1589837D01*
X3791221Y1589004D01*
X3791531Y1587337D01*
X3791221Y1585670D01*
X3790291Y1584629D01*
X3789206Y1584004D01*
X3785331D01*
G01X3789206D02*
X3791531Y1577962D01*
G01X3800831Y1590462D02*
Y1577962D01*
G01X3797266Y1590462D02*
X3804396D01*
G01X3822531D02*
Y1577962D01*
X3828731D01*
G01X3834156D02*
X3838031Y1590462D01*
X3841906Y1577962D01*
G01X3840511Y1582337D02*
X3835551D01*
G01X3850431Y1577962D02*
Y1583587D01*
X3847331Y1590462D01*
G01X3853531D02*
X3850431Y1583587D01*
G01X3865931Y1577962D02*
X3859731D01*
Y1590462D01*
X3865931D01*
G01X3863451Y1584420D02*
X3859731D01*
G01X3872131Y1577962D02*
Y1590462D01*
X3876006D01*
X3877246Y1589837D01*
X3878021Y1589004D01*
X3878331Y1587337D01*
X3878021Y1585670D01*
X3877091Y1584629D01*
X3876006Y1584004D01*
X3872131D01*
G01X3876006D02*
X3878331Y1577962D01*
G01X3900031Y1590462D02*
Y1577962D01*
G01X3896466Y1590462D02*
X3903596D01*
G01X3912431Y1577962D02*
X3911191Y1578170D01*
X3910106Y1579003D01*
X3909176Y1580254D01*
X3908556Y1581712D01*
X3908246Y1583379D01*
Y1585045D01*
X3908556Y1586712D01*
X3909176Y1588170D01*
X3910106Y1589420D01*
X3911191Y1590254D01*
X3912431Y1590462D01*
X3913671Y1590254D01*
X3914756Y1589420D01*
X3915686Y1588170D01*
X3916306Y1586712D01*
X3916616Y1585045D01*
Y1583379D01*
X3916306Y1581712D01*
X3915686Y1580254D01*
X3914756Y1579003D01*
X3913671Y1578170D01*
X3912431Y1577962D01*
G01X3937231Y1590462D02*
Y1577962D01*
G01X3933666Y1590462D02*
X3940796D01*
G01X3946376Y1577962D02*
Y1590462D01*
G01X3952886D02*
Y1577962D01*
G01Y1584212D02*
X3946376D01*
G01X3965131Y1577962D02*
X3958931D01*
Y1590462D01*
X3965131D01*
G01X3962651Y1584420D02*
X3958931D01*
G01X3451616Y1600879D02*
X3455646D01*
G01X3474401Y1596712D02*
Y1609212D01*
X3478431Y1598795D01*
X3482461Y1609212D01*
Y1596712D01*
G01X3487266D02*
Y1609212D01*
X3494396Y1596712D01*
Y1609212D01*
G01X3506641Y1608170D02*
X3505711Y1608795D01*
X3504626Y1609212D01*
X3503386D01*
X3501991Y1608587D01*
X3500906Y1607545D01*
X3500131Y1606295D01*
X3499511Y1604212D01*
X3499356Y1602337D01*
X3499666Y1600462D01*
X3500131Y1599212D01*
X3501061Y1597962D01*
X3502146Y1597129D01*
X3503231Y1596712D01*
X3504316D01*
X3505401Y1597129D01*
X3506331Y1597753D01*
X3507106Y1598587D01*
G01X3510981Y1592545D02*
X3520281D01*
G01X3524931Y1609212D02*
Y1596712D01*
X3531131D01*
G01X3536556D02*
X3540431Y1609212D01*
X3544306Y1596712D01*
G01X3542911Y1601087D02*
X3537951D01*
G01X3552831Y1596712D02*
Y1602337D01*
X3549731Y1609212D01*
G01X3555931D02*
X3552831Y1602337D01*
G01X3568331Y1596712D02*
X3562131D01*
Y1609212D01*
X3568331D01*
G01X3565851Y1603170D02*
X3562131D01*
G01X3574531Y1596712D02*
Y1609212D01*
X3578406D01*
X3579646Y1608587D01*
X3580421Y1607754D01*
X3580731Y1606087D01*
X3580421Y1604420D01*
X3579491Y1603379D01*
X3578406Y1602754D01*
X3574531D01*
G01X3578406D02*
X3580731Y1596712D01*
G01X3590031Y1596295D02*
X3589721Y1596504D01*
Y1596920D01*
X3590031Y1597129D01*
X3590341Y1596920D01*
Y1596504D01*
X3590031Y1596295D01*
G01Y1601920D02*
X3589721Y1602129D01*
Y1602545D01*
X3590031Y1602754D01*
X3590341Y1602545D01*
Y1602129D01*
X3590031Y1601920D01*
G01X3610801Y1596712D02*
Y1609212D01*
X3614831Y1598795D01*
X3618861Y1609212D01*
Y1596712D01*
G01X3623821Y1609212D02*
Y1600254D01*
X3624441Y1598378D01*
X3625681Y1597129D01*
X3627231Y1596712D01*
X3628781Y1597129D01*
X3630021Y1598378D01*
X3630641Y1600254D01*
Y1609212D01*
G01X3636376Y1598378D02*
X3637616Y1597337D01*
X3639011Y1596712D01*
X3640251D01*
X3641491Y1597337D01*
X3642421Y1598378D01*
X3642886Y1599837D01*
X3642576Y1601295D01*
X3641801Y1602545D01*
X3640406Y1603379D01*
X3638546Y1603795D01*
X3637461Y1604629D01*
X3636996Y1606087D01*
X3637306Y1607545D01*
X3638081Y1608587D01*
X3639166Y1609212D01*
X3640251D01*
X3641336Y1608795D01*
X3642266Y1607754D01*
G01X3652031Y1609212D02*
Y1596712D01*
G01X3648466Y1609212D02*
X3655596D01*
G01X3662416Y1600879D02*
X3666446D01*
G01X3673266Y1596712D02*
Y1609212D01*
X3680396Y1596712D01*
Y1609212D01*
G01X3689231Y1596712D02*
X3687991Y1596920D01*
X3686906Y1597753D01*
X3685976Y1599004D01*
X3685356Y1600462D01*
X3685046Y1602129D01*
Y1603795D01*
X3685356Y1605462D01*
X3685976Y1606920D01*
X3686906Y1608170D01*
X3687991Y1609004D01*
X3689231Y1609212D01*
X3690471Y1609004D01*
X3691556Y1608170D01*
X3692486Y1606920D01*
X3693106Y1605462D01*
X3693416Y1603795D01*
Y1602129D01*
X3693106Y1600462D01*
X3692486Y1599004D01*
X3691556Y1597753D01*
X3690471Y1596920D01*
X3689231Y1596712D01*
G01X3701631Y1609212D02*
Y1596712D01*
G01X3698066Y1609212D02*
X3705196D01*
G01X3712016Y1600879D02*
X3716046D01*
G01X3729841Y1608170D02*
X3728911Y1608795D01*
X3727826Y1609212D01*
X3726586D01*
X3725191Y1608587D01*
X3724106Y1607545D01*
X3723331Y1606295D01*
X3722711Y1604212D01*
X3722556Y1602337D01*
X3722866Y1600462D01*
X3723331Y1599212D01*
X3724261Y1597962D01*
X3725346Y1597129D01*
X3726431Y1596712D01*
X3727516D01*
X3728601Y1597129D01*
X3729531Y1597753D01*
X3730306Y1598587D01*
G01X3735421Y1609212D02*
Y1600254D01*
X3736041Y1598378D01*
X3737281Y1597129D01*
X3738831Y1596712D01*
X3740381Y1597129D01*
X3741621Y1598378D01*
X3742241Y1600254D01*
Y1609212D01*
G01X3751231D02*
Y1596712D01*
G01X3747666Y1609212D02*
X3754796D01*
G01X3761616Y1600879D02*
X3765646D01*
G01X3772931Y1609212D02*
Y1596712D01*
X3779131D01*
G01X3784556D02*
X3788431Y1609212D01*
X3792306Y1596712D01*
G01X3790911Y1601087D02*
X3785951D01*
G01X3800831Y1596712D02*
Y1602337D01*
X3797731Y1609212D01*
G01X3803931D02*
X3800831Y1602337D01*
G01X3816331Y1596712D02*
X3810131D01*
Y1609212D01*
X3816331D01*
G01X3813851Y1603170D02*
X3810131D01*
G01X3822531Y1596712D02*
Y1609212D01*
X3826406D01*
X3827646Y1608587D01*
X3828421Y1607754D01*
X3828731Y1606087D01*
X3828421Y1604420D01*
X3827491Y1603379D01*
X3826406Y1602754D01*
X3822531D01*
G01X3826406D02*
X3828731Y1596712D01*
G01X3450066Y1615462D02*
Y1627962D01*
X3457196Y1615462D01*
Y1627962D01*
G01X3466031Y1615462D02*
X3464791Y1615670D01*
X3463706Y1616503D01*
X3462776Y1617754D01*
X3462156Y1619212D01*
X3461846Y1620879D01*
Y1622545D01*
X3462156Y1624212D01*
X3462776Y1625670D01*
X3463706Y1626920D01*
X3464791Y1627754D01*
X3466031Y1627962D01*
X3467271Y1627754D01*
X3468356Y1626920D01*
X3469286Y1625670D01*
X3469906Y1624212D01*
X3470216Y1622545D01*
Y1620879D01*
X3469906Y1619212D01*
X3469286Y1617754D01*
X3468356Y1616503D01*
X3467271Y1615670D01*
X3466031Y1615462D01*
G01X3478431Y1627962D02*
Y1615462D01*
G01X3474866Y1627962D02*
X3481996D01*
G01X3493931Y1615462D02*
X3487731D01*
Y1627962D01*
X3493931D01*
G01X3491451Y1621920D02*
X3487731D01*
G01X3499976Y1617128D02*
X3501216Y1616087D01*
X3502611Y1615462D01*
X3503851D01*
X3505091Y1616087D01*
X3506021Y1617128D01*
X3506486Y1618587D01*
X3506176Y1620045D01*
X3505401Y1621295D01*
X3504006Y1622129D01*
X3502146Y1622545D01*
X3501061Y1623379D01*
X3500596Y1624837D01*
X3500906Y1626295D01*
X3501681Y1627337D01*
X3502766Y1627962D01*
X3503851D01*
X3504936Y1627545D01*
X3505866Y1626504D01*
G01X3515631Y1615045D02*
X3515321Y1615254D01*
Y1615670D01*
X3515631Y1615879D01*
X3515941Y1615670D01*
Y1615254D01*
X3515631Y1615045D01*
G01Y1620670D02*
X3515321Y1620879D01*
Y1621295D01*
X3515631Y1621504D01*
X3515941Y1621295D01*
Y1620879D01*
X3515631Y1620670D01*
G01X3459986Y1665462D02*
Y1677962D01*
X3465876D01*
G01X3463706Y1671920D02*
X3459986D01*
G01X3473471Y1677962D02*
X3477191D01*
G01X3475331D02*
Y1665462D01*
G01X3473471D02*
X3477191D01*
G01X3488661Y1671712D02*
X3491761D01*
Y1667962D01*
X3490831Y1666712D01*
X3489746Y1665879D01*
X3488196Y1665462D01*
X3486646Y1665879D01*
X3485561Y1666712D01*
X3484631Y1667962D01*
X3484011Y1669420D01*
X3483701Y1671087D01*
Y1672545D01*
X3484011Y1673795D01*
X3484631Y1675254D01*
X3485561Y1676504D01*
X3486491Y1677337D01*
X3487731Y1677962D01*
X3488816D01*
X3490056Y1677545D01*
X3490986Y1676712D01*
G01X3496721Y1677962D02*
Y1669004D01*
X3497341Y1667128D01*
X3498581Y1665879D01*
X3500131Y1665462D01*
X3501681Y1665879D01*
X3502921Y1667128D01*
X3503541Y1669004D01*
Y1677962D01*
G01X3509431Y1665462D02*
Y1677962D01*
X3513306D01*
X3514546Y1677337D01*
X3515321Y1676504D01*
X3515631Y1674837D01*
X3515321Y1673170D01*
X3514391Y1672129D01*
X3513306Y1671504D01*
X3509431D01*
G01X3513306D02*
X3515631Y1665462D01*
G01X3528031D02*
X3521831D01*
Y1677962D01*
X3528031D01*
G01X3525551Y1671920D02*
X3521831D01*
G01X3530925Y2403333D02*
X3531545Y2403958D01*
X3532010Y2404999D01*
X3532320Y2406458D01*
X3532010Y2407708D01*
X3531390Y2408541D01*
X3530305Y2409166D01*
X3526120D01*
Y2396666D01*
X3531235D01*
X3532320Y2397499D01*
X3532940Y2398749D01*
X3533250Y2400208D01*
X3532940Y2401666D01*
X3532010Y2402916D01*
X3530925Y2403333D01*
X3526120D01*
G01X3538675Y2396666D02*
Y2409166D01*
X3541775D01*
X3543015Y2408541D01*
X3543945Y2407708D01*
X3544720Y2406458D01*
X3545340Y2404999D01*
X3545495Y2402916D01*
X3545340Y2400833D01*
X3544720Y2399374D01*
X3543945Y2398124D01*
X3543015Y2397291D01*
X3541775Y2396666D01*
X3538675D01*
G01X3549835Y2392499D02*
X3559135D01*
G01X3563630Y2398332D02*
X3564870Y2397291D01*
X3566265Y2396666D01*
X3567505D01*
X3568745Y2397291D01*
X3569675Y2398332D01*
X3570140Y2399791D01*
X3569830Y2401249D01*
X3569055Y2402499D01*
X3567660Y2403333D01*
X3565800Y2403749D01*
X3564715Y2404583D01*
X3564250Y2406041D01*
X3564560Y2407499D01*
X3565335Y2408541D01*
X3566420Y2409166D01*
X3567505D01*
X3568590Y2408749D01*
X3569520Y2407708D01*
G01X3577425Y2409166D02*
X3581145D01*
G01X3579285D02*
Y2396666D01*
G01X3577425D02*
X3581145D01*
G01X3588740Y2409166D02*
X3594630D01*
X3588740Y2396666D01*
X3594630D01*
G01X3607185D02*
X3600985D01*
Y2409166D01*
X3607185D01*
G01X3604705Y2403124D02*
X3600985D01*
G01X3536004Y2032653D02*
X3536624Y2033278D01*
X3537089Y2034319D01*
X3537399Y2035778D01*
X3537089Y2037028D01*
X3536469Y2037861D01*
X3535384Y2038486D01*
X3531199D01*
Y2025986D01*
X3536314D01*
X3537399Y2026819D01*
X3538019Y2028069D01*
X3538329Y2029528D01*
X3538019Y2030986D01*
X3537089Y2032236D01*
X3536004Y2032653D01*
X3531199D01*
G01X3543754Y2025986D02*
Y2038486D01*
X3546854D01*
X3548094Y2037861D01*
X3549024Y2037028D01*
X3549799Y2035778D01*
X3550419Y2034319D01*
X3550574Y2032236D01*
X3550419Y2030153D01*
X3549799Y2028694D01*
X3549024Y2027444D01*
X3548094Y2026611D01*
X3546854Y2025986D01*
X3543754D01*
G01X3554914Y2021819D02*
X3564214D01*
G01X3568709Y2027652D02*
X3569949Y2026611D01*
X3571344Y2025986D01*
X3572584D01*
X3573824Y2026611D01*
X3574754Y2027652D01*
X3575219Y2029111D01*
X3574909Y2030569D01*
X3574134Y2031819D01*
X3572739Y2032653D01*
X3570879Y2033069D01*
X3569794Y2033903D01*
X3569329Y2035361D01*
X3569639Y2036819D01*
X3570414Y2037861D01*
X3571499Y2038486D01*
X3572584D01*
X3573669Y2038069D01*
X3574599Y2037028D01*
G01X3582504Y2038486D02*
X3586224D01*
G01X3584364D02*
Y2025986D01*
G01X3582504D02*
X3586224D01*
G01X3593819Y2038486D02*
X3599709D01*
X3593819Y2025986D01*
X3599709D01*
G01X3612264D02*
X3606064D01*
Y2038486D01*
X3612264D01*
G01X3609784Y2032444D02*
X3606064D01*
G01X3548285Y2371666D02*
Y2384166D01*
X3546425Y2381666D01*
G01Y2371666D02*
X3550145D01*
G01X3560375D02*
X3560685Y2374374D01*
X3561150Y2376666D01*
X3561770Y2378749D01*
X3562545Y2381041D01*
X3563785Y2384166D01*
X3557585D01*
G01X3573085Y2371249D02*
X3572775Y2371458D01*
Y2371874D01*
X3573085Y2372083D01*
X3573395Y2371874D01*
Y2371458D01*
X3573085Y2371249D01*
G01X3585175Y2371666D02*
X3585485Y2374374D01*
X3585950Y2376666D01*
X3586570Y2378749D01*
X3587345Y2381041D01*
X3588585Y2384166D01*
X3582385D01*
G01X3553364Y2000986D02*
Y2013486D01*
X3551504Y2010986D01*
G01Y2000986D02*
X3555224D01*
G01X3565454D02*
X3565764Y2003694D01*
X3566229Y2005986D01*
X3566849Y2008069D01*
X3567624Y2010361D01*
X3568864Y2013486D01*
X3562664D01*
G01X3578164Y2000569D02*
X3577854Y2000778D01*
Y2001194D01*
X3578164Y2001403D01*
X3578474Y2001194D01*
Y2000778D01*
X3578164Y2000569D01*
G01X3590254Y2000986D02*
X3590564Y2003694D01*
X3591029Y2005986D01*
X3591649Y2008069D01*
X3592424Y2010361D01*
X3593664Y2013486D01*
X3587464D01*
G01X3554036Y2825015D02*
X3554656Y2825640D01*
X3555121Y2826681D01*
X3555431Y2828140D01*
X3555121Y2829390D01*
X3554501Y2830223D01*
X3553416Y2830848D01*
X3549231D01*
Y2818348D01*
X3554346D01*
X3555431Y2819181D01*
X3556051Y2820431D01*
X3556361Y2821890D01*
X3556051Y2823348D01*
X3555121Y2824598D01*
X3554036Y2825015D01*
X3549231D01*
G01X3561786Y2818348D02*
Y2830848D01*
X3564886D01*
X3566126Y2830223D01*
X3567056Y2829390D01*
X3567831Y2828140D01*
X3568451Y2826681D01*
X3568606Y2824598D01*
X3568451Y2822515D01*
X3567831Y2821056D01*
X3567056Y2819806D01*
X3566126Y2818973D01*
X3564886Y2818348D01*
X3561786D01*
G01X3572946Y2814181D02*
X3582246D01*
G01X3586741Y2820014D02*
X3587981Y2818973D01*
X3589376Y2818348D01*
X3590616D01*
X3591856Y2818973D01*
X3592786Y2820014D01*
X3593251Y2821473D01*
X3592941Y2822931D01*
X3592166Y2824181D01*
X3590771Y2825015D01*
X3588911Y2825431D01*
X3587826Y2826265D01*
X3587361Y2827723D01*
X3587671Y2829181D01*
X3588446Y2830223D01*
X3589531Y2830848D01*
X3590616D01*
X3591701Y2830431D01*
X3592631Y2829390D01*
G01X3600536Y2830848D02*
X3604256D01*
G01X3602396D02*
Y2818348D01*
G01X3600536D02*
X3604256D01*
G01X3611851Y2830848D02*
X3617741D01*
X3611851Y2818348D01*
X3617741D01*
G01X3630296D02*
X3624096D01*
Y2830848D01*
X3630296D01*
G01X3627816Y2824806D02*
X3624096D01*
G01X3565903Y96963D02*
Y109463D01*
X3573033Y96963D01*
Y109463D01*
G01X3581868Y96963D02*
X3580628Y97171D01*
X3579543Y98004D01*
X3578613Y99255D01*
X3577993Y100713D01*
X3577683Y102380D01*
Y104046D01*
X3577993Y105713D01*
X3578613Y107171D01*
X3579543Y108421D01*
X3580628Y109255D01*
X3581868Y109463D01*
X3583108Y109255D01*
X3584193Y108421D01*
X3585123Y107171D01*
X3585743Y105713D01*
X3586053Y104046D01*
Y102380D01*
X3585743Y100713D01*
X3585123Y99255D01*
X3584193Y98004D01*
X3583108Y97171D01*
X3581868Y96963D01*
G01X3590703D02*
Y109463D01*
X3597833Y96963D01*
Y109463D01*
G01X3604653Y101130D02*
X3608683D01*
G01X3615968Y96963D02*
Y109463D01*
X3619688D01*
X3620928Y108838D01*
X3621858Y107380D01*
X3622168Y105713D01*
X3621858Y104046D01*
X3621083Y102796D01*
X3619688Y102171D01*
X3615968D01*
G01X3628368Y109463D02*
Y96963D01*
X3634568D01*
G01X3639993D02*
X3643868Y109463D01*
X3647743Y96963D01*
G01X3646348Y101338D02*
X3641388D01*
G01X3656268Y109463D02*
Y96963D01*
G01X3652703Y109463D02*
X3659833D01*
G01X3671768Y96963D02*
X3665568D01*
Y109463D01*
X3671768D01*
G01X3669288Y103421D02*
X3665568D01*
G01X3677658Y96963D02*
Y109463D01*
X3680758D01*
X3681998Y108838D01*
X3682928Y108005D01*
X3683703Y106755D01*
X3684323Y105296D01*
X3684478Y103213D01*
X3684323Y101130D01*
X3683703Y99671D01*
X3682928Y98421D01*
X3681998Y97588D01*
X3680758Y96963D01*
X3677658D01*
G01X3565903Y130113D02*
Y142613D01*
X3573033Y130113D01*
Y142613D01*
G01X3581868Y130113D02*
X3580628Y130321D01*
X3579543Y131154D01*
X3578613Y132405D01*
X3577993Y133863D01*
X3577683Y135530D01*
Y137196D01*
X3577993Y138863D01*
X3578613Y140321D01*
X3579543Y141571D01*
X3580628Y142405D01*
X3581868Y142613D01*
X3583108Y142405D01*
X3584193Y141571D01*
X3585123Y140321D01*
X3585743Y138863D01*
X3586053Y137196D01*
Y135530D01*
X3585743Y133863D01*
X3585123Y132405D01*
X3584193Y131154D01*
X3583108Y130321D01*
X3581868Y130113D01*
G01X3590703D02*
Y142613D01*
X3597833Y130113D01*
Y142613D01*
G01X3604653Y134280D02*
X3608683D01*
G01X3615968Y130113D02*
Y142613D01*
X3619688D01*
X3620928Y141988D01*
X3621858Y140530D01*
X3622168Y138863D01*
X3621858Y137196D01*
X3621083Y135946D01*
X3619688Y135321D01*
X3615968D01*
G01X3628368Y142613D02*
Y130113D01*
X3634568D01*
G01X3639993D02*
X3643868Y142613D01*
X3647743Y130113D01*
G01X3646348Y134488D02*
X3641388D01*
G01X3656268Y142613D02*
Y130113D01*
G01X3652703Y142613D02*
X3659833D01*
G01X3671768Y130113D02*
X3665568D01*
Y142613D01*
X3671768D01*
G01X3669288Y136571D02*
X3665568D01*
G01X3677658Y130113D02*
Y142613D01*
X3680758D01*
X3681998Y141988D01*
X3682928Y141155D01*
X3683703Y139905D01*
X3684323Y138446D01*
X3684478Y136363D01*
X3684323Y134280D01*
X3683703Y132821D01*
X3682928Y131571D01*
X3681998Y130738D01*
X3680758Y130113D01*
X3677658D01*
G01X3565903Y163263D02*
Y175763D01*
X3573033Y163263D01*
Y175763D01*
G01X3581868Y163263D02*
X3580628Y163471D01*
X3579543Y164304D01*
X3578613Y165555D01*
X3577993Y167013D01*
X3577683Y168680D01*
Y170346D01*
X3577993Y172013D01*
X3578613Y173471D01*
X3579543Y174721D01*
X3580628Y175555D01*
X3581868Y175763D01*
X3583108Y175555D01*
X3584193Y174721D01*
X3585123Y173471D01*
X3585743Y172013D01*
X3586053Y170346D01*
Y168680D01*
X3585743Y167013D01*
X3585123Y165555D01*
X3584193Y164304D01*
X3583108Y163471D01*
X3581868Y163263D01*
G01X3590703D02*
Y175763D01*
X3597833Y163263D01*
Y175763D01*
G01X3604653Y167430D02*
X3608683D01*
G01X3615968Y163263D02*
Y175763D01*
X3619688D01*
X3620928Y175138D01*
X3621858Y173680D01*
X3622168Y172013D01*
X3621858Y170346D01*
X3621083Y169096D01*
X3619688Y168471D01*
X3615968D01*
G01X3628368Y175763D02*
Y163263D01*
X3634568D01*
G01X3639993D02*
X3643868Y175763D01*
X3647743Y163263D01*
G01X3646348Y167638D02*
X3641388D01*
G01X3656268Y175763D02*
Y163263D01*
G01X3652703Y175763D02*
X3659833D01*
G01X3671768Y163263D02*
X3665568D01*
Y175763D01*
X3671768D01*
G01X3669288Y169721D02*
X3665568D01*
G01X3677658Y163263D02*
Y175763D01*
X3680758D01*
X3681998Y175138D01*
X3682928Y174305D01*
X3683703Y173055D01*
X3684323Y171596D01*
X3684478Y169513D01*
X3684323Y167430D01*
X3683703Y165971D01*
X3682928Y164721D01*
X3681998Y163888D01*
X3680758Y163263D01*
X3677658D01*
G01X3565903Y196413D02*
Y208913D01*
X3573033Y196413D01*
Y208913D01*
G01X3581868Y196413D02*
X3580628Y196621D01*
X3579543Y197454D01*
X3578613Y198705D01*
X3577993Y200163D01*
X3577683Y201830D01*
Y203496D01*
X3577993Y205163D01*
X3578613Y206621D01*
X3579543Y207871D01*
X3580628Y208705D01*
X3581868Y208913D01*
X3583108Y208705D01*
X3584193Y207871D01*
X3585123Y206621D01*
X3585743Y205163D01*
X3586053Y203496D01*
Y201830D01*
X3585743Y200163D01*
X3585123Y198705D01*
X3584193Y197454D01*
X3583108Y196621D01*
X3581868Y196413D01*
G01X3590703D02*
Y208913D01*
X3597833Y196413D01*
Y208913D01*
G01X3604653Y200580D02*
X3608683D01*
G01X3615968Y196413D02*
Y208913D01*
X3619688D01*
X3620928Y208288D01*
X3621858Y206830D01*
X3622168Y205163D01*
X3621858Y203496D01*
X3621083Y202246D01*
X3619688Y201621D01*
X3615968D01*
G01X3628368Y208913D02*
Y196413D01*
X3634568D01*
G01X3639993D02*
X3643868Y208913D01*
X3647743Y196413D01*
G01X3646348Y200788D02*
X3641388D01*
G01X3656268Y208913D02*
Y196413D01*
G01X3652703Y208913D02*
X3659833D01*
G01X3671768Y196413D02*
X3665568D01*
Y208913D01*
X3671768D01*
G01X3669288Y202871D02*
X3665568D01*
G01X3677658Y196413D02*
Y208913D01*
X3680758D01*
X3681998Y208288D01*
X3682928Y207455D01*
X3683703Y206205D01*
X3684323Y204746D01*
X3684478Y202663D01*
X3684323Y200580D01*
X3683703Y199121D01*
X3682928Y197871D01*
X3681998Y197038D01*
X3680758Y196413D01*
X3677658D01*
G01X3565903Y229563D02*
Y242063D01*
X3573033Y229563D01*
Y242063D01*
G01X3581868Y229563D02*
X3580628Y229771D01*
X3579543Y230604D01*
X3578613Y231855D01*
X3577993Y233313D01*
X3577683Y234980D01*
Y236646D01*
X3577993Y238313D01*
X3578613Y239771D01*
X3579543Y241021D01*
X3580628Y241855D01*
X3581868Y242063D01*
X3583108Y241855D01*
X3584193Y241021D01*
X3585123Y239771D01*
X3585743Y238313D01*
X3586053Y236646D01*
Y234980D01*
X3585743Y233313D01*
X3585123Y231855D01*
X3584193Y230604D01*
X3583108Y229771D01*
X3581868Y229563D01*
G01X3590703D02*
Y242063D01*
X3597833Y229563D01*
Y242063D01*
G01X3604653Y233730D02*
X3608683D01*
G01X3615968Y229563D02*
Y242063D01*
X3619688D01*
X3620928Y241438D01*
X3621858Y239980D01*
X3622168Y238313D01*
X3621858Y236646D01*
X3621083Y235396D01*
X3619688Y234771D01*
X3615968D01*
G01X3628368Y242063D02*
Y229563D01*
X3634568D01*
G01X3639993D02*
X3643868Y242063D01*
X3647743Y229563D01*
G01X3646348Y233938D02*
X3641388D01*
G01X3656268Y242063D02*
Y229563D01*
G01X3652703Y242063D02*
X3659833D01*
G01X3671768Y229563D02*
X3665568D01*
Y242063D01*
X3671768D01*
G01X3669288Y236021D02*
X3665568D01*
G01X3677658Y229563D02*
Y242063D01*
X3680758D01*
X3681998Y241438D01*
X3682928Y240605D01*
X3683703Y239355D01*
X3684323Y237896D01*
X3684478Y235813D01*
X3684323Y233730D01*
X3683703Y232271D01*
X3682928Y231021D01*
X3681998Y230188D01*
X3680758Y229563D01*
X3677658D01*
G01X3565903Y262713D02*
Y275213D01*
X3573033Y262713D01*
Y275213D01*
G01X3581868Y262713D02*
X3580628Y262921D01*
X3579543Y263754D01*
X3578613Y265005D01*
X3577993Y266463D01*
X3577683Y268130D01*
Y269796D01*
X3577993Y271463D01*
X3578613Y272921D01*
X3579543Y274171D01*
X3580628Y275005D01*
X3581868Y275213D01*
X3583108Y275005D01*
X3584193Y274171D01*
X3585123Y272921D01*
X3585743Y271463D01*
X3586053Y269796D01*
Y268130D01*
X3585743Y266463D01*
X3585123Y265005D01*
X3584193Y263754D01*
X3583108Y262921D01*
X3581868Y262713D01*
G01X3590703D02*
Y275213D01*
X3597833Y262713D01*
Y275213D01*
G01X3604653Y266880D02*
X3608683D01*
G01X3615968Y262713D02*
Y275213D01*
X3619688D01*
X3620928Y274588D01*
X3621858Y273130D01*
X3622168Y271463D01*
X3621858Y269796D01*
X3621083Y268546D01*
X3619688Y267921D01*
X3615968D01*
G01X3628368Y275213D02*
Y262713D01*
X3634568D01*
G01X3639993D02*
X3643868Y275213D01*
X3647743Y262713D01*
G01X3646348Y267088D02*
X3641388D01*
G01X3656268Y275213D02*
Y262713D01*
G01X3652703Y275213D02*
X3659833D01*
G01X3671768Y262713D02*
X3665568D01*
Y275213D01*
X3671768D01*
G01X3669288Y269171D02*
X3665568D01*
G01X3677658Y262713D02*
Y275213D01*
X3680758D01*
X3681998Y274588D01*
X3682928Y273755D01*
X3683703Y272505D01*
X3684323Y271046D01*
X3684478Y268963D01*
X3684323Y266880D01*
X3683703Y265421D01*
X3682928Y264171D01*
X3681998Y263338D01*
X3680758Y262713D01*
X3677658D01*
G01X3565903Y295863D02*
Y308363D01*
X3573033Y295863D01*
Y308363D01*
G01X3581868Y295863D02*
X3580628Y296071D01*
X3579543Y296904D01*
X3578613Y298155D01*
X3577993Y299613D01*
X3577683Y301280D01*
Y302946D01*
X3577993Y304613D01*
X3578613Y306071D01*
X3579543Y307321D01*
X3580628Y308155D01*
X3581868Y308363D01*
X3583108Y308155D01*
X3584193Y307321D01*
X3585123Y306071D01*
X3585743Y304613D01*
X3586053Y302946D01*
Y301280D01*
X3585743Y299613D01*
X3585123Y298155D01*
X3584193Y296904D01*
X3583108Y296071D01*
X3581868Y295863D01*
G01X3590703D02*
Y308363D01*
X3597833Y295863D01*
Y308363D01*
G01X3604653Y300030D02*
X3608683D01*
G01X3615968Y295863D02*
Y308363D01*
X3619688D01*
X3620928Y307738D01*
X3621858Y306280D01*
X3622168Y304613D01*
X3621858Y302946D01*
X3621083Y301696D01*
X3619688Y301071D01*
X3615968D01*
G01X3628368Y308363D02*
Y295863D01*
X3634568D01*
G01X3639993D02*
X3643868Y308363D01*
X3647743Y295863D01*
G01X3646348Y300238D02*
X3641388D01*
G01X3656268Y308363D02*
Y295863D01*
G01X3652703Y308363D02*
X3659833D01*
G01X3671768Y295863D02*
X3665568D01*
Y308363D01*
X3671768D01*
G01X3669288Y302321D02*
X3665568D01*
G01X3677658Y295863D02*
Y308363D01*
X3680758D01*
X3681998Y307738D01*
X3682928Y306905D01*
X3683703Y305655D01*
X3684323Y304196D01*
X3684478Y302113D01*
X3684323Y300030D01*
X3683703Y298571D01*
X3682928Y297321D01*
X3681998Y296488D01*
X3680758Y295863D01*
X3677658D01*
G01X3565903Y329013D02*
Y341513D01*
X3573033Y329013D01*
Y341513D01*
G01X3581868Y329013D02*
X3580628Y329221D01*
X3579543Y330054D01*
X3578613Y331305D01*
X3577993Y332763D01*
X3577683Y334430D01*
Y336096D01*
X3577993Y337763D01*
X3578613Y339221D01*
X3579543Y340471D01*
X3580628Y341305D01*
X3581868Y341513D01*
X3583108Y341305D01*
X3584193Y340471D01*
X3585123Y339221D01*
X3585743Y337763D01*
X3586053Y336096D01*
Y334430D01*
X3585743Y332763D01*
X3585123Y331305D01*
X3584193Y330054D01*
X3583108Y329221D01*
X3581868Y329013D01*
G01X3590703D02*
Y341513D01*
X3597833Y329013D01*
Y341513D01*
G01X3604653Y333180D02*
X3608683D01*
G01X3615968Y329013D02*
Y341513D01*
X3619688D01*
X3620928Y340888D01*
X3621858Y339430D01*
X3622168Y337763D01*
X3621858Y336096D01*
X3621083Y334846D01*
X3619688Y334221D01*
X3615968D01*
G01X3628368Y341513D02*
Y329013D01*
X3634568D01*
G01X3639993D02*
X3643868Y341513D01*
X3647743Y329013D01*
G01X3646348Y333388D02*
X3641388D01*
G01X3656268Y341513D02*
Y329013D01*
G01X3652703Y341513D02*
X3659833D01*
G01X3671768Y329013D02*
X3665568D01*
Y341513D01*
X3671768D01*
G01X3669288Y335471D02*
X3665568D01*
G01X3677658Y329013D02*
Y341513D01*
X3680758D01*
X3681998Y340888D01*
X3682928Y340055D01*
X3683703Y338805D01*
X3684323Y337346D01*
X3684478Y335263D01*
X3684323Y333180D01*
X3683703Y331721D01*
X3682928Y330471D01*
X3681998Y329638D01*
X3680758Y329013D01*
X3677658D01*
G01X3565903Y362163D02*
Y374663D01*
X3573033Y362163D01*
Y374663D01*
G01X3581868Y362163D02*
X3580628Y362371D01*
X3579543Y363204D01*
X3578613Y364455D01*
X3577993Y365913D01*
X3577683Y367580D01*
Y369246D01*
X3577993Y370913D01*
X3578613Y372371D01*
X3579543Y373621D01*
X3580628Y374455D01*
X3581868Y374663D01*
X3583108Y374455D01*
X3584193Y373621D01*
X3585123Y372371D01*
X3585743Y370913D01*
X3586053Y369246D01*
Y367580D01*
X3585743Y365913D01*
X3585123Y364455D01*
X3584193Y363204D01*
X3583108Y362371D01*
X3581868Y362163D01*
G01X3590703D02*
Y374663D01*
X3597833Y362163D01*
Y374663D01*
G01X3604653Y366330D02*
X3608683D01*
G01X3615968Y362163D02*
Y374663D01*
X3619688D01*
X3620928Y374038D01*
X3621858Y372580D01*
X3622168Y370913D01*
X3621858Y369246D01*
X3621083Y367996D01*
X3619688Y367371D01*
X3615968D01*
G01X3628368Y374663D02*
Y362163D01*
X3634568D01*
G01X3639993D02*
X3643868Y374663D01*
X3647743Y362163D01*
G01X3646348Y366538D02*
X3641388D01*
G01X3656268Y374663D02*
Y362163D01*
G01X3652703Y374663D02*
X3659833D01*
G01X3671768Y362163D02*
X3665568D01*
Y374663D01*
X3671768D01*
G01X3669288Y368621D02*
X3665568D01*
G01X3677658Y362163D02*
Y374663D01*
X3680758D01*
X3681998Y374038D01*
X3682928Y373205D01*
X3683703Y371955D01*
X3684323Y370496D01*
X3684478Y368413D01*
X3684323Y366330D01*
X3683703Y364871D01*
X3682928Y363621D01*
X3681998Y362788D01*
X3680758Y362163D01*
X3677658D01*
G01X3565903Y395313D02*
Y407813D01*
X3573033Y395313D01*
Y407813D01*
G01X3581868Y395313D02*
X3580628Y395521D01*
X3579543Y396354D01*
X3578613Y397605D01*
X3577993Y399063D01*
X3577683Y400730D01*
Y402396D01*
X3577993Y404063D01*
X3578613Y405521D01*
X3579543Y406771D01*
X3580628Y407605D01*
X3581868Y407813D01*
X3583108Y407605D01*
X3584193Y406771D01*
X3585123Y405521D01*
X3585743Y404063D01*
X3586053Y402396D01*
Y400730D01*
X3585743Y399063D01*
X3585123Y397605D01*
X3584193Y396354D01*
X3583108Y395521D01*
X3581868Y395313D01*
G01X3590703D02*
Y407813D01*
X3597833Y395313D01*
Y407813D01*
G01X3604653Y399480D02*
X3608683D01*
G01X3615968Y395313D02*
Y407813D01*
X3619688D01*
X3620928Y407188D01*
X3621858Y405730D01*
X3622168Y404063D01*
X3621858Y402396D01*
X3621083Y401146D01*
X3619688Y400521D01*
X3615968D01*
G01X3628368Y407813D02*
Y395313D01*
X3634568D01*
G01X3639993D02*
X3643868Y407813D01*
X3647743Y395313D01*
G01X3646348Y399688D02*
X3641388D01*
G01X3656268Y407813D02*
Y395313D01*
G01X3652703Y407813D02*
X3659833D01*
G01X3671768Y395313D02*
X3665568D01*
Y407813D01*
X3671768D01*
G01X3669288Y401771D02*
X3665568D01*
G01X3677658Y395313D02*
Y407813D01*
X3680758D01*
X3681998Y407188D01*
X3682928Y406355D01*
X3683703Y405105D01*
X3684323Y403646D01*
X3684478Y401563D01*
X3684323Y399480D01*
X3683703Y398021D01*
X3682928Y396771D01*
X3681998Y395938D01*
X3680758Y395313D01*
X3677658D01*
G01X3566471Y1672129D02*
X3567091Y1672754D01*
X3567556Y1673795D01*
X3567866Y1675254D01*
X3567556Y1676504D01*
X3566936Y1677337D01*
X3565851Y1677962D01*
X3561666D01*
Y1665462D01*
X3566781D01*
X3567866Y1666295D01*
X3568486Y1667545D01*
X3568796Y1669004D01*
X3568486Y1670462D01*
X3567556Y1671712D01*
X3566471Y1672129D01*
X3561666D01*
G01X3574221Y1665462D02*
Y1677962D01*
X3577321D01*
X3578561Y1677337D01*
X3579491Y1676504D01*
X3580266Y1675254D01*
X3580886Y1673795D01*
X3581041Y1671712D01*
X3580886Y1669629D01*
X3580266Y1668170D01*
X3579491Y1666920D01*
X3578561Y1666087D01*
X3577321Y1665462D01*
X3574221D01*
G01X3585381Y1661295D02*
X3594681D01*
G01X3599176Y1667128D02*
X3600416Y1666087D01*
X3601811Y1665462D01*
X3603051D01*
X3604291Y1666087D01*
X3605221Y1667128D01*
X3605686Y1668587D01*
X3605376Y1670045D01*
X3604601Y1671295D01*
X3603206Y1672129D01*
X3601346Y1672545D01*
X3600261Y1673379D01*
X3599796Y1674837D01*
X3600106Y1676295D01*
X3600881Y1677337D01*
X3601966Y1677962D01*
X3603051D01*
X3604136Y1677545D01*
X3605066Y1676504D01*
G01X3612971Y1677962D02*
X3616691D01*
G01X3614831D02*
Y1665462D01*
G01X3612971D02*
X3616691D01*
G01X3624286Y1677962D02*
X3630176D01*
X3624286Y1665462D01*
X3630176D01*
G01X3642731D02*
X3636531D01*
Y1677962D01*
X3642731D01*
G01X3640251Y1671920D02*
X3636531D01*
G01X3571396Y2743348D02*
Y2755848D01*
X3569536Y2753348D01*
G01Y2743348D02*
X3573256D01*
G01X3581161Y2744806D02*
X3582246Y2743765D01*
X3583486Y2743348D01*
X3584726Y2743765D01*
X3585811Y2745014D01*
X3586586Y2746890D01*
X3586896Y2748765D01*
Y2751056D01*
X3586586Y2752931D01*
X3585811Y2754598D01*
X3584881Y2755431D01*
X3583796Y2755848D01*
X3582556Y2755431D01*
X3581626Y2754598D01*
X3581006Y2753348D01*
X3580696Y2751681D01*
X3581006Y2750223D01*
X3581781Y2748765D01*
X3582711Y2747931D01*
X3583796Y2747723D01*
X3585036Y2748139D01*
X3585966Y2749181D01*
X3586896Y2751056D01*
G01X3596196Y2742931D02*
X3595886Y2743140D01*
Y2743556D01*
X3596196Y2743765D01*
X3596506Y2743556D01*
Y2743140D01*
X3596196Y2742931D01*
G01X3605961Y2744806D02*
X3607046Y2743765D01*
X3608286Y2743348D01*
X3609526Y2743765D01*
X3610611Y2745014D01*
X3611386Y2746890D01*
X3611696Y2748765D01*
Y2751056D01*
X3611386Y2752931D01*
X3610611Y2754598D01*
X3609681Y2755431D01*
X3608596Y2755848D01*
X3607356Y2755431D01*
X3606426Y2754598D01*
X3605806Y2753348D01*
X3605496Y2751681D01*
X3605806Y2750223D01*
X3606581Y2748765D01*
X3607511Y2747931D01*
X3608596Y2747723D01*
X3609836Y2748139D01*
X3610766Y2749181D01*
X3611696Y2751056D01*
G01X3571396Y2768348D02*
Y2780848D01*
X3569536Y2778348D01*
G01Y2768348D02*
X3573256D01*
G01X3583486D02*
X3583796Y2771056D01*
X3584261Y2773348D01*
X3584881Y2775431D01*
X3585656Y2777723D01*
X3586896Y2780848D01*
X3580696D01*
G01X3596196Y2767931D02*
X3595886Y2768140D01*
Y2768556D01*
X3596196Y2768765D01*
X3596506Y2768556D01*
Y2768140D01*
X3596196Y2767931D01*
G01X3608286Y2768348D02*
X3608596Y2771056D01*
X3609061Y2773348D01*
X3609681Y2775431D01*
X3610456Y2777723D01*
X3611696Y2780848D01*
X3605496D01*
G01X3571396Y2793348D02*
Y2805848D01*
X3569536Y2803348D01*
G01Y2793348D02*
X3573256D01*
G01X3580386Y2795223D02*
X3581316Y2794181D01*
X3582401Y2793556D01*
X3583796Y2793348D01*
X3585191Y2793765D01*
X3586276Y2794598D01*
X3587051Y2796056D01*
X3587206Y2797723D01*
X3586896Y2799390D01*
X3586121Y2800431D01*
X3585036Y2801265D01*
X3583951Y2801473D01*
X3582866Y2801265D01*
X3581471Y2800431D01*
X3581936Y2805848D01*
X3586121D01*
G01X3596196Y2792931D02*
X3595886Y2793140D01*
Y2793556D01*
X3596196Y2793765D01*
X3596506Y2793556D01*
Y2793140D01*
X3596196Y2792931D01*
G01X3608286Y2793348D02*
X3608596Y2796056D01*
X3609061Y2798348D01*
X3609681Y2800431D01*
X3610456Y2802723D01*
X3611696Y2805848D01*
X3605496D01*
G01X3591168Y-35637D02*
Y-23137D01*
X3594888D01*
X3596128Y-23762D01*
X3597058Y-25220D01*
X3597368Y-26887D01*
X3597058Y-28554D01*
X3596283Y-29804D01*
X3594888Y-30429D01*
X3591168D01*
G01X3603568Y-23137D02*
Y-35637D01*
X3609768D01*
G01X3615193D02*
X3619068Y-23137D01*
X3622943Y-35637D01*
G01X3621548Y-31262D02*
X3616588D01*
G01X3631468Y-23137D02*
Y-35637D01*
G01X3627903Y-23137D02*
X3635033D01*
G01X3646968Y-35637D02*
X3640768D01*
Y-23137D01*
X3646968D01*
G01X3644488Y-29179D02*
X3640768D01*
G01X3652858Y-35637D02*
Y-23137D01*
X3655958D01*
X3657198Y-23762D01*
X3658128Y-24595D01*
X3658903Y-25845D01*
X3659523Y-27304D01*
X3659678Y-29387D01*
X3659523Y-31470D01*
X3658903Y-32929D01*
X3658128Y-34179D01*
X3657198Y-35012D01*
X3655958Y-35637D01*
X3652858D01*
G01X3591168Y-2487D02*
Y10013D01*
X3594888D01*
X3596128Y9388D01*
X3597058Y7930D01*
X3597368Y6263D01*
X3597058Y4596D01*
X3596283Y3346D01*
X3594888Y2721D01*
X3591168D01*
G01X3603568Y10013D02*
Y-2487D01*
X3609768D01*
G01X3615193D02*
X3619068Y10013D01*
X3622943Y-2487D01*
G01X3621548Y1888D02*
X3616588D01*
G01X3631468Y10013D02*
Y-2487D01*
G01X3627903Y10013D02*
X3635033D01*
G01X3646968Y-2487D02*
X3640768D01*
Y10013D01*
X3646968D01*
G01X3644488Y3971D02*
X3640768D01*
G01X3652858Y-2487D02*
Y10013D01*
X3655958D01*
X3657198Y9388D01*
X3658128Y8555D01*
X3658903Y7305D01*
X3659523Y5846D01*
X3659678Y3763D01*
X3659523Y1680D01*
X3658903Y221D01*
X3658128Y-1029D01*
X3657198Y-1862D01*
X3655958Y-2487D01*
X3652858D01*
G01X3591168Y30663D02*
Y43163D01*
X3594888D01*
X3596128Y42538D01*
X3597058Y41080D01*
X3597368Y39413D01*
X3597058Y37746D01*
X3596283Y36496D01*
X3594888Y35871D01*
X3591168D01*
G01X3603568Y43163D02*
Y30663D01*
X3609768D01*
G01X3615193D02*
X3619068Y43163D01*
X3622943Y30663D01*
G01X3621548Y35038D02*
X3616588D01*
G01X3631468Y43163D02*
Y30663D01*
G01X3627903Y43163D02*
X3635033D01*
G01X3646968Y30663D02*
X3640768D01*
Y43163D01*
X3646968D01*
G01X3644488Y37121D02*
X3640768D01*
G01X3652858Y30663D02*
Y43163D01*
X3655958D01*
X3657198Y42538D01*
X3658128Y41705D01*
X3658903Y40455D01*
X3659523Y38996D01*
X3659678Y36913D01*
X3659523Y34830D01*
X3658903Y33371D01*
X3658128Y32121D01*
X3657198Y31288D01*
X3655958Y30663D01*
X3652858D01*
G01X3591168Y63813D02*
Y76313D01*
X3594888D01*
X3596128Y75688D01*
X3597058Y74230D01*
X3597368Y72563D01*
X3597058Y70896D01*
X3596283Y69646D01*
X3594888Y69021D01*
X3591168D01*
G01X3603568Y76313D02*
Y63813D01*
X3609768D01*
G01X3615193D02*
X3619068Y76313D01*
X3622943Y63813D01*
G01X3621548Y68188D02*
X3616588D01*
G01X3631468Y76313D02*
Y63813D01*
G01X3627903Y76313D02*
X3635033D01*
G01X3646968Y63813D02*
X3640768D01*
Y76313D01*
X3646968D01*
G01X3644488Y70271D02*
X3640768D01*
G01X3652858Y63813D02*
Y76313D01*
X3655958D01*
X3657198Y75688D01*
X3658128Y74855D01*
X3658903Y73605D01*
X3659523Y72146D01*
X3659678Y70063D01*
X3659523Y67980D01*
X3658903Y66521D01*
X3658128Y65271D01*
X3657198Y64438D01*
X3655958Y63813D01*
X3652858D01*
G01X3591168Y428463D02*
Y440963D01*
X3594888D01*
X3596128Y440338D01*
X3597058Y438880D01*
X3597368Y437213D01*
X3597058Y435546D01*
X3596283Y434296D01*
X3594888Y433671D01*
X3591168D01*
G01X3603568Y440963D02*
Y428463D01*
X3609768D01*
G01X3615193D02*
X3619068Y440963D01*
X3622943Y428463D01*
G01X3621548Y432838D02*
X3616588D01*
G01X3631468Y440963D02*
Y428463D01*
G01X3627903Y440963D02*
X3635033D01*
G01X3646968Y428463D02*
X3640768D01*
Y440963D01*
X3646968D01*
G01X3644488Y434921D02*
X3640768D01*
G01X3652858Y428463D02*
Y440963D01*
X3655958D01*
X3657198Y440338D01*
X3658128Y439505D01*
X3658903Y438255D01*
X3659523Y436796D01*
X3659678Y434713D01*
X3659523Y432630D01*
X3658903Y431171D01*
X3658128Y429921D01*
X3657198Y429088D01*
X3655958Y428463D01*
X3652858D01*
G01X3591168Y461613D02*
Y474113D01*
X3594888D01*
X3596128Y473488D01*
X3597058Y472030D01*
X3597368Y470363D01*
X3597058Y468696D01*
X3596283Y467446D01*
X3594888Y466821D01*
X3591168D01*
G01X3603568Y474113D02*
Y461613D01*
X3609768D01*
G01X3615193D02*
X3619068Y474113D01*
X3622943Y461613D01*
G01X3621548Y465988D02*
X3616588D01*
G01X3631468Y474113D02*
Y461613D01*
G01X3627903Y474113D02*
X3635033D01*
G01X3646968Y461613D02*
X3640768D01*
Y474113D01*
X3646968D01*
G01X3644488Y468071D02*
X3640768D01*
G01X3652858Y461613D02*
Y474113D01*
X3655958D01*
X3657198Y473488D01*
X3658128Y472655D01*
X3658903Y471405D01*
X3659523Y469946D01*
X3659678Y467863D01*
X3659523Y465780D01*
X3658903Y464321D01*
X3658128Y463071D01*
X3657198Y462238D01*
X3655958Y461613D01*
X3652858D01*
G01X3591168Y494763D02*
Y507263D01*
X3594888D01*
X3596128Y506638D01*
X3597058Y505180D01*
X3597368Y503513D01*
X3597058Y501846D01*
X3596283Y500596D01*
X3594888Y499971D01*
X3591168D01*
G01X3603568Y507263D02*
Y494763D01*
X3609768D01*
G01X3615193D02*
X3619068Y507263D01*
X3622943Y494763D01*
G01X3621548Y499138D02*
X3616588D01*
G01X3631468Y507263D02*
Y494763D01*
G01X3627903Y507263D02*
X3635033D01*
G01X3646968Y494763D02*
X3640768D01*
Y507263D01*
X3646968D01*
G01X3644488Y501221D02*
X3640768D01*
G01X3652858Y494763D02*
Y507263D01*
X3655958D01*
X3657198Y506638D01*
X3658128Y505805D01*
X3658903Y504555D01*
X3659523Y503096D01*
X3659678Y501013D01*
X3659523Y498930D01*
X3658903Y497471D01*
X3658128Y496221D01*
X3657198Y495388D01*
X3655958Y494763D01*
X3652858D01*
G01X3591168Y527913D02*
Y540413D01*
X3594888D01*
X3596128Y539788D01*
X3597058Y538330D01*
X3597368Y536663D01*
X3597058Y534996D01*
X3596283Y533746D01*
X3594888Y533121D01*
X3591168D01*
G01X3603568Y540413D02*
Y527913D01*
X3609768D01*
G01X3615193D02*
X3619068Y540413D01*
X3622943Y527913D01*
G01X3621548Y532288D02*
X3616588D01*
G01X3631468Y540413D02*
Y527913D01*
G01X3627903Y540413D02*
X3635033D01*
G01X3646968Y527913D02*
X3640768D01*
Y540413D01*
X3646968D01*
G01X3644488Y534371D02*
X3640768D01*
G01X3652858Y527913D02*
Y540413D01*
X3655958D01*
X3657198Y539788D01*
X3658128Y538955D01*
X3658903Y537705D01*
X3659523Y536246D01*
X3659678Y534163D01*
X3659523Y532080D01*
X3658903Y530621D01*
X3658128Y529371D01*
X3657198Y528538D01*
X3655958Y527913D01*
X3652858D01*
G01X3591168Y561063D02*
Y573563D01*
X3594888D01*
X3596128Y572938D01*
X3597058Y571480D01*
X3597368Y569813D01*
X3597058Y568146D01*
X3596283Y566896D01*
X3594888Y566271D01*
X3591168D01*
G01X3603568Y573563D02*
Y561063D01*
X3609768D01*
G01X3615193D02*
X3619068Y573563D01*
X3622943Y561063D01*
G01X3621548Y565438D02*
X3616588D01*
G01X3631468Y573563D02*
Y561063D01*
G01X3627903Y573563D02*
X3635033D01*
G01X3646968Y561063D02*
X3640768D01*
Y573563D01*
X3646968D01*
G01X3644488Y567521D02*
X3640768D01*
G01X3652858Y561063D02*
Y573563D01*
X3655958D01*
X3657198Y572938D01*
X3658128Y572105D01*
X3658903Y570855D01*
X3659523Y569396D01*
X3659678Y567313D01*
X3659523Y565230D01*
X3658903Y563771D01*
X3658128Y562521D01*
X3657198Y561688D01*
X3655958Y561063D01*
X3652858D01*
G01X3591168Y594213D02*
Y606713D01*
X3594888D01*
X3596128Y606088D01*
X3597058Y604630D01*
X3597368Y602963D01*
X3597058Y601296D01*
X3596283Y600046D01*
X3594888Y599421D01*
X3591168D01*
G01X3603568Y606713D02*
Y594213D01*
X3609768D01*
G01X3615193D02*
X3619068Y606713D01*
X3622943Y594213D01*
G01X3621548Y598588D02*
X3616588D01*
G01X3631468Y606713D02*
Y594213D01*
G01X3627903Y606713D02*
X3635033D01*
G01X3646968Y594213D02*
X3640768D01*
Y606713D01*
X3646968D01*
G01X3644488Y600671D02*
X3640768D01*
G01X3652858Y594213D02*
Y606713D01*
X3655958D01*
X3657198Y606088D01*
X3658128Y605255D01*
X3658903Y604005D01*
X3659523Y602546D01*
X3659678Y600463D01*
X3659523Y598380D01*
X3658903Y596921D01*
X3658128Y595671D01*
X3657198Y594838D01*
X3655958Y594213D01*
X3652858D01*
G01X3591168Y627363D02*
Y639863D01*
X3594888D01*
X3596128Y639238D01*
X3597058Y637780D01*
X3597368Y636113D01*
X3597058Y634446D01*
X3596283Y633196D01*
X3594888Y632571D01*
X3591168D01*
G01X3603568Y639863D02*
Y627363D01*
X3609768D01*
G01X3615193D02*
X3619068Y639863D01*
X3622943Y627363D01*
G01X3621548Y631738D02*
X3616588D01*
G01X3631468Y639863D02*
Y627363D01*
G01X3627903Y639863D02*
X3635033D01*
G01X3646968Y627363D02*
X3640768D01*
Y639863D01*
X3646968D01*
G01X3644488Y633821D02*
X3640768D01*
G01X3652858Y627363D02*
Y639863D01*
X3655958D01*
X3657198Y639238D01*
X3658128Y638405D01*
X3658903Y637155D01*
X3659523Y635696D01*
X3659678Y633613D01*
X3659523Y631530D01*
X3658903Y630071D01*
X3658128Y628821D01*
X3657198Y627988D01*
X3655958Y627363D01*
X3652858D01*
G01X3591168Y660513D02*
Y673013D01*
X3594888D01*
X3596128Y672388D01*
X3597058Y670930D01*
X3597368Y669263D01*
X3597058Y667596D01*
X3596283Y666346D01*
X3594888Y665721D01*
X3591168D01*
G01X3603568Y673013D02*
Y660513D01*
X3609768D01*
G01X3615193D02*
X3619068Y673013D01*
X3622943Y660513D01*
G01X3621548Y664888D02*
X3616588D01*
G01X3631468Y673013D02*
Y660513D01*
G01X3627903Y673013D02*
X3635033D01*
G01X3646968Y660513D02*
X3640768D01*
Y673013D01*
X3646968D01*
G01X3644488Y666971D02*
X3640768D01*
G01X3652858Y660513D02*
Y673013D01*
X3655958D01*
X3657198Y672388D01*
X3658128Y671555D01*
X3658903Y670305D01*
X3659523Y668846D01*
X3659678Y666763D01*
X3659523Y664680D01*
X3658903Y663221D01*
X3658128Y661971D01*
X3657198Y661138D01*
X3655958Y660513D01*
X3652858D01*
G01X3591168Y693663D02*
Y706163D01*
X3594888D01*
X3596128Y705538D01*
X3597058Y704080D01*
X3597368Y702413D01*
X3597058Y700746D01*
X3596283Y699496D01*
X3594888Y698871D01*
X3591168D01*
G01X3603568Y706163D02*
Y693663D01*
X3609768D01*
G01X3615193D02*
X3619068Y706163D01*
X3622943Y693663D01*
G01X3621548Y698038D02*
X3616588D01*
G01X3631468Y706163D02*
Y693663D01*
G01X3627903Y706163D02*
X3635033D01*
G01X3646968Y693663D02*
X3640768D01*
Y706163D01*
X3646968D01*
G01X3644488Y700121D02*
X3640768D01*
G01X3652858Y693663D02*
Y706163D01*
X3655958D01*
X3657198Y705538D01*
X3658128Y704705D01*
X3658903Y703455D01*
X3659523Y701996D01*
X3659678Y699913D01*
X3659523Y697830D01*
X3658903Y696371D01*
X3658128Y695121D01*
X3657198Y694288D01*
X3655958Y693663D01*
X3652858D01*
G01X3591168Y726813D02*
Y739313D01*
X3594888D01*
X3596128Y738688D01*
X3597058Y737230D01*
X3597368Y735563D01*
X3597058Y733896D01*
X3596283Y732646D01*
X3594888Y732021D01*
X3591168D01*
G01X3603568Y739313D02*
Y726813D01*
X3609768D01*
G01X3615193D02*
X3619068Y739313D01*
X3622943Y726813D01*
G01X3621548Y731188D02*
X3616588D01*
G01X3631468Y739313D02*
Y726813D01*
G01X3627903Y739313D02*
X3635033D01*
G01X3646968Y726813D02*
X3640768D01*
Y739313D01*
X3646968D01*
G01X3644488Y733271D02*
X3640768D01*
G01X3652858Y726813D02*
Y739313D01*
X3655958D01*
X3657198Y738688D01*
X3658128Y737855D01*
X3658903Y736605D01*
X3659523Y735146D01*
X3659678Y733063D01*
X3659523Y730980D01*
X3658903Y729521D01*
X3658128Y728271D01*
X3657198Y727438D01*
X3655958Y726813D01*
X3652858D01*
G01X3591168Y759963D02*
Y772463D01*
X3594888D01*
X3596128Y771838D01*
X3597058Y770380D01*
X3597368Y768713D01*
X3597058Y767046D01*
X3596283Y765796D01*
X3594888Y765171D01*
X3591168D01*
G01X3603568Y772463D02*
Y759963D01*
X3609768D01*
G01X3615193D02*
X3619068Y772463D01*
X3622943Y759963D01*
G01X3621548Y764338D02*
X3616588D01*
G01X3631468Y772463D02*
Y759963D01*
G01X3627903Y772463D02*
X3635033D01*
G01X3646968Y759963D02*
X3640768D01*
Y772463D01*
X3646968D01*
G01X3644488Y766421D02*
X3640768D01*
G01X3652858Y759963D02*
Y772463D01*
X3655958D01*
X3657198Y771838D01*
X3658128Y771005D01*
X3658903Y769755D01*
X3659523Y768296D01*
X3659678Y766213D01*
X3659523Y764130D01*
X3658903Y762671D01*
X3658128Y761421D01*
X3657198Y760588D01*
X3655958Y759963D01*
X3652858D01*
G01X3591168Y793113D02*
Y805613D01*
X3594888D01*
X3596128Y804988D01*
X3597058Y803530D01*
X3597368Y801863D01*
X3597058Y800196D01*
X3596283Y798946D01*
X3594888Y798321D01*
X3591168D01*
G01X3603568Y805613D02*
Y793113D01*
X3609768D01*
G01X3615193D02*
X3619068Y805613D01*
X3622943Y793113D01*
G01X3621548Y797488D02*
X3616588D01*
G01X3631468Y805613D02*
Y793113D01*
G01X3627903Y805613D02*
X3635033D01*
G01X3646968Y793113D02*
X3640768D01*
Y805613D01*
X3646968D01*
G01X3644488Y799571D02*
X3640768D01*
G01X3652858Y793113D02*
Y805613D01*
X3655958D01*
X3657198Y804988D01*
X3658128Y804155D01*
X3658903Y802905D01*
X3659523Y801446D01*
X3659678Y799363D01*
X3659523Y797280D01*
X3658903Y795821D01*
X3658128Y794571D01*
X3657198Y793738D01*
X3655958Y793113D01*
X3652858D01*
G01X3591168Y826263D02*
Y838763D01*
X3594888D01*
X3596128Y838138D01*
X3597058Y836680D01*
X3597368Y835013D01*
X3597058Y833346D01*
X3596283Y832096D01*
X3594888Y831471D01*
X3591168D01*
G01X3603568Y838763D02*
Y826263D01*
X3609768D01*
G01X3615193D02*
X3619068Y838763D01*
X3622943Y826263D01*
G01X3621548Y830638D02*
X3616588D01*
G01X3631468Y838763D02*
Y826263D01*
G01X3627903Y838763D02*
X3635033D01*
G01X3646968Y826263D02*
X3640768D01*
Y838763D01*
X3646968D01*
G01X3644488Y832721D02*
X3640768D01*
G01X3652858Y826263D02*
Y838763D01*
X3655958D01*
X3657198Y838138D01*
X3658128Y837305D01*
X3658903Y836055D01*
X3659523Y834596D01*
X3659678Y832513D01*
X3659523Y830430D01*
X3658903Y828971D01*
X3658128Y827721D01*
X3657198Y826888D01*
X3655958Y826263D01*
X3652858D01*
G01X3591168Y859413D02*
Y871913D01*
X3594888D01*
X3596128Y871288D01*
X3597058Y869830D01*
X3597368Y868163D01*
X3597058Y866496D01*
X3596283Y865246D01*
X3594888Y864621D01*
X3591168D01*
G01X3603568Y871913D02*
Y859413D01*
X3609768D01*
G01X3615193D02*
X3619068Y871913D01*
X3622943Y859413D01*
G01X3621548Y863788D02*
X3616588D01*
G01X3631468Y871913D02*
Y859413D01*
G01X3627903Y871913D02*
X3635033D01*
G01X3646968Y859413D02*
X3640768D01*
Y871913D01*
X3646968D01*
G01X3644488Y865871D02*
X3640768D01*
G01X3652858Y859413D02*
Y871913D01*
X3655958D01*
X3657198Y871288D01*
X3658128Y870455D01*
X3658903Y869205D01*
X3659523Y867746D01*
X3659678Y865663D01*
X3659523Y863580D01*
X3658903Y862121D01*
X3658128Y860871D01*
X3657198Y860038D01*
X3655958Y859413D01*
X3652858D01*
G01X3591168Y892563D02*
Y905063D01*
X3594888D01*
X3596128Y904438D01*
X3597058Y902980D01*
X3597368Y901313D01*
X3597058Y899646D01*
X3596283Y898396D01*
X3594888Y897771D01*
X3591168D01*
G01X3603568Y905063D02*
Y892563D01*
X3609768D01*
G01X3615193D02*
X3619068Y905063D01*
X3622943Y892563D01*
G01X3621548Y896938D02*
X3616588D01*
G01X3631468Y905063D02*
Y892563D01*
G01X3627903Y905063D02*
X3635033D01*
G01X3646968Y892563D02*
X3640768D01*
Y905063D01*
X3646968D01*
G01X3644488Y899021D02*
X3640768D01*
G01X3652858Y892563D02*
Y905063D01*
X3655958D01*
X3657198Y904438D01*
X3658128Y903605D01*
X3658903Y902355D01*
X3659523Y900896D01*
X3659678Y898813D01*
X3659523Y896730D01*
X3658903Y895271D01*
X3658128Y894021D01*
X3657198Y893188D01*
X3655958Y892563D01*
X3652858D01*
G01X3591168Y925713D02*
Y938213D01*
X3594888D01*
X3596128Y937588D01*
X3597058Y936130D01*
X3597368Y934463D01*
X3597058Y932796D01*
X3596283Y931546D01*
X3594888Y930921D01*
X3591168D01*
G01X3603568Y938213D02*
Y925713D01*
X3609768D01*
G01X3615193D02*
X3619068Y938213D01*
X3622943Y925713D01*
G01X3621548Y930088D02*
X3616588D01*
G01X3631468Y938213D02*
Y925713D01*
G01X3627903Y938213D02*
X3635033D01*
G01X3646968Y925713D02*
X3640768D01*
Y938213D01*
X3646968D01*
G01X3644488Y932171D02*
X3640768D01*
G01X3652858Y925713D02*
Y938213D01*
X3655958D01*
X3657198Y937588D01*
X3658128Y936755D01*
X3658903Y935505D01*
X3659523Y934046D01*
X3659678Y931963D01*
X3659523Y929880D01*
X3658903Y928421D01*
X3658128Y927171D01*
X3657198Y926338D01*
X3655958Y925713D01*
X3652858D01*
G01X3591168Y958863D02*
Y971363D01*
X3594888D01*
X3596128Y970738D01*
X3597058Y969280D01*
X3597368Y967613D01*
X3597058Y965946D01*
X3596283Y964696D01*
X3594888Y964071D01*
X3591168D01*
G01X3603568Y971363D02*
Y958863D01*
X3609768D01*
G01X3615193D02*
X3619068Y971363D01*
X3622943Y958863D01*
G01X3621548Y963238D02*
X3616588D01*
G01X3631468Y971363D02*
Y958863D01*
G01X3627903Y971363D02*
X3635033D01*
G01X3646968Y958863D02*
X3640768D01*
Y971363D01*
X3646968D01*
G01X3644488Y965321D02*
X3640768D01*
G01X3652858Y958863D02*
Y971363D01*
X3655958D01*
X3657198Y970738D01*
X3658128Y969905D01*
X3658903Y968655D01*
X3659523Y967196D01*
X3659678Y965113D01*
X3659523Y963030D01*
X3658903Y961571D01*
X3658128Y960321D01*
X3657198Y959488D01*
X3655958Y958863D01*
X3652858D01*
G01X3591168Y987938D02*
Y1000438D01*
X3594888D01*
X3596128Y999813D01*
X3597058Y998355D01*
X3597368Y996688D01*
X3597058Y995021D01*
X3596283Y993771D01*
X3594888Y993146D01*
X3591168D01*
G01X3603568Y1000438D02*
Y987938D01*
X3609768D01*
G01X3615193D02*
X3619068Y1000438D01*
X3622943Y987938D01*
G01X3621548Y992313D02*
X3616588D01*
G01X3631468Y1000438D02*
Y987938D01*
G01X3627903Y1000438D02*
X3635033D01*
G01X3646968Y987938D02*
X3640768D01*
Y1000438D01*
X3646968D01*
G01X3644488Y994396D02*
X3640768D01*
G01X3652858Y987938D02*
Y1000438D01*
X3655958D01*
X3657198Y999813D01*
X3658128Y998980D01*
X3658903Y997730D01*
X3659523Y996271D01*
X3659678Y994188D01*
X3659523Y992105D01*
X3658903Y990646D01*
X3658128Y989396D01*
X3657198Y988563D01*
X3655958Y987938D01*
X3652858D01*
G01X3583831Y1640462D02*
Y1652962D01*
X3581971Y1650462D01*
G01Y1640462D02*
X3585691D01*
G01X3595921D02*
X3596231Y1643170D01*
X3596696Y1645462D01*
X3597316Y1647545D01*
X3598091Y1649837D01*
X3599331Y1652962D01*
X3593131D01*
G01X3608631Y1640045D02*
X3608321Y1640254D01*
Y1640670D01*
X3608631Y1640879D01*
X3608941Y1640670D01*
Y1640254D01*
X3608631Y1640045D01*
G01X3620721Y1640462D02*
X3621031Y1643170D01*
X3621496Y1645462D01*
X3622116Y1647545D01*
X3622891Y1649837D01*
X3624131Y1652962D01*
X3617931D01*
G01X3659575Y2453333D02*
X3660195Y2453958D01*
X3660660Y2454999D01*
X3660970Y2456458D01*
X3660660Y2457708D01*
X3660040Y2458541D01*
X3658955Y2459166D01*
X3654770D01*
Y2446666D01*
X3659885D01*
X3660970Y2447499D01*
X3661590Y2448749D01*
X3661900Y2450208D01*
X3661590Y2451666D01*
X3660660Y2452916D01*
X3659575Y2453333D01*
X3654770D01*
G01X3666860Y2446666D02*
X3670735Y2459166D01*
X3674610Y2446666D01*
G01X3673215Y2451041D02*
X3668255D01*
G01X3686545Y2458124D02*
X3685615Y2458749D01*
X3684530Y2459166D01*
X3683290D01*
X3681895Y2458541D01*
X3680810Y2457499D01*
X3680035Y2456249D01*
X3679415Y2454166D01*
X3679260Y2452291D01*
X3679570Y2450416D01*
X3680035Y2449166D01*
X3680965Y2447916D01*
X3682050Y2447083D01*
X3683135Y2446666D01*
X3684220D01*
X3685305Y2447083D01*
X3686235Y2447707D01*
X3687010Y2448541D01*
G01X3692125Y2446666D02*
Y2459166D01*
G01X3698015D02*
X3692125Y2451457D01*
G01X3698945Y2446666D02*
X3694760Y2454999D01*
G01X3704525Y2446666D02*
Y2459166D01*
X3707625D01*
X3708865Y2458541D01*
X3709795Y2457708D01*
X3710570Y2456458D01*
X3711190Y2454999D01*
X3711345Y2452916D01*
X3711190Y2450833D01*
X3710570Y2449374D01*
X3709795Y2448124D01*
X3708865Y2447291D01*
X3707625Y2446666D01*
X3704525D01*
G01X3717235D02*
Y2459166D01*
X3721110D01*
X3722350Y2458541D01*
X3723125Y2457708D01*
X3723435Y2456041D01*
X3723125Y2454374D01*
X3722195Y2453333D01*
X3721110Y2452708D01*
X3717235D01*
G01X3721110D02*
X3723435Y2446666D01*
G01X3730875Y2459166D02*
X3734595D01*
G01X3732735D02*
Y2446666D01*
G01X3730875D02*
X3734595D01*
G01X3742035Y2459166D02*
Y2446666D01*
X3748235D01*
G01X3754435Y2459166D02*
Y2446666D01*
X3760635D01*
G01X3769935Y2446249D02*
X3769625Y2446458D01*
Y2446874D01*
X3769935Y2447083D01*
X3770245Y2446874D01*
Y2446458D01*
X3769935Y2446249D01*
G01Y2451874D02*
X3769625Y2452083D01*
Y2452499D01*
X3769935Y2452708D01*
X3770245Y2452499D01*
Y2452083D01*
X3769935Y2451874D01*
G01X3794735Y2459166D02*
Y2446666D01*
G01X3791170Y2459166D02*
X3798300D01*
G01X3807135Y2446666D02*
X3805895Y2446874D01*
X3804810Y2447707D01*
X3803880Y2448958D01*
X3803260Y2450416D01*
X3802950Y2452083D01*
Y2453749D01*
X3803260Y2455416D01*
X3803880Y2456874D01*
X3804810Y2458124D01*
X3805895Y2458958D01*
X3807135Y2459166D01*
X3808375Y2458958D01*
X3809460Y2458124D01*
X3810390Y2456874D01*
X3811010Y2455416D01*
X3811320Y2453749D01*
Y2452083D01*
X3811010Y2450416D01*
X3810390Y2448958D01*
X3809460Y2447707D01*
X3808375Y2446874D01*
X3807135Y2446666D01*
G01X3816435D02*
Y2459166D01*
X3820155D01*
X3821395Y2458541D01*
X3822325Y2457083D01*
X3822635Y2455416D01*
X3822325Y2453749D01*
X3821550Y2452499D01*
X3820155Y2451874D01*
X3816435D01*
G01X3844335Y2459166D02*
Y2446666D01*
G01X3842165Y2454999D02*
X3846505D01*
G01X3856735Y2446666D02*
X3855805Y2446874D01*
X3854875Y2447707D01*
X3854255Y2449166D01*
X3853945Y2450833D01*
X3854255Y2452499D01*
X3854875Y2453958D01*
X3855805Y2454791D01*
X3856735Y2454999D01*
X3857665Y2454791D01*
X3858595Y2453958D01*
X3859215Y2452499D01*
X3859370Y2450833D01*
X3859215Y2449166D01*
X3858595Y2447707D01*
X3857665Y2446874D01*
X3856735Y2446666D01*
G01X3882465Y2452916D02*
X3885565D01*
Y2449166D01*
X3884635Y2447916D01*
X3883550Y2447083D01*
X3882000Y2446666D01*
X3880450Y2447083D01*
X3879365Y2447916D01*
X3878435Y2449166D01*
X3877815Y2450624D01*
X3877505Y2452291D01*
Y2453749D01*
X3877815Y2454999D01*
X3878435Y2456458D01*
X3879365Y2457708D01*
X3880295Y2458541D01*
X3881535Y2459166D01*
X3882620D01*
X3883860Y2458749D01*
X3884790Y2457916D01*
G01X3890370Y2446666D02*
Y2459166D01*
X3897500Y2446666D01*
Y2459166D01*
G01X3902925Y2446666D02*
Y2459166D01*
X3906025D01*
X3907265Y2458541D01*
X3908195Y2457708D01*
X3908970Y2456458D01*
X3909590Y2454999D01*
X3909745Y2452916D01*
X3909590Y2450833D01*
X3908970Y2449374D01*
X3908195Y2448124D01*
X3907265Y2447291D01*
X3906025Y2446666D01*
X3902925D01*
G01X3915790Y2451874D02*
X3916875Y2453333D01*
X3917805Y2454166D01*
X3919045Y2454583D01*
X3920130Y2454166D01*
X3920905Y2453333D01*
X3921525Y2452083D01*
X3921680Y2450624D01*
X3921525Y2449374D01*
X3920905Y2448124D01*
X3919975Y2447083D01*
X3918890Y2446666D01*
X3917650Y2447083D01*
X3916565Y2448332D01*
X3915945Y2450208D01*
X3915790Y2452291D01*
X3916100Y2454999D01*
X3916565Y2456458D01*
X3917340Y2457916D01*
X3918425Y2458958D01*
X3919510Y2459166D01*
X3920595Y2458749D01*
X3921370Y2457708D01*
G01X3665739Y2050986D02*
X3669614Y2063486D01*
X3673489Y2050986D01*
G01X3672094Y2055361D02*
X3667134D01*
G01X3678914Y2063486D02*
Y2050986D01*
X3685114D01*
G01X3691314Y2063486D02*
Y2050986D01*
X3697514D01*
G01X3715804Y2063486D02*
Y2054528D01*
X3716424Y2052652D01*
X3717664Y2051403D01*
X3719214Y2050986D01*
X3720764Y2051403D01*
X3722004Y2052652D01*
X3722624Y2054528D01*
Y2063486D01*
G01X3728049Y2050986D02*
Y2063486D01*
X3735179Y2050986D01*
Y2063486D01*
G01X3742154D02*
X3745874D01*
G01X3744014D02*
Y2050986D01*
G01X3742154D02*
X3745874D01*
G01X3756414Y2063486D02*
Y2050986D01*
G01X3752849Y2063486D02*
X3759979D01*
G01X3765559Y2052652D02*
X3766799Y2051611D01*
X3768194Y2050986D01*
X3769434D01*
X3770674Y2051611D01*
X3771604Y2052652D01*
X3772069Y2054111D01*
X3771759Y2055569D01*
X3770984Y2056819D01*
X3769589Y2057653D01*
X3767729Y2058069D01*
X3766644Y2058903D01*
X3766179Y2060361D01*
X3766489Y2061819D01*
X3767264Y2062861D01*
X3768349Y2063486D01*
X3769434D01*
X3770519Y2063069D01*
X3771449Y2062028D01*
G01X3789739Y2050986D02*
X3793614Y2063486D01*
X3797489Y2050986D01*
G01X3796094Y2055361D02*
X3791134D01*
G01X3802914Y2050986D02*
Y2063486D01*
X3806789D01*
X3808029Y2062861D01*
X3808804Y2062028D01*
X3809114Y2060361D01*
X3808804Y2058694D01*
X3807874Y2057653D01*
X3806789Y2057028D01*
X3802914D01*
G01X3806789D02*
X3809114Y2050986D01*
G01X3821514D02*
X3815314D01*
Y2063486D01*
X3821514D01*
G01X3819034Y2057444D02*
X3815314D01*
G01X3841354Y2063486D02*
X3845074D01*
G01X3843214D02*
Y2050986D01*
G01X3841354D02*
X3845074D01*
G01X3852049D02*
Y2063486D01*
X3859179Y2050986D01*
Y2063486D01*
G01X3876384Y2050986D02*
Y2063486D01*
X3880414Y2053069D01*
X3884444Y2063486D01*
Y2050986D01*
G01X3890954Y2063486D02*
X3894674D01*
G01X3892814D02*
Y2050986D01*
G01X3890954D02*
X3894674D01*
G01X3902114Y2063486D02*
Y2050986D01*
X3908314D01*
G01X3914359Y2052652D02*
X3915599Y2051611D01*
X3916994Y2050986D01*
X3918234D01*
X3919474Y2051611D01*
X3920404Y2052652D01*
X3920869Y2054111D01*
X3920559Y2055569D01*
X3919784Y2056819D01*
X3918389Y2057653D01*
X3916529Y2058069D01*
X3915444Y2058903D01*
X3914979Y2060361D01*
X3915289Y2061819D01*
X3916064Y2062861D01*
X3917149Y2063486D01*
X3918234D01*
X3919319Y2063069D01*
X3920249Y2062028D01*
G01X3664654Y2082653D02*
X3665274Y2083278D01*
X3665739Y2084319D01*
X3666049Y2085778D01*
X3665739Y2087028D01*
X3665119Y2087861D01*
X3664034Y2088486D01*
X3659849D01*
Y2075986D01*
X3664964D01*
X3666049Y2076819D01*
X3666669Y2078069D01*
X3666979Y2079528D01*
X3666669Y2080986D01*
X3665739Y2082236D01*
X3664654Y2082653D01*
X3659849D01*
G01X3671939Y2075986D02*
X3675814Y2088486D01*
X3679689Y2075986D01*
G01X3678294Y2080361D02*
X3673334D01*
G01X3691624Y2087444D02*
X3690694Y2088069D01*
X3689609Y2088486D01*
X3688369D01*
X3686974Y2087861D01*
X3685889Y2086819D01*
X3685114Y2085569D01*
X3684494Y2083486D01*
X3684339Y2081611D01*
X3684649Y2079736D01*
X3685114Y2078486D01*
X3686044Y2077236D01*
X3687129Y2076403D01*
X3688214Y2075986D01*
X3689299D01*
X3690384Y2076403D01*
X3691314Y2077027D01*
X3692089Y2077861D01*
G01X3697204Y2075986D02*
Y2088486D01*
G01X3703094D02*
X3697204Y2080777D01*
G01X3704024Y2075986D02*
X3699839Y2084319D01*
G01X3709604Y2075986D02*
Y2088486D01*
X3712704D01*
X3713944Y2087861D01*
X3714874Y2087028D01*
X3715649Y2085778D01*
X3716269Y2084319D01*
X3716424Y2082236D01*
X3716269Y2080153D01*
X3715649Y2078694D01*
X3714874Y2077444D01*
X3713944Y2076611D01*
X3712704Y2075986D01*
X3709604D01*
G01X3722314D02*
Y2088486D01*
X3726189D01*
X3727429Y2087861D01*
X3728204Y2087028D01*
X3728514Y2085361D01*
X3728204Y2083694D01*
X3727274Y2082653D01*
X3726189Y2082028D01*
X3722314D01*
G01X3726189D02*
X3728514Y2075986D01*
G01X3735954Y2088486D02*
X3739674D01*
G01X3737814D02*
Y2075986D01*
G01X3735954D02*
X3739674D01*
G01X3747114Y2088486D02*
Y2075986D01*
X3753314D01*
G01X3759514Y2088486D02*
Y2075986D01*
X3765714D01*
G01X3775014Y2075569D02*
X3774704Y2075778D01*
Y2076194D01*
X3775014Y2076403D01*
X3775324Y2076194D01*
Y2075778D01*
X3775014Y2075569D01*
G01Y2081194D02*
X3774704Y2081403D01*
Y2081819D01*
X3775014Y2082028D01*
X3775324Y2081819D01*
Y2081403D01*
X3775014Y2081194D01*
G01X3799814Y2088486D02*
Y2075986D01*
G01X3796249Y2088486D02*
X3803379D01*
G01X3812214Y2075986D02*
X3810974Y2076194D01*
X3809889Y2077027D01*
X3808959Y2078278D01*
X3808339Y2079736D01*
X3808029Y2081403D01*
Y2083069D01*
X3808339Y2084736D01*
X3808959Y2086194D01*
X3809889Y2087444D01*
X3810974Y2088278D01*
X3812214Y2088486D01*
X3813454Y2088278D01*
X3814539Y2087444D01*
X3815469Y2086194D01*
X3816089Y2084736D01*
X3816399Y2083069D01*
Y2081403D01*
X3816089Y2079736D01*
X3815469Y2078278D01*
X3814539Y2077027D01*
X3813454Y2076194D01*
X3812214Y2075986D01*
G01X3821514D02*
Y2088486D01*
X3825234D01*
X3826474Y2087861D01*
X3827404Y2086403D01*
X3827714Y2084736D01*
X3827404Y2083069D01*
X3826629Y2081819D01*
X3825234Y2081194D01*
X3821514D01*
G01X3849414Y2088486D02*
Y2075986D01*
G01X3847244Y2084319D02*
X3851584D01*
G01X3861814Y2075986D02*
X3860884Y2076194D01*
X3859954Y2077027D01*
X3859334Y2078486D01*
X3859024Y2080153D01*
X3859334Y2081819D01*
X3859954Y2083278D01*
X3860884Y2084111D01*
X3861814Y2084319D01*
X3862744Y2084111D01*
X3863674Y2083278D01*
X3864294Y2081819D01*
X3864449Y2080153D01*
X3864294Y2078486D01*
X3863674Y2077027D01*
X3862744Y2076194D01*
X3861814Y2075986D01*
G01X3887544Y2082236D02*
X3890644D01*
Y2078486D01*
X3889714Y2077236D01*
X3888629Y2076403D01*
X3887079Y2075986D01*
X3885529Y2076403D01*
X3884444Y2077236D01*
X3883514Y2078486D01*
X3882894Y2079944D01*
X3882584Y2081611D01*
Y2083069D01*
X3882894Y2084319D01*
X3883514Y2085778D01*
X3884444Y2087028D01*
X3885374Y2087861D01*
X3886614Y2088486D01*
X3887699D01*
X3888939Y2088069D01*
X3889869Y2087236D01*
G01X3895449Y2075986D02*
Y2088486D01*
X3902579Y2075986D01*
Y2088486D01*
G01X3908004Y2075986D02*
Y2088486D01*
X3911104D01*
X3912344Y2087861D01*
X3913274Y2087028D01*
X3914049Y2085778D01*
X3914669Y2084319D01*
X3914824Y2082236D01*
X3914669Y2080153D01*
X3914049Y2078694D01*
X3913274Y2077444D01*
X3912344Y2076611D01*
X3911104Y2075986D01*
X3908004D01*
G01X3920404Y2077861D02*
X3921334Y2076819D01*
X3922419Y2076194D01*
X3923814Y2075986D01*
X3925209Y2076403D01*
X3926294Y2077236D01*
X3927069Y2078694D01*
X3927224Y2080361D01*
X3926914Y2082028D01*
X3926139Y2083069D01*
X3925054Y2083903D01*
X3923969Y2084111D01*
X3922884Y2083903D01*
X3921489Y2083069D01*
X3921954Y2088486D01*
X3926139D01*
G01X3660660Y2421666D02*
X3664535Y2434166D01*
X3668410Y2421666D01*
G01X3667015Y2426041D02*
X3662055D01*
G01X3673835Y2434166D02*
Y2421666D01*
X3680035D01*
G01X3686235Y2434166D02*
Y2421666D01*
X3692435D01*
G01X3710725Y2434166D02*
Y2425208D01*
X3711345Y2423332D01*
X3712585Y2422083D01*
X3714135Y2421666D01*
X3715685Y2422083D01*
X3716925Y2423332D01*
X3717545Y2425208D01*
Y2434166D01*
G01X3722970Y2421666D02*
Y2434166D01*
X3730100Y2421666D01*
Y2434166D01*
G01X3737075D02*
X3740795D01*
G01X3738935D02*
Y2421666D01*
G01X3737075D02*
X3740795D01*
G01X3751335Y2434166D02*
Y2421666D01*
G01X3747770Y2434166D02*
X3754900D01*
G01X3760480Y2423332D02*
X3761720Y2422291D01*
X3763115Y2421666D01*
X3764355D01*
X3765595Y2422291D01*
X3766525Y2423332D01*
X3766990Y2424791D01*
X3766680Y2426249D01*
X3765905Y2427499D01*
X3764510Y2428333D01*
X3762650Y2428749D01*
X3761565Y2429583D01*
X3761100Y2431041D01*
X3761410Y2432499D01*
X3762185Y2433541D01*
X3763270Y2434166D01*
X3764355D01*
X3765440Y2433749D01*
X3766370Y2432708D01*
G01X3784660Y2421666D02*
X3788535Y2434166D01*
X3792410Y2421666D01*
G01X3791015Y2426041D02*
X3786055D01*
G01X3797835Y2421666D02*
Y2434166D01*
X3801710D01*
X3802950Y2433541D01*
X3803725Y2432708D01*
X3804035Y2431041D01*
X3803725Y2429374D01*
X3802795Y2428333D01*
X3801710Y2427708D01*
X3797835D01*
G01X3801710D02*
X3804035Y2421666D01*
G01X3816435D02*
X3810235D01*
Y2434166D01*
X3816435D01*
G01X3813955Y2428124D02*
X3810235D01*
G01X3836275Y2434166D02*
X3839995D01*
G01X3838135D02*
Y2421666D01*
G01X3836275D02*
X3839995D01*
G01X3846970D02*
Y2434166D01*
X3854100Y2421666D01*
Y2434166D01*
G01X3871305Y2421666D02*
Y2434166D01*
X3875335Y2423749D01*
X3879365Y2434166D01*
Y2421666D01*
G01X3885875Y2434166D02*
X3889595D01*
G01X3887735D02*
Y2421666D01*
G01X3885875D02*
X3889595D01*
G01X3897035Y2434166D02*
Y2421666D01*
X3903235D01*
G01X3909280Y2423332D02*
X3910520Y2422291D01*
X3911915Y2421666D01*
X3913155D01*
X3914395Y2422291D01*
X3915325Y2423332D01*
X3915790Y2424791D01*
X3915480Y2426249D01*
X3914705Y2427499D01*
X3913310Y2428333D01*
X3911450Y2428749D01*
X3910365Y2429583D01*
X3909900Y2431041D01*
X3910210Y2432499D01*
X3910985Y2433541D01*
X3912070Y2434166D01*
X3913155D01*
X3914240Y2433749D01*
X3915170Y2432708D01*
G01X3664086Y2875015D02*
X3664706Y2875640D01*
X3665171Y2876681D01*
X3665481Y2878140D01*
X3665171Y2879390D01*
X3664551Y2880223D01*
X3663466Y2880848D01*
X3659281D01*
Y2868348D01*
X3664396D01*
X3665481Y2869181D01*
X3666101Y2870431D01*
X3666411Y2871890D01*
X3666101Y2873348D01*
X3665171Y2874598D01*
X3664086Y2875015D01*
X3659281D01*
G01X3671371Y2868348D02*
X3675246Y2880848D01*
X3679121Y2868348D01*
G01X3677726Y2872723D02*
X3672766D01*
G01X3691056Y2879806D02*
X3690126Y2880431D01*
X3689041Y2880848D01*
X3687801D01*
X3686406Y2880223D01*
X3685321Y2879181D01*
X3684546Y2877931D01*
X3683926Y2875848D01*
X3683771Y2873973D01*
X3684081Y2872098D01*
X3684546Y2870848D01*
X3685476Y2869598D01*
X3686561Y2868765D01*
X3687646Y2868348D01*
X3688731D01*
X3689816Y2868765D01*
X3690746Y2869389D01*
X3691521Y2870223D01*
G01X3696636Y2868348D02*
Y2880848D01*
G01X3702526D02*
X3696636Y2873139D01*
G01X3703456Y2868348D02*
X3699271Y2876681D01*
G01X3709036Y2868348D02*
Y2880848D01*
X3712136D01*
X3713376Y2880223D01*
X3714306Y2879390D01*
X3715081Y2878140D01*
X3715701Y2876681D01*
X3715856Y2874598D01*
X3715701Y2872515D01*
X3715081Y2871056D01*
X3714306Y2869806D01*
X3713376Y2868973D01*
X3712136Y2868348D01*
X3709036D01*
G01X3721746D02*
Y2880848D01*
X3725621D01*
X3726861Y2880223D01*
X3727636Y2879390D01*
X3727946Y2877723D01*
X3727636Y2876056D01*
X3726706Y2875015D01*
X3725621Y2874390D01*
X3721746D01*
G01X3725621D02*
X3727946Y2868348D01*
G01X3735386Y2880848D02*
X3739106D01*
G01X3737246D02*
Y2868348D01*
G01X3735386D02*
X3739106D01*
G01X3746546Y2880848D02*
Y2868348D01*
X3752746D01*
G01X3758946Y2880848D02*
Y2868348D01*
X3765146D01*
G01X3774446Y2867931D02*
X3774136Y2868140D01*
Y2868556D01*
X3774446Y2868765D01*
X3774756Y2868556D01*
Y2868140D01*
X3774446Y2867931D01*
G01Y2873556D02*
X3774136Y2873765D01*
Y2874181D01*
X3774446Y2874390D01*
X3774756Y2874181D01*
Y2873765D01*
X3774446Y2873556D01*
G01X3800486Y2875015D02*
X3801106Y2875640D01*
X3801571Y2876681D01*
X3801881Y2878140D01*
X3801571Y2879390D01*
X3800951Y2880223D01*
X3799866Y2880848D01*
X3795681D01*
Y2868348D01*
X3800796D01*
X3801881Y2869181D01*
X3802501Y2870431D01*
X3802811Y2871890D01*
X3802501Y2873348D01*
X3801571Y2874598D01*
X3800486Y2875015D01*
X3795681D01*
G01X3811646Y2868348D02*
X3810406Y2868556D01*
X3809321Y2869389D01*
X3808391Y2870640D01*
X3807771Y2872098D01*
X3807461Y2873765D01*
Y2875431D01*
X3807771Y2877098D01*
X3808391Y2878556D01*
X3809321Y2879806D01*
X3810406Y2880640D01*
X3811646Y2880848D01*
X3812886Y2880640D01*
X3813971Y2879806D01*
X3814901Y2878556D01*
X3815521Y2877098D01*
X3815831Y2875431D01*
Y2873765D01*
X3815521Y2872098D01*
X3814901Y2870640D01*
X3813971Y2869389D01*
X3812886Y2868556D01*
X3811646Y2868348D01*
G01X3824046Y2880848D02*
Y2868348D01*
G01X3820481Y2880848D02*
X3827611D01*
G01X3836446D02*
Y2868348D01*
G01X3832881Y2880848D02*
X3840011D01*
G01X3848846Y2868348D02*
X3847606Y2868556D01*
X3846521Y2869389D01*
X3845591Y2870640D01*
X3844971Y2872098D01*
X3844661Y2873765D01*
Y2875431D01*
X3844971Y2877098D01*
X3845591Y2878556D01*
X3846521Y2879806D01*
X3847606Y2880640D01*
X3848846Y2880848D01*
X3850086Y2880640D01*
X3851171Y2879806D01*
X3852101Y2878556D01*
X3852721Y2877098D01*
X3853031Y2875431D01*
Y2873765D01*
X3852721Y2872098D01*
X3852101Y2870640D01*
X3851171Y2869389D01*
X3850086Y2868556D01*
X3848846Y2868348D01*
G01X3857216D02*
Y2880848D01*
X3861246Y2870431D01*
X3865276Y2880848D01*
Y2868348D01*
G01X3886046Y2880848D02*
Y2868348D01*
G01X3883876Y2876681D02*
X3888216D01*
G01X3898446Y2868348D02*
X3897516Y2868556D01*
X3896586Y2869389D01*
X3895966Y2870848D01*
X3895656Y2872515D01*
X3895966Y2874181D01*
X3896586Y2875640D01*
X3897516Y2876473D01*
X3898446Y2876681D01*
X3899376Y2876473D01*
X3900306Y2875640D01*
X3900926Y2874181D01*
X3901081Y2872515D01*
X3900926Y2870848D01*
X3900306Y2869389D01*
X3899376Y2868556D01*
X3898446Y2868348D01*
G01X3924176Y2874598D02*
X3927276D01*
Y2870848D01*
X3926346Y2869598D01*
X3925261Y2868765D01*
X3923711Y2868348D01*
X3922161Y2868765D01*
X3921076Y2869598D01*
X3920146Y2870848D01*
X3919526Y2872306D01*
X3919216Y2873973D01*
Y2875431D01*
X3919526Y2876681D01*
X3920146Y2878140D01*
X3921076Y2879390D01*
X3922006Y2880223D01*
X3923246Y2880848D01*
X3924331D01*
X3925571Y2880431D01*
X3926501Y2879598D01*
G01X3932081Y2868348D02*
Y2880848D01*
X3939211Y2868348D01*
Y2880848D01*
G01X3944636Y2868348D02*
Y2880848D01*
X3947736D01*
X3948976Y2880223D01*
X3949906Y2879390D01*
X3950681Y2878140D01*
X3951301Y2876681D01*
X3951456Y2874598D01*
X3951301Y2872515D01*
X3950681Y2871056D01*
X3949906Y2869806D01*
X3948976Y2868973D01*
X3947736Y2868348D01*
X3944636D01*
G01X3957036Y2870848D02*
X3957966Y2869389D01*
X3959206Y2868556D01*
X3960601Y2868348D01*
X3961841Y2868556D01*
X3963081Y2869598D01*
X3963856Y2870848D01*
X3964011Y2872098D01*
X3963701Y2873556D01*
X3962616Y2874598D01*
X3961531Y2875015D01*
X3960136D01*
G01X3961531D02*
X3962461Y2875640D01*
X3963236Y2876681D01*
X3963546Y2877931D01*
X3963236Y2879181D01*
X3962461Y2880223D01*
X3961066Y2880848D01*
X3959671Y2880640D01*
X3958276Y2879806D01*
G01X3695121Y1722129D02*
X3695741Y1722754D01*
X3696206Y1723795D01*
X3696516Y1725254D01*
X3696206Y1726504D01*
X3695586Y1727337D01*
X3694501Y1727962D01*
X3690316D01*
Y1715462D01*
X3695431D01*
X3696516Y1716295D01*
X3697136Y1717545D01*
X3697446Y1719004D01*
X3697136Y1720462D01*
X3696206Y1721712D01*
X3695121Y1722129D01*
X3690316D01*
G01X3702406Y1715462D02*
X3706281Y1727962D01*
X3710156Y1715462D01*
G01X3708761Y1719837D02*
X3703801D01*
G01X3722091Y1726920D02*
X3721161Y1727545D01*
X3720076Y1727962D01*
X3718836D01*
X3717441Y1727337D01*
X3716356Y1726295D01*
X3715581Y1725045D01*
X3714961Y1722962D01*
X3714806Y1721087D01*
X3715116Y1719212D01*
X3715581Y1717962D01*
X3716511Y1716712D01*
X3717596Y1715879D01*
X3718681Y1715462D01*
X3719766D01*
X3720851Y1715879D01*
X3721781Y1716503D01*
X3722556Y1717337D01*
G01X3727671Y1715462D02*
Y1727962D01*
G01X3733561D02*
X3727671Y1720253D01*
G01X3734491Y1715462D02*
X3730306Y1723795D01*
G01X3740071Y1715462D02*
Y1727962D01*
X3743171D01*
X3744411Y1727337D01*
X3745341Y1726504D01*
X3746116Y1725254D01*
X3746736Y1723795D01*
X3746891Y1721712D01*
X3746736Y1719629D01*
X3746116Y1718170D01*
X3745341Y1716920D01*
X3744411Y1716087D01*
X3743171Y1715462D01*
X3740071D01*
G01X3752781D02*
Y1727962D01*
X3756656D01*
X3757896Y1727337D01*
X3758671Y1726504D01*
X3758981Y1724837D01*
X3758671Y1723170D01*
X3757741Y1722129D01*
X3756656Y1721504D01*
X3752781D01*
G01X3756656D02*
X3758981Y1715462D01*
G01X3766421Y1727962D02*
X3770141D01*
G01X3768281D02*
Y1715462D01*
G01X3766421D02*
X3770141D01*
G01X3777581Y1727962D02*
Y1715462D01*
X3783781D01*
G01X3789981Y1727962D02*
Y1715462D01*
X3796181D01*
G01X3805481Y1715045D02*
X3805171Y1715254D01*
Y1715670D01*
X3805481Y1715879D01*
X3805791Y1715670D01*
Y1715254D01*
X3805481Y1715045D01*
G01Y1720670D02*
X3805171Y1720879D01*
Y1721295D01*
X3805481Y1721504D01*
X3805791Y1721295D01*
Y1720879D01*
X3805481Y1720670D01*
G01X3830281Y1727962D02*
Y1715462D01*
G01X3826716Y1727962D02*
X3833846D01*
G01X3842681Y1715462D02*
X3841441Y1715670D01*
X3840356Y1716503D01*
X3839426Y1717754D01*
X3838806Y1719212D01*
X3838496Y1720879D01*
Y1722545D01*
X3838806Y1724212D01*
X3839426Y1725670D01*
X3840356Y1726920D01*
X3841441Y1727754D01*
X3842681Y1727962D01*
X3843921Y1727754D01*
X3845006Y1726920D01*
X3845936Y1725670D01*
X3846556Y1724212D01*
X3846866Y1722545D01*
Y1720879D01*
X3846556Y1719212D01*
X3845936Y1717754D01*
X3845006Y1716503D01*
X3843921Y1715670D01*
X3842681Y1715462D01*
G01X3851981D02*
Y1727962D01*
X3855701D01*
X3856941Y1727337D01*
X3857871Y1725879D01*
X3858181Y1724212D01*
X3857871Y1722545D01*
X3857096Y1721295D01*
X3855701Y1720670D01*
X3851981D01*
G01X3879881Y1727962D02*
Y1715462D01*
G01X3877711Y1723795D02*
X3882051D01*
G01X3892281Y1715462D02*
X3891351Y1715670D01*
X3890421Y1716503D01*
X3889801Y1717962D01*
X3889491Y1719629D01*
X3889801Y1721295D01*
X3890421Y1722754D01*
X3891351Y1723587D01*
X3892281Y1723795D01*
X3893211Y1723587D01*
X3894141Y1722754D01*
X3894761Y1721295D01*
X3894916Y1719629D01*
X3894761Y1717962D01*
X3894141Y1716503D01*
X3893211Y1715670D01*
X3892281Y1715462D01*
G01X3918011Y1721712D02*
X3921111D01*
Y1717962D01*
X3920181Y1716712D01*
X3919096Y1715879D01*
X3917546Y1715462D01*
X3915996Y1715879D01*
X3914911Y1716712D01*
X3913981Y1717962D01*
X3913361Y1719420D01*
X3913051Y1721087D01*
Y1722545D01*
X3913361Y1723795D01*
X3913981Y1725254D01*
X3914911Y1726504D01*
X3915841Y1727337D01*
X3917081Y1727962D01*
X3918166D01*
X3919406Y1727545D01*
X3920336Y1726712D01*
G01X3925916Y1715462D02*
Y1727962D01*
X3933046Y1715462D01*
Y1727962D01*
G01X3938471Y1715462D02*
Y1727962D01*
X3941571D01*
X3942811Y1727337D01*
X3943741Y1726504D01*
X3944516Y1725254D01*
X3945136Y1723795D01*
X3945291Y1721712D01*
X3945136Y1719629D01*
X3944516Y1718170D01*
X3943741Y1716920D01*
X3942811Y1716087D01*
X3941571Y1715462D01*
X3938471D01*
G01X3956141D02*
Y1727962D01*
X3950406Y1719004D01*
X3958156D01*
G01X3682634Y2025986D02*
Y2038486D01*
X3686664Y2028069D01*
X3690694Y2038486D01*
Y2025986D01*
G01X3695499D02*
Y2038486D01*
X3702629Y2025986D01*
Y2038486D01*
G01X3714874Y2037444D02*
X3713944Y2038069D01*
X3712859Y2038486D01*
X3711619D01*
X3710224Y2037861D01*
X3709139Y2036819D01*
X3708364Y2035569D01*
X3707744Y2033486D01*
X3707589Y2031611D01*
X3707899Y2029736D01*
X3708364Y2028486D01*
X3709294Y2027236D01*
X3710379Y2026403D01*
X3711464Y2025986D01*
X3712549D01*
X3713634Y2026403D01*
X3714564Y2027027D01*
X3715339Y2027861D01*
G01X3719214Y2021819D02*
X3728514D01*
G01X3733164Y2038486D02*
Y2025986D01*
X3739364D01*
G01X3744789D02*
X3748664Y2038486D01*
X3752539Y2025986D01*
G01X3751144Y2030361D02*
X3746184D01*
G01X3761064Y2025986D02*
Y2031611D01*
X3757964Y2038486D01*
G01X3764164D02*
X3761064Y2031611D01*
G01X3776564Y2025986D02*
X3770364D01*
Y2038486D01*
X3776564D01*
G01X3774084Y2032444D02*
X3770364D01*
G01X3782764Y2025986D02*
Y2038486D01*
X3786639D01*
X3787879Y2037861D01*
X3788654Y2037028D01*
X3788964Y2035361D01*
X3788654Y2033694D01*
X3787724Y2032653D01*
X3786639Y2032028D01*
X3782764D01*
G01X3786639D02*
X3788964Y2025986D01*
G01X3677555Y2396666D02*
Y2409166D01*
X3681585Y2398749D01*
X3685615Y2409166D01*
Y2396666D01*
G01X3690420D02*
Y2409166D01*
X3697550Y2396666D01*
Y2409166D01*
G01X3709795Y2408124D02*
X3708865Y2408749D01*
X3707780Y2409166D01*
X3706540D01*
X3705145Y2408541D01*
X3704060Y2407499D01*
X3703285Y2406249D01*
X3702665Y2404166D01*
X3702510Y2402291D01*
X3702820Y2400416D01*
X3703285Y2399166D01*
X3704215Y2397916D01*
X3705300Y2397083D01*
X3706385Y2396666D01*
X3707470D01*
X3708555Y2397083D01*
X3709485Y2397707D01*
X3710260Y2398541D01*
G01X3714135Y2392499D02*
X3723435D01*
G01X3728085Y2409166D02*
Y2396666D01*
X3734285D01*
G01X3739710D02*
X3743585Y2409166D01*
X3747460Y2396666D01*
G01X3746065Y2401041D02*
X3741105D01*
G01X3755985Y2396666D02*
Y2402291D01*
X3752885Y2409166D01*
G01X3759085D02*
X3755985Y2402291D01*
G01X3771485Y2396666D02*
X3765285D01*
Y2409166D01*
X3771485D01*
G01X3769005Y2403124D02*
X3765285D01*
G01X3777685Y2396666D02*
Y2409166D01*
X3781560D01*
X3782800Y2408541D01*
X3783575Y2407708D01*
X3783885Y2406041D01*
X3783575Y2404374D01*
X3782645Y2403333D01*
X3781560Y2402708D01*
X3777685D01*
G01X3781560D02*
X3783885Y2396666D01*
G01X3683771Y2843348D02*
X3687646Y2855848D01*
X3691521Y2843348D01*
G01X3690126Y2847723D02*
X3685166D01*
G01X3696946Y2855848D02*
Y2843348D01*
X3703146D01*
G01X3709346Y2855848D02*
Y2843348D01*
X3715546D01*
G01X3733836Y2855848D02*
Y2846890D01*
X3734456Y2845014D01*
X3735696Y2843765D01*
X3737246Y2843348D01*
X3738796Y2843765D01*
X3740036Y2845014D01*
X3740656Y2846890D01*
Y2855848D01*
G01X3746081Y2843348D02*
Y2855848D01*
X3753211Y2843348D01*
Y2855848D01*
G01X3760186D02*
X3763906D01*
G01X3762046D02*
Y2843348D01*
G01X3760186D02*
X3763906D01*
G01X3774446Y2855848D02*
Y2843348D01*
G01X3770881Y2855848D02*
X3778011D01*
G01X3783591Y2845014D02*
X3784831Y2843973D01*
X3786226Y2843348D01*
X3787466D01*
X3788706Y2843973D01*
X3789636Y2845014D01*
X3790101Y2846473D01*
X3789791Y2847931D01*
X3789016Y2849181D01*
X3787621Y2850015D01*
X3785761Y2850431D01*
X3784676Y2851265D01*
X3784211Y2852723D01*
X3784521Y2854181D01*
X3785296Y2855223D01*
X3786381Y2855848D01*
X3787466D01*
X3788551Y2855431D01*
X3789481Y2854390D01*
G01X3807771Y2843348D02*
X3811646Y2855848D01*
X3815521Y2843348D01*
G01X3814126Y2847723D02*
X3809166D01*
G01X3820946Y2843348D02*
Y2855848D01*
X3824821D01*
X3826061Y2855223D01*
X3826836Y2854390D01*
X3827146Y2852723D01*
X3826836Y2851056D01*
X3825906Y2850015D01*
X3824821Y2849390D01*
X3820946D01*
G01X3824821D02*
X3827146Y2843348D01*
G01X3839546D02*
X3833346D01*
Y2855848D01*
X3839546D01*
G01X3837066Y2849806D02*
X3833346D01*
G01X3859386Y2855848D02*
X3863106D01*
G01X3861246D02*
Y2843348D01*
G01X3859386D02*
X3863106D01*
G01X3870081D02*
Y2855848D01*
X3877211Y2843348D01*
Y2855848D01*
G01X3894416Y2843348D02*
Y2855848D01*
X3898446Y2845431D01*
X3902476Y2855848D01*
Y2843348D01*
G01X3908986Y2855848D02*
X3912706D01*
G01X3910846D02*
Y2843348D01*
G01X3908986D02*
X3912706D01*
G01X3920146Y2855848D02*
Y2843348D01*
X3926346D01*
G01X3932391Y2845014D02*
X3933631Y2843973D01*
X3935026Y2843348D01*
X3936266D01*
X3937506Y2843973D01*
X3938436Y2845014D01*
X3938901Y2846473D01*
X3938591Y2847931D01*
X3937816Y2849181D01*
X3936421Y2850015D01*
X3934561Y2850431D01*
X3933476Y2851265D01*
X3933011Y2852723D01*
X3933321Y2854181D01*
X3934096Y2855223D01*
X3935181Y2855848D01*
X3936266D01*
X3937351Y2855431D01*
X3938281Y2854390D01*
G01X3708968Y793113D02*
Y805613D01*
X3707108Y803113D01*
G01Y793113D02*
X3710828D01*
G01X3717958Y795613D02*
X3718888Y794154D01*
X3720128Y793321D01*
X3721523Y793113D01*
X3722763Y793321D01*
X3724003Y794363D01*
X3724778Y795613D01*
X3724933Y796863D01*
X3724623Y798321D01*
X3723538Y799363D01*
X3722453Y799780D01*
X3721058D01*
G01X3722453D02*
X3723383Y800405D01*
X3724158Y801446D01*
X3724468Y802696D01*
X3724158Y803946D01*
X3723383Y804988D01*
X3721988Y805613D01*
X3720593Y805405D01*
X3719198Y804571D01*
G01X3730823Y798321D02*
X3731908Y799780D01*
X3732838Y800613D01*
X3734078Y801030D01*
X3735163Y800613D01*
X3735938Y799780D01*
X3736558Y798530D01*
X3736713Y797071D01*
X3736558Y795821D01*
X3735938Y794571D01*
X3735008Y793530D01*
X3733923Y793113D01*
X3732683Y793530D01*
X3731598Y794779D01*
X3730978Y796655D01*
X3730823Y798738D01*
X3731133Y801446D01*
X3731598Y802905D01*
X3732373Y804363D01*
X3733458Y805405D01*
X3734543Y805613D01*
X3735628Y805196D01*
X3736403Y804155D01*
G01X3746168Y805613D02*
X3744928Y805196D01*
X3743998Y804155D01*
X3743378Y802905D01*
X3742913Y801238D01*
X3742758Y799363D01*
X3742913Y797488D01*
X3743378Y795821D01*
X3743998Y794571D01*
X3744928Y793530D01*
X3746168Y793113D01*
X3747408Y793530D01*
X3748338Y794571D01*
X3748958Y795821D01*
X3749423Y797488D01*
X3749578Y799363D01*
X3749423Y801238D01*
X3748958Y802905D01*
X3748338Y804155D01*
X3747408Y805196D01*
X3746168Y805613D01*
G01X3699823Y836680D02*
X3700753Y837929D01*
X3701838Y838555D01*
X3703078Y838763D01*
X3704628Y838346D01*
X3705713Y837305D01*
X3706023Y836055D01*
X3705868Y834804D01*
X3705248Y833763D01*
X3702148Y831680D01*
X3700753Y830221D01*
X3699823Y828138D01*
X3699513Y826263D01*
X3706023D01*
G01X3712223Y836680D02*
X3713153Y837929D01*
X3714238Y838555D01*
X3715478Y838763D01*
X3717028Y838346D01*
X3718113Y837305D01*
X3718423Y836055D01*
X3718268Y834804D01*
X3717648Y833763D01*
X3714548Y831680D01*
X3713153Y830221D01*
X3712223Y828138D01*
X3711913Y826263D01*
X3718423D01*
G01X3724933Y827721D02*
X3726018Y826680D01*
X3727258Y826263D01*
X3728498Y826680D01*
X3729583Y827929D01*
X3730358Y829805D01*
X3730668Y831680D01*
Y833971D01*
X3730358Y835846D01*
X3729583Y837513D01*
X3728653Y838346D01*
X3727568Y838763D01*
X3726328Y838346D01*
X3725398Y837513D01*
X3724778Y836263D01*
X3724468Y834596D01*
X3724778Y833138D01*
X3725553Y831680D01*
X3726483Y830846D01*
X3727568Y830638D01*
X3728808Y831054D01*
X3729738Y832096D01*
X3730668Y833971D01*
G01X3737023Y836680D02*
X3737953Y837929D01*
X3739038Y838555D01*
X3740278Y838763D01*
X3741828Y838346D01*
X3742913Y837305D01*
X3743223Y836055D01*
X3743068Y834804D01*
X3742448Y833763D01*
X3739348Y831680D01*
X3737953Y830221D01*
X3737023Y828138D01*
X3736713Y826263D01*
X3743223D01*
G01X3749423Y831471D02*
X3750508Y832930D01*
X3751438Y833763D01*
X3752678Y834180D01*
X3753763Y833763D01*
X3754538Y832930D01*
X3755158Y831680D01*
X3755313Y830221D01*
X3755158Y828971D01*
X3754538Y827721D01*
X3753608Y826680D01*
X3752523Y826263D01*
X3751283Y826680D01*
X3750198Y827929D01*
X3749578Y829805D01*
X3749423Y831888D01*
X3749733Y834596D01*
X3750198Y836055D01*
X3750973Y837513D01*
X3752058Y838555D01*
X3753143Y838763D01*
X3754228Y838346D01*
X3755003Y837305D01*
G01X3705558Y861913D02*
X3706488Y860454D01*
X3707728Y859621D01*
X3709123Y859413D01*
X3710363Y859621D01*
X3711603Y860663D01*
X3712378Y861913D01*
X3712533Y863163D01*
X3712223Y864621D01*
X3711138Y865663D01*
X3710053Y866080D01*
X3708658D01*
G01X3710053D02*
X3710983Y866705D01*
X3711758Y867746D01*
X3712068Y868996D01*
X3711758Y870246D01*
X3710983Y871288D01*
X3709588Y871913D01*
X3708193Y871705D01*
X3706798Y870871D01*
G01X3718423Y869830D02*
X3719353Y871079D01*
X3720438Y871705D01*
X3721678Y871913D01*
X3723228Y871496D01*
X3724313Y870455D01*
X3724623Y869205D01*
X3724468Y867954D01*
X3723848Y866913D01*
X3720748Y864830D01*
X3719353Y863371D01*
X3718423Y861288D01*
X3718113Y859413D01*
X3724623D01*
G01X3733458D02*
X3733768Y862121D01*
X3734233Y864413D01*
X3734853Y866496D01*
X3735628Y868788D01*
X3736868Y871913D01*
X3730668D01*
G01X3746168D02*
X3744928Y871496D01*
X3743998Y870455D01*
X3743378Y869205D01*
X3742913Y867538D01*
X3742758Y865663D01*
X3742913Y863788D01*
X3743378Y862121D01*
X3743998Y860871D01*
X3744928Y859830D01*
X3746168Y859413D01*
X3747408Y859830D01*
X3748338Y860871D01*
X3748958Y862121D01*
X3749423Y863788D01*
X3749578Y865663D01*
X3749423Y867538D01*
X3748958Y869205D01*
X3748338Y870455D01*
X3747408Y871496D01*
X3746168Y871913D01*
G01X3702768Y925713D02*
Y938213D01*
X3700908Y935713D01*
G01Y925713D02*
X3704628D01*
G01X3715168Y938213D02*
X3713928Y937796D01*
X3712998Y936755D01*
X3712378Y935505D01*
X3711913Y933838D01*
X3711758Y931963D01*
X3711913Y930088D01*
X3712378Y928421D01*
X3712998Y927171D01*
X3713928Y926130D01*
X3715168Y925713D01*
X3716408Y926130D01*
X3717338Y927171D01*
X3717958Y928421D01*
X3718423Y930088D01*
X3718578Y931963D01*
X3718423Y933838D01*
X3717958Y935505D01*
X3717338Y936755D01*
X3716408Y937796D01*
X3715168Y938213D01*
G01X3724158Y928213D02*
X3725088Y926754D01*
X3726328Y925921D01*
X3727723Y925713D01*
X3728963Y925921D01*
X3730203Y926963D01*
X3730978Y928213D01*
X3731133Y929463D01*
X3730823Y930921D01*
X3729738Y931963D01*
X3728653Y932380D01*
X3727258D01*
G01X3728653D02*
X3729583Y933005D01*
X3730358Y934046D01*
X3730668Y935296D01*
X3730358Y936546D01*
X3729583Y937588D01*
X3728188Y938213D01*
X3726793Y938005D01*
X3725398Y937171D01*
G01X3737023Y930921D02*
X3738108Y932380D01*
X3739038Y933213D01*
X3740278Y933630D01*
X3741363Y933213D01*
X3742138Y932380D01*
X3742758Y931130D01*
X3742913Y929671D01*
X3742758Y928421D01*
X3742138Y927171D01*
X3741208Y926130D01*
X3740123Y925713D01*
X3738883Y926130D01*
X3737798Y927379D01*
X3737178Y929255D01*
X3737023Y931338D01*
X3737333Y934046D01*
X3737798Y935505D01*
X3738573Y936963D01*
X3739658Y938005D01*
X3740743Y938213D01*
X3741828Y937796D01*
X3742603Y936755D01*
G01X3754228Y925713D02*
Y938213D01*
X3748493Y929255D01*
X3756243D01*
G01X3696206Y1690462D02*
X3700081Y1702962D01*
X3703956Y1690462D01*
G01X3702561Y1694837D02*
X3697601D01*
G01X3709381Y1702962D02*
Y1690462D01*
X3715581D01*
G01X3721781Y1702962D02*
Y1690462D01*
X3727981D01*
G01X3746271Y1702962D02*
Y1694004D01*
X3746891Y1692128D01*
X3748131Y1690879D01*
X3749681Y1690462D01*
X3751231Y1690879D01*
X3752471Y1692128D01*
X3753091Y1694004D01*
Y1702962D01*
G01X3758516Y1690462D02*
Y1702962D01*
X3765646Y1690462D01*
Y1702962D01*
G01X3772621D02*
X3776341D01*
G01X3774481D02*
Y1690462D01*
G01X3772621D02*
X3776341D01*
G01X3786881Y1702962D02*
Y1690462D01*
G01X3783316Y1702962D02*
X3790446D01*
G01X3796026Y1692128D02*
X3797266Y1691087D01*
X3798661Y1690462D01*
X3799901D01*
X3801141Y1691087D01*
X3802071Y1692128D01*
X3802536Y1693587D01*
X3802226Y1695045D01*
X3801451Y1696295D01*
X3800056Y1697129D01*
X3798196Y1697545D01*
X3797111Y1698379D01*
X3796646Y1699837D01*
X3796956Y1701295D01*
X3797731Y1702337D01*
X3798816Y1702962D01*
X3799901D01*
X3800986Y1702545D01*
X3801916Y1701504D01*
G01X3820206Y1690462D02*
X3824081Y1702962D01*
X3827956Y1690462D01*
G01X3826561Y1694837D02*
X3821601D01*
G01X3833381Y1690462D02*
Y1702962D01*
X3837256D01*
X3838496Y1702337D01*
X3839271Y1701504D01*
X3839581Y1699837D01*
X3839271Y1698170D01*
X3838341Y1697129D01*
X3837256Y1696504D01*
X3833381D01*
G01X3837256D02*
X3839581Y1690462D01*
G01X3851981D02*
X3845781D01*
Y1702962D01*
X3851981D01*
G01X3849501Y1696920D02*
X3845781D01*
G01X3871821Y1702962D02*
X3875541D01*
G01X3873681D02*
Y1690462D01*
G01X3871821D02*
X3875541D01*
G01X3882516D02*
Y1702962D01*
X3889646Y1690462D01*
Y1702962D01*
G01X3906851Y1690462D02*
Y1702962D01*
X3910881Y1692545D01*
X3914911Y1702962D01*
Y1690462D01*
G01X3921421Y1702962D02*
X3925141D01*
G01X3923281D02*
Y1690462D01*
G01X3921421D02*
X3925141D01*
G01X3932581Y1702962D02*
Y1690462D01*
X3938781D01*
G01X3944826Y1692128D02*
X3946066Y1691087D01*
X3947461Y1690462D01*
X3948701D01*
X3949941Y1691087D01*
X3950871Y1692128D01*
X3951336Y1693587D01*
X3951026Y1695045D01*
X3950251Y1696295D01*
X3948856Y1697129D01*
X3946996Y1697545D01*
X3945911Y1698379D01*
X3945446Y1699837D01*
X3945756Y1701295D01*
X3946531Y1702337D01*
X3947616Y1702962D01*
X3948701D01*
X3949786Y1702545D01*
X3950716Y1701504D01*
G01X3700666Y2818348D02*
Y2830848D01*
X3704696Y2820431D01*
X3708726Y2830848D01*
Y2818348D01*
G01X3713531D02*
Y2830848D01*
X3720661Y2818348D01*
Y2830848D01*
G01X3732906Y2829806D02*
X3731976Y2830431D01*
X3730891Y2830848D01*
X3729651D01*
X3728256Y2830223D01*
X3727171Y2829181D01*
X3726396Y2827931D01*
X3725776Y2825848D01*
X3725621Y2823973D01*
X3725931Y2822098D01*
X3726396Y2820848D01*
X3727326Y2819598D01*
X3728411Y2818765D01*
X3729496Y2818348D01*
X3730581D01*
X3731666Y2818765D01*
X3732596Y2819389D01*
X3733371Y2820223D01*
G01X3737246Y2814181D02*
X3746546D01*
G01X3751196Y2830848D02*
Y2818348D01*
X3757396D01*
G01X3762821D02*
X3766696Y2830848D01*
X3770571Y2818348D01*
G01X3769176Y2822723D02*
X3764216D01*
G01X3779096Y2818348D02*
Y2823973D01*
X3775996Y2830848D01*
G01X3782196D02*
X3779096Y2823973D01*
G01X3794596Y2818348D02*
X3788396D01*
Y2830848D01*
X3794596D01*
G01X3792116Y2824806D02*
X3788396D01*
G01X3800796Y2818348D02*
Y2830848D01*
X3804671D01*
X3805911Y2830223D01*
X3806686Y2829390D01*
X3806996Y2827723D01*
X3806686Y2826056D01*
X3805756Y2825015D01*
X3804671Y2824390D01*
X3800796D01*
G01X3804671D02*
X3806996Y2818348D01*
G01X3723228Y-35637D02*
Y-23137D01*
X3717493Y-32095D01*
X3725243D01*
G01X3733768Y-23137D02*
X3732528Y-23554D01*
X3731598Y-24595D01*
X3730978Y-25845D01*
X3730513Y-27512D01*
X3730358Y-29387D01*
X3730513Y-31262D01*
X3730978Y-32929D01*
X3731598Y-34179D01*
X3732528Y-35220D01*
X3733768Y-35637D01*
X3735008Y-35220D01*
X3735938Y-34179D01*
X3736558Y-32929D01*
X3737023Y-31262D01*
X3737178Y-29387D01*
X3737023Y-27512D01*
X3736558Y-25845D01*
X3735938Y-24595D01*
X3735008Y-23554D01*
X3733768Y-23137D01*
G01X3717958Y13D02*
X3718888Y-1446D01*
X3720128Y-2279D01*
X3721523Y-2487D01*
X3722763Y-2279D01*
X3724003Y-1237D01*
X3724778Y13D01*
X3724933Y1263D01*
X3724623Y2721D01*
X3723538Y3763D01*
X3722453Y4180D01*
X3721058D01*
G01X3722453D02*
X3723383Y4805D01*
X3724158Y5846D01*
X3724468Y7096D01*
X3724158Y8346D01*
X3723383Y9388D01*
X3721988Y10013D01*
X3720593Y9805D01*
X3719198Y8971D01*
G01X3730823Y7930D02*
X3731753Y9179D01*
X3732838Y9805D01*
X3734078Y10013D01*
X3735628Y9596D01*
X3736713Y8555D01*
X3737023Y7305D01*
X3736868Y6054D01*
X3736248Y5013D01*
X3733148Y2930D01*
X3731753Y1471D01*
X3730823Y-612D01*
X3730513Y-2487D01*
X3737023D01*
G01X3721368Y96963D02*
Y109463D01*
X3719508Y106963D01*
G01Y96963D02*
X3723228D01*
G01X3730823Y102171D02*
X3731908Y103630D01*
X3732838Y104463D01*
X3734078Y104880D01*
X3735163Y104463D01*
X3735938Y103630D01*
X3736558Y102380D01*
X3736713Y100921D01*
X3736558Y99671D01*
X3735938Y98421D01*
X3735008Y97380D01*
X3733923Y96963D01*
X3732683Y97380D01*
X3731598Y98629D01*
X3730978Y100505D01*
X3730823Y102588D01*
X3731133Y105296D01*
X3731598Y106755D01*
X3732373Y108213D01*
X3733458Y109255D01*
X3734543Y109463D01*
X3735628Y109046D01*
X3736403Y108005D01*
G01X3721368Y163263D02*
Y175763D01*
X3719508Y173263D01*
G01Y163263D02*
X3723228D01*
G01X3730823Y173680D02*
X3731753Y174929D01*
X3732838Y175555D01*
X3734078Y175763D01*
X3735628Y175346D01*
X3736713Y174305D01*
X3737023Y173055D01*
X3736868Y171804D01*
X3736248Y170763D01*
X3733148Y168680D01*
X3731753Y167221D01*
X3730823Y165138D01*
X3730513Y163263D01*
X3737023D01*
G01X3721368Y295863D02*
Y308363D01*
X3719508Y305863D01*
G01Y295863D02*
X3723228D01*
G01X3730823Y301071D02*
X3731908Y302530D01*
X3732838Y303363D01*
X3734078Y303780D01*
X3735163Y303363D01*
X3735938Y302530D01*
X3736558Y301280D01*
X3736713Y299821D01*
X3736558Y298571D01*
X3735938Y297321D01*
X3735008Y296280D01*
X3733923Y295863D01*
X3732683Y296280D01*
X3731598Y297529D01*
X3730978Y299405D01*
X3730823Y301488D01*
X3731133Y304196D01*
X3731598Y305655D01*
X3732373Y307113D01*
X3733458Y308155D01*
X3734543Y308363D01*
X3735628Y307946D01*
X3736403Y306905D01*
G01X3717958Y331513D02*
X3718888Y330054D01*
X3720128Y329221D01*
X3721523Y329013D01*
X3722763Y329221D01*
X3724003Y330263D01*
X3724778Y331513D01*
X3724933Y332763D01*
X3724623Y334221D01*
X3723538Y335263D01*
X3722453Y335680D01*
X3721058D01*
G01X3722453D02*
X3723383Y336305D01*
X3724158Y337346D01*
X3724468Y338596D01*
X3724158Y339846D01*
X3723383Y340888D01*
X3721988Y341513D01*
X3720593Y341305D01*
X3719198Y340471D01*
G01X3730823Y339430D02*
X3731753Y340679D01*
X3732838Y341305D01*
X3734078Y341513D01*
X3735628Y341096D01*
X3736713Y340055D01*
X3737023Y338805D01*
X3736868Y337554D01*
X3736248Y336513D01*
X3733148Y334430D01*
X3731753Y332971D01*
X3730823Y330888D01*
X3730513Y329013D01*
X3737023D01*
G01X3715168Y362163D02*
Y374663D01*
X3713308Y372163D01*
G01Y362163D02*
X3717028D01*
G01X3724623Y372580D02*
X3725553Y373829D01*
X3726638Y374455D01*
X3727878Y374663D01*
X3729428Y374246D01*
X3730513Y373205D01*
X3730823Y371955D01*
X3730668Y370704D01*
X3730048Y369663D01*
X3726948Y367580D01*
X3725553Y366121D01*
X3724623Y364038D01*
X3724313Y362163D01*
X3730823D01*
G01X3739968D02*
X3741053Y362371D01*
X3742293Y362996D01*
X3743068Y364038D01*
X3743378Y365496D01*
X3743068Y366954D01*
X3742138Y368205D01*
X3740743Y368830D01*
X3739193D01*
X3738263Y369246D01*
X3737488Y370288D01*
X3737178Y371746D01*
X3737643Y373205D01*
X3738728Y374246D01*
X3739968Y374663D01*
X3741208Y374246D01*
X3742293Y373205D01*
X3742758Y371746D01*
X3742448Y370288D01*
X3741673Y369246D01*
X3740743Y368830D01*
X3739193D01*
X3737798Y368205D01*
X3736868Y366954D01*
X3736558Y365496D01*
X3736868Y364038D01*
X3737643Y362996D01*
X3738883Y362371D01*
X3739968Y362163D01*
G01X3718423Y438880D02*
X3719353Y440129D01*
X3720438Y440755D01*
X3721678Y440963D01*
X3723228Y440546D01*
X3724313Y439505D01*
X3724623Y438255D01*
X3724468Y437004D01*
X3723848Y435963D01*
X3720748Y433880D01*
X3719353Y432421D01*
X3718423Y430338D01*
X3718113Y428463D01*
X3724623D01*
G01X3730358Y430963D02*
X3731288Y429504D01*
X3732528Y428671D01*
X3733923Y428463D01*
X3735163Y428671D01*
X3736403Y429713D01*
X3737178Y430963D01*
X3737333Y432213D01*
X3737023Y433671D01*
X3735938Y434713D01*
X3734853Y435130D01*
X3733458D01*
G01X3734853D02*
X3735783Y435755D01*
X3736558Y436796D01*
X3736868Y438046D01*
X3736558Y439296D01*
X3735783Y440338D01*
X3734388Y440963D01*
X3732993Y440755D01*
X3731598Y439921D01*
G01X3721368Y494763D02*
Y507263D01*
X3719508Y504763D01*
G01Y494763D02*
X3723228D01*
G01X3733768Y507263D02*
X3732528Y506846D01*
X3731598Y505805D01*
X3730978Y504555D01*
X3730513Y502888D01*
X3730358Y501013D01*
X3730513Y499138D01*
X3730978Y497471D01*
X3731598Y496221D01*
X3732528Y495180D01*
X3733768Y494763D01*
X3735008Y495180D01*
X3735938Y496221D01*
X3736558Y497471D01*
X3737023Y499138D01*
X3737178Y501013D01*
X3737023Y502888D01*
X3736558Y504555D01*
X3735938Y505805D01*
X3735008Y506846D01*
X3733768Y507263D01*
G01X3717958Y530413D02*
X3718888Y528954D01*
X3720128Y528121D01*
X3721523Y527913D01*
X3722763Y528121D01*
X3724003Y529163D01*
X3724778Y530413D01*
X3724933Y531663D01*
X3724623Y533121D01*
X3723538Y534163D01*
X3722453Y534580D01*
X3721058D01*
G01X3722453D02*
X3723383Y535205D01*
X3724158Y536246D01*
X3724468Y537496D01*
X3724158Y538746D01*
X3723383Y539788D01*
X3721988Y540413D01*
X3720593Y540205D01*
X3719198Y539371D01*
G01X3730823Y538330D02*
X3731753Y539579D01*
X3732838Y540205D01*
X3734078Y540413D01*
X3735628Y539996D01*
X3736713Y538955D01*
X3737023Y537705D01*
X3736868Y536454D01*
X3736248Y535413D01*
X3733148Y533330D01*
X3731753Y531871D01*
X3730823Y529788D01*
X3730513Y527913D01*
X3737023D01*
G01X3718423Y571480D02*
X3719353Y572729D01*
X3720438Y573355D01*
X3721678Y573563D01*
X3723228Y573146D01*
X3724313Y572105D01*
X3724623Y570855D01*
X3724468Y569604D01*
X3723848Y568563D01*
X3720748Y566480D01*
X3719353Y565021D01*
X3718423Y562938D01*
X3718113Y561063D01*
X3724623D01*
G01X3735628D02*
Y573563D01*
X3729893Y564605D01*
X3737643D01*
G01X3717958Y596713D02*
X3718888Y595254D01*
X3720128Y594421D01*
X3721523Y594213D01*
X3722763Y594421D01*
X3724003Y595463D01*
X3724778Y596713D01*
X3724933Y597963D01*
X3724623Y599421D01*
X3723538Y600463D01*
X3722453Y600880D01*
X3721058D01*
G01X3722453D02*
X3723383Y601505D01*
X3724158Y602546D01*
X3724468Y603796D01*
X3724158Y605046D01*
X3723383Y606088D01*
X3721988Y606713D01*
X3720593Y606505D01*
X3719198Y605671D01*
G01X3730823Y604630D02*
X3731753Y605879D01*
X3732838Y606505D01*
X3734078Y606713D01*
X3735628Y606296D01*
X3736713Y605255D01*
X3737023Y604005D01*
X3736868Y602754D01*
X3736248Y601713D01*
X3733148Y599630D01*
X3731753Y598171D01*
X3730823Y596088D01*
X3730513Y594213D01*
X3737023D01*
G01X3723228Y660513D02*
Y673013D01*
X3717493Y664055D01*
X3725243D01*
G01X3733768Y660513D02*
X3734853Y660721D01*
X3736093Y661346D01*
X3736868Y662388D01*
X3737178Y663846D01*
X3736868Y665304D01*
X3735938Y666555D01*
X3734543Y667180D01*
X3732993D01*
X3732063Y667596D01*
X3731288Y668638D01*
X3730978Y670096D01*
X3731443Y671555D01*
X3732528Y672596D01*
X3733768Y673013D01*
X3735008Y672596D01*
X3736093Y671555D01*
X3736558Y670096D01*
X3736248Y668638D01*
X3735473Y667596D01*
X3734543Y667180D01*
X3732993D01*
X3731598Y666555D01*
X3730668Y665304D01*
X3730358Y663846D01*
X3730668Y662388D01*
X3731443Y661346D01*
X3732683Y660721D01*
X3733768Y660513D01*
G01X3715168Y726813D02*
Y739313D01*
X3713308Y736813D01*
G01Y726813D02*
X3717028D01*
G01X3724623Y732021D02*
X3725708Y733480D01*
X3726638Y734313D01*
X3727878Y734730D01*
X3728963Y734313D01*
X3729738Y733480D01*
X3730358Y732230D01*
X3730513Y730771D01*
X3730358Y729521D01*
X3729738Y728271D01*
X3728808Y727230D01*
X3727723Y726813D01*
X3726483Y727230D01*
X3725398Y728479D01*
X3724778Y730355D01*
X3724623Y732438D01*
X3724933Y735146D01*
X3725398Y736605D01*
X3726173Y738063D01*
X3727258Y739105D01*
X3728343Y739313D01*
X3729428Y738896D01*
X3730203Y737855D01*
G01X3739968Y739313D02*
X3738728Y738896D01*
X3737798Y737855D01*
X3737178Y736605D01*
X3736713Y734938D01*
X3736558Y733063D01*
X3736713Y731188D01*
X3737178Y729521D01*
X3737798Y728271D01*
X3738728Y727230D01*
X3739968Y726813D01*
X3741208Y727230D01*
X3742138Y728271D01*
X3742758Y729521D01*
X3743223Y731188D01*
X3743378Y733063D01*
X3743223Y734938D01*
X3742758Y736605D01*
X3742138Y737855D01*
X3741208Y738896D01*
X3739968Y739313D01*
G01X3715168Y759963D02*
X3716253Y760171D01*
X3717493Y760796D01*
X3718268Y761838D01*
X3718578Y763296D01*
X3718268Y764754D01*
X3717338Y766005D01*
X3715943Y766630D01*
X3714393D01*
X3713463Y767046D01*
X3712688Y768088D01*
X3712378Y769546D01*
X3712843Y771005D01*
X3713928Y772046D01*
X3715168Y772463D01*
X3716408Y772046D01*
X3717493Y771005D01*
X3717958Y769546D01*
X3717648Y768088D01*
X3716873Y767046D01*
X3715943Y766630D01*
X3714393D01*
X3712998Y766005D01*
X3712068Y764754D01*
X3711758Y763296D01*
X3712068Y761838D01*
X3712843Y760796D01*
X3714083Y760171D01*
X3715168Y759963D01*
G01X3727568Y772463D02*
X3726328Y772046D01*
X3725398Y771005D01*
X3724778Y769755D01*
X3724313Y768088D01*
X3724158Y766213D01*
X3724313Y764338D01*
X3724778Y762671D01*
X3725398Y761421D01*
X3726328Y760380D01*
X3727568Y759963D01*
X3728808Y760380D01*
X3729738Y761421D01*
X3730358Y762671D01*
X3730823Y764338D01*
X3730978Y766213D01*
X3730823Y768088D01*
X3730358Y769755D01*
X3729738Y771005D01*
X3728808Y772046D01*
X3727568Y772463D01*
G01X3739968D02*
X3738728Y772046D01*
X3737798Y771005D01*
X3737178Y769755D01*
X3736713Y768088D01*
X3736558Y766213D01*
X3736713Y764338D01*
X3737178Y762671D01*
X3737798Y761421D01*
X3738728Y760380D01*
X3739968Y759963D01*
X3741208Y760380D01*
X3742138Y761421D01*
X3742758Y762671D01*
X3743223Y764338D01*
X3743378Y766213D01*
X3743223Y768088D01*
X3742758Y769755D01*
X3742138Y771005D01*
X3741208Y772046D01*
X3739968Y772463D01*
G01X3715168Y892563D02*
Y905063D01*
X3713308Y902563D01*
G01Y892563D02*
X3717028D01*
G01X3724623Y902980D02*
X3725553Y904229D01*
X3726638Y904855D01*
X3727878Y905063D01*
X3729428Y904646D01*
X3730513Y903605D01*
X3730823Y902355D01*
X3730668Y901104D01*
X3730048Y900063D01*
X3726948Y897980D01*
X3725553Y896521D01*
X3724623Y894438D01*
X3724313Y892563D01*
X3730823D01*
G01X3739968D02*
X3741053Y892771D01*
X3742293Y893396D01*
X3743068Y894438D01*
X3743378Y895896D01*
X3743068Y897354D01*
X3742138Y898605D01*
X3740743Y899230D01*
X3739193D01*
X3738263Y899646D01*
X3737488Y900688D01*
X3737178Y902146D01*
X3737643Y903605D01*
X3738728Y904646D01*
X3739968Y905063D01*
X3741208Y904646D01*
X3742293Y903605D01*
X3742758Y902146D01*
X3742448Y900688D01*
X3741673Y899646D01*
X3740743Y899230D01*
X3739193D01*
X3737798Y898605D01*
X3736868Y897354D01*
X3736558Y895896D01*
X3736868Y894438D01*
X3737643Y893396D01*
X3738883Y892771D01*
X3739968Y892563D01*
G01X3721368Y958863D02*
X3722453Y959071D01*
X3723693Y959696D01*
X3724468Y960738D01*
X3724778Y962196D01*
X3724468Y963654D01*
X3723538Y964905D01*
X3722143Y965530D01*
X3720593D01*
X3719663Y965946D01*
X3718888Y966988D01*
X3718578Y968446D01*
X3719043Y969905D01*
X3720128Y970946D01*
X3721368Y971363D01*
X3722608Y970946D01*
X3723693Y969905D01*
X3724158Y968446D01*
X3723848Y966988D01*
X3723073Y965946D01*
X3722143Y965530D01*
X3720593D01*
X3719198Y964905D01*
X3718268Y963654D01*
X3717958Y962196D01*
X3718268Y960738D01*
X3719043Y959696D01*
X3720283Y959071D01*
X3721368Y958863D01*
G01X3733768Y971363D02*
X3732528Y970946D01*
X3731598Y969905D01*
X3730978Y968655D01*
X3730513Y966988D01*
X3730358Y965113D01*
X3730513Y963238D01*
X3730978Y961571D01*
X3731598Y960321D01*
X3732528Y959280D01*
X3733768Y958863D01*
X3735008Y959280D01*
X3735938Y960321D01*
X3736558Y961571D01*
X3737023Y963238D01*
X3737178Y965113D01*
X3737023Y966988D01*
X3736558Y968655D01*
X3735938Y969905D01*
X3735008Y970946D01*
X3733768Y971363D01*
G01X3715168Y987938D02*
X3713928Y988146D01*
X3712843Y988979D01*
X3711913Y990230D01*
X3711293Y991688D01*
X3710983Y993355D01*
Y995021D01*
X3711293Y996688D01*
X3711913Y998146D01*
X3712843Y999396D01*
X3713928Y1000230D01*
X3715168Y1000438D01*
X3716408Y1000230D01*
X3717493Y999396D01*
X3718423Y998146D01*
X3719043Y996688D01*
X3719353Y995021D01*
Y993355D01*
X3719043Y991688D01*
X3718423Y990230D01*
X3717493Y988979D01*
X3716408Y988146D01*
X3715168Y987938D01*
G01X3716408Y991271D02*
X3718268Y987938D01*
G01X3727568Y1000438D02*
Y987938D01*
G01X3724003Y1000438D02*
X3731133D01*
G01X3739968Y987938D02*
Y993563D01*
X3736868Y1000438D01*
G01X3743068D02*
X3739968Y993563D01*
G01X3713101Y1665462D02*
Y1677962D01*
X3717131Y1667545D01*
X3721161Y1677962D01*
Y1665462D01*
G01X3725966D02*
Y1677962D01*
X3733096Y1665462D01*
Y1677962D01*
G01X3745341Y1676920D02*
X3744411Y1677545D01*
X3743326Y1677962D01*
X3742086D01*
X3740691Y1677337D01*
X3739606Y1676295D01*
X3738831Y1675045D01*
X3738211Y1672962D01*
X3738056Y1671087D01*
X3738366Y1669212D01*
X3738831Y1667962D01*
X3739761Y1666712D01*
X3740846Y1665879D01*
X3741931Y1665462D01*
X3743016D01*
X3744101Y1665879D01*
X3745031Y1666503D01*
X3745806Y1667337D01*
G01X3749681Y1661295D02*
X3758981D01*
G01X3763631Y1677962D02*
Y1665462D01*
X3769831D01*
G01X3775256D02*
X3779131Y1677962D01*
X3783006Y1665462D01*
G01X3781611Y1669837D02*
X3776651D01*
G01X3791531Y1665462D02*
Y1671087D01*
X3788431Y1677962D01*
G01X3794631D02*
X3791531Y1671087D01*
G01X3807031Y1665462D02*
X3800831D01*
Y1677962D01*
X3807031D01*
G01X3804551Y1671920D02*
X3800831D01*
G01X3813231Y1665462D02*
Y1677962D01*
X3817106D01*
X3818346Y1677337D01*
X3819121Y1676504D01*
X3819431Y1674837D01*
X3819121Y1673170D01*
X3818191Y1672129D01*
X3817106Y1671504D01*
X3813231D01*
G01X3817106D02*
X3819431Y1665462D01*
G01X3722004Y2013486D02*
X3725724D01*
G01X3723864D02*
Y2000986D01*
G01X3722004D02*
X3725724D01*
G01X3732699D02*
Y2013486D01*
X3739829Y2000986D01*
Y2013486D01*
G01X3745254Y2002861D02*
X3746184Y2001819D01*
X3747269Y2001194D01*
X3748664Y2000986D01*
X3750059Y2001403D01*
X3751144Y2002236D01*
X3751919Y2003694D01*
X3752074Y2005361D01*
X3751764Y2007028D01*
X3750989Y2008069D01*
X3749904Y2008903D01*
X3748819Y2009111D01*
X3747734Y2008903D01*
X3746339Y2008069D01*
X3746804Y2013486D01*
X3750989D01*
G01X3716925Y2384166D02*
X3720645D01*
G01X3718785D02*
Y2371666D01*
G01X3716925D02*
X3720645D01*
G01X3727620D02*
Y2384166D01*
X3734750Y2371666D01*
Y2384166D01*
G01X3740640Y2376874D02*
X3741725Y2378333D01*
X3742655Y2379166D01*
X3743895Y2379583D01*
X3744980Y2379166D01*
X3745755Y2378333D01*
X3746375Y2377083D01*
X3746530Y2375624D01*
X3746375Y2374374D01*
X3745755Y2373124D01*
X3744825Y2372083D01*
X3743740Y2371666D01*
X3742500Y2372083D01*
X3741415Y2373332D01*
X3740795Y2375208D01*
X3740640Y2377291D01*
X3740950Y2379999D01*
X3741415Y2381458D01*
X3742190Y2382916D01*
X3743275Y2383958D01*
X3744360Y2384166D01*
X3745445Y2383749D01*
X3746220Y2382708D01*
G01X3727568Y30663D02*
Y43163D01*
X3725708Y40663D01*
G01Y30663D02*
X3729428D01*
G01X3724623Y74230D02*
X3725553Y75479D01*
X3726638Y76105D01*
X3727878Y76313D01*
X3729428Y75896D01*
X3730513Y74855D01*
X3730823Y73605D01*
X3730668Y72354D01*
X3730048Y71313D01*
X3726948Y69230D01*
X3725553Y67771D01*
X3724623Y65688D01*
X3724313Y63813D01*
X3730823D01*
G01X3729428Y130113D02*
Y142613D01*
X3723693Y133655D01*
X3731443D01*
G01X3729428Y196413D02*
Y208913D01*
X3723693Y199955D01*
X3731443D01*
G01X3727568Y229563D02*
Y242063D01*
X3725708Y239563D01*
G01Y229563D02*
X3729428D01*
G01X3724623Y273130D02*
X3725553Y274379D01*
X3726638Y275005D01*
X3727878Y275213D01*
X3729428Y274796D01*
X3730513Y273755D01*
X3730823Y272505D01*
X3730668Y271254D01*
X3730048Y270213D01*
X3726948Y268130D01*
X3725553Y266671D01*
X3724623Y264588D01*
X3724313Y262713D01*
X3730823D01*
G01X3724623Y405730D02*
X3725553Y406979D01*
X3726638Y407605D01*
X3727878Y407813D01*
X3729428Y407396D01*
X3730513Y406355D01*
X3730823Y405105D01*
X3730668Y403854D01*
X3730048Y402813D01*
X3726948Y400730D01*
X3725553Y399271D01*
X3724623Y397188D01*
X3724313Y395313D01*
X3730823D01*
G01X3727568Y461613D02*
Y474113D01*
X3725708Y471613D01*
G01Y461613D02*
X3729428D01*
G01X3727568Y627363D02*
X3728653Y627571D01*
X3729893Y628196D01*
X3730668Y629238D01*
X3730978Y630696D01*
X3730668Y632154D01*
X3729738Y633405D01*
X3728343Y634030D01*
X3726793D01*
X3725863Y634446D01*
X3725088Y635488D01*
X3724778Y636946D01*
X3725243Y638405D01*
X3726328Y639446D01*
X3727568Y639863D01*
X3728808Y639446D01*
X3729893Y638405D01*
X3730358Y636946D01*
X3730048Y635488D01*
X3729273Y634446D01*
X3728343Y634030D01*
X3726793D01*
X3725398Y633405D01*
X3724468Y632154D01*
X3724158Y630696D01*
X3724468Y629238D01*
X3725243Y628196D01*
X3726483Y627571D01*
X3727568Y627363D01*
G01X3729428Y693663D02*
Y706163D01*
X3723693Y697205D01*
X3731443D01*
G01X3740036Y2755848D02*
X3743756D01*
G01X3741896D02*
Y2743348D01*
G01X3740036D02*
X3743756D01*
G01X3750731D02*
Y2755848D01*
X3757861Y2743348D01*
Y2755848D01*
G01X3763751Y2753765D02*
X3764681Y2755014D01*
X3765766Y2755640D01*
X3767006Y2755848D01*
X3768556Y2755431D01*
X3769641Y2754390D01*
X3769951Y2753140D01*
X3769796Y2751889D01*
X3769176Y2750848D01*
X3766076Y2748765D01*
X3764681Y2747306D01*
X3763751Y2745223D01*
X3763441Y2743348D01*
X3769951D01*
G01X3740036Y2780848D02*
X3743756D01*
G01X3741896D02*
Y2768348D01*
G01X3740036D02*
X3743756D01*
G01X3750731D02*
Y2780848D01*
X3757861Y2768348D01*
Y2780848D01*
G01X3763751Y2778765D02*
X3764681Y2780014D01*
X3765766Y2780640D01*
X3767006Y2780848D01*
X3768556Y2780431D01*
X3769641Y2779390D01*
X3769951Y2778140D01*
X3769796Y2776889D01*
X3769176Y2775848D01*
X3766076Y2773765D01*
X3764681Y2772306D01*
X3763751Y2770223D01*
X3763441Y2768348D01*
X3769951D01*
G01X3740036Y2805848D02*
X3743756D01*
G01X3741896D02*
Y2793348D01*
G01X3740036D02*
X3743756D01*
G01X3750731D02*
Y2805848D01*
X3757861Y2793348D01*
Y2805848D01*
G01X3763751Y2803765D02*
X3764681Y2805014D01*
X3765766Y2805640D01*
X3767006Y2805848D01*
X3768556Y2805431D01*
X3769641Y2804390D01*
X3769951Y2803140D01*
X3769796Y2801889D01*
X3769176Y2800848D01*
X3766076Y2798765D01*
X3764681Y2797306D01*
X3763751Y2795223D01*
X3763441Y2793348D01*
X3769951D01*
G01X3752471Y1652962D02*
X3756191D01*
G01X3754331D02*
Y1640462D01*
G01X3752471D02*
X3756191D01*
G01X3763166D02*
Y1652962D01*
X3770296Y1640462D01*
Y1652962D01*
G01X3780991Y1640462D02*
Y1652962D01*
X3775256Y1644004D01*
X3783006D01*
G01X3770906Y791847D02*
Y799347D01*
X3775200Y791847D01*
Y799347D01*
G01X3780553Y791847D02*
X3779806Y791972D01*
X3779153Y792472D01*
X3778593Y793222D01*
X3778220Y794097D01*
X3778033Y795097D01*
Y796097D01*
X3778220Y797097D01*
X3778593Y797972D01*
X3779153Y798722D01*
X3779806Y799222D01*
X3780553Y799347D01*
X3781300Y799222D01*
X3781953Y798722D01*
X3782513Y797972D01*
X3782886Y797097D01*
X3783073Y796097D01*
Y795097D01*
X3782886Y794097D01*
X3782513Y793222D01*
X3781953Y792472D01*
X3781300Y791972D01*
X3780553Y791847D01*
G01X3785906D02*
Y799347D01*
X3790200Y791847D01*
Y799347D01*
G01X3794340Y794347D02*
X3796766D01*
G01X3800626Y791847D02*
Y799347D01*
X3803053Y793097D01*
X3805480Y799347D01*
Y791847D01*
G01X3808220D02*
X3810553Y799347D01*
X3812886Y791847D01*
G01X3812046Y794472D02*
X3809060D01*
G01X3816186Y791847D02*
Y799347D01*
X3818520D01*
X3819266Y798972D01*
X3819733Y798472D01*
X3819920Y797472D01*
X3819733Y796472D01*
X3819173Y795847D01*
X3818520Y795472D01*
X3816186D01*
G01X3818520D02*
X3819920Y791847D01*
G01X3823500D02*
Y799347D01*
G01X3827046D02*
X3823500Y794722D01*
G01X3827606Y791847D02*
X3825086Y796847D01*
G01X3833053Y791597D02*
X3832866Y791722D01*
Y791972D01*
X3833053Y792097D01*
X3833240Y791972D01*
Y791722D01*
X3833053Y791597D01*
G01Y794972D02*
X3832866Y795097D01*
Y795347D01*
X3833053Y795472D01*
X3833240Y795347D01*
Y795097D01*
X3833053Y794972D01*
G01X3838686Y791847D02*
Y799347D01*
X3841020D01*
X3841766Y798972D01*
X3842233Y798472D01*
X3842420Y797472D01*
X3842233Y796472D01*
X3841673Y795847D01*
X3841020Y795472D01*
X3838686D01*
G01X3841020D02*
X3842420Y791847D01*
G01X3849920D02*
X3846186D01*
Y799347D01*
X3849920D01*
G01X3848426Y795722D02*
X3846186D01*
G01X3857606Y798722D02*
X3857046Y799097D01*
X3856393Y799347D01*
X3855646D01*
X3854806Y798972D01*
X3854153Y798347D01*
X3853686Y797597D01*
X3853313Y796347D01*
X3853220Y795222D01*
X3853406Y794097D01*
X3853686Y793347D01*
X3854246Y792597D01*
X3854900Y792097D01*
X3855553Y791847D01*
X3856206D01*
X3856860Y792097D01*
X3857420Y792472D01*
X3857886Y792972D01*
G01X3863053Y791847D02*
X3862306Y791972D01*
X3861653Y792472D01*
X3861093Y793222D01*
X3860720Y794097D01*
X3860533Y795097D01*
Y796097D01*
X3860720Y797097D01*
X3861093Y797972D01*
X3861653Y798722D01*
X3862306Y799222D01*
X3863053Y799347D01*
X3863800Y799222D01*
X3864453Y798722D01*
X3865013Y797972D01*
X3865386Y797097D01*
X3865573Y796097D01*
Y795097D01*
X3865386Y794097D01*
X3865013Y793222D01*
X3864453Y792472D01*
X3863800Y791972D01*
X3863053Y791847D01*
G01X3868126D02*
Y799347D01*
X3870553Y793097D01*
X3872980Y799347D01*
Y791847D01*
G01X3875626D02*
Y799347D01*
X3878053Y793097D01*
X3880480Y799347D01*
Y791847D01*
G01X3887420D02*
X3883686D01*
Y799347D01*
X3887420D01*
G01X3885926Y795722D02*
X3883686D01*
G01X3890906Y791847D02*
Y799347D01*
X3895200Y791847D01*
Y799347D01*
G01X3898500Y791847D02*
Y799347D01*
X3900366D01*
X3901113Y798972D01*
X3901673Y798472D01*
X3902140Y797722D01*
X3902513Y796847D01*
X3902606Y795597D01*
X3902513Y794347D01*
X3902140Y793472D01*
X3901673Y792722D01*
X3901113Y792222D01*
X3900366Y791847D01*
X3898500D01*
G01X3909920D02*
X3906186D01*
Y799347D01*
X3909920D01*
G01X3908426Y795722D02*
X3906186D01*
G01X3913500Y791847D02*
Y799347D01*
X3915366D01*
X3916113Y798972D01*
X3916673Y798472D01*
X3917140Y797722D01*
X3917513Y796847D01*
X3917606Y795597D01*
X3917513Y794347D01*
X3917140Y793472D01*
X3916673Y792722D01*
X3916113Y792222D01*
X3915366Y791847D01*
X3913500D01*
G01X3928500D02*
Y799347D01*
X3930366D01*
X3931113Y798972D01*
X3931673Y798472D01*
X3932140Y797722D01*
X3932513Y796847D01*
X3932606Y795597D01*
X3932513Y794347D01*
X3932140Y793472D01*
X3931673Y792722D01*
X3931113Y792222D01*
X3930366Y791847D01*
X3928500D01*
G01X3936186D02*
Y799347D01*
X3938520D01*
X3939266Y798972D01*
X3939733Y798472D01*
X3939920Y797472D01*
X3939733Y796472D01*
X3939173Y795847D01*
X3938520Y795472D01*
X3936186D01*
G01X3938520D02*
X3939920Y791847D01*
G01X3944433Y799347D02*
X3946673D01*
G01X3945553D02*
Y791847D01*
G01X3944433D02*
X3946673D01*
G01X3951186Y799347D02*
Y791847D01*
X3954920D01*
G01X3958686Y799347D02*
Y791847D01*
X3962420D01*
G01X3973593Y792847D02*
X3974340Y792222D01*
X3975180Y791847D01*
X3975926D01*
X3976673Y792222D01*
X3977233Y792847D01*
X3977513Y793722D01*
X3977326Y794597D01*
X3976860Y795347D01*
X3976020Y795847D01*
X3974900Y796097D01*
X3974246Y796597D01*
X3973966Y797472D01*
X3974153Y798347D01*
X3974620Y798972D01*
X3975273Y799347D01*
X3975926D01*
X3976580Y799097D01*
X3977140Y798472D01*
G01X3981933Y799347D02*
X3984173D01*
G01X3983053D02*
Y791847D01*
G01X3981933D02*
X3984173D01*
G01X3988780Y799347D02*
X3992326D01*
X3988780Y791847D01*
X3992326D01*
G01X3999920D02*
X3996186D01*
Y799347D01*
X3999920D01*
G01X3998426Y795722D02*
X3996186D01*
G01X4011280Y791847D02*
Y799347D01*
X4014826D01*
G01X4013520Y795722D02*
X4011280D01*
G01X4020553Y791847D02*
X4019806Y791972D01*
X4019153Y792472D01*
X4018593Y793222D01*
X4018220Y794097D01*
X4018033Y795097D01*
Y796097D01*
X4018220Y797097D01*
X4018593Y797972D01*
X4019153Y798722D01*
X4019806Y799222D01*
X4020553Y799347D01*
X4021300Y799222D01*
X4021953Y798722D01*
X4022513Y797972D01*
X4022886Y797097D01*
X4023073Y796097D01*
Y795097D01*
X4022886Y794097D01*
X4022513Y793222D01*
X4021953Y792472D01*
X4021300Y791972D01*
X4020553Y791847D01*
G01X4026186D02*
Y799347D01*
X4028520D01*
X4029266Y798972D01*
X4029733Y798472D01*
X4029920Y797472D01*
X4029733Y796472D01*
X4029173Y795847D01*
X4028520Y795472D01*
X4026186D01*
G01X4028520D02*
X4029920Y791847D01*
G01X4043053Y799347D02*
X4042306Y799097D01*
X4041746Y798472D01*
X4041373Y797722D01*
X4041093Y796722D01*
X4041000Y795597D01*
X4041093Y794472D01*
X4041373Y793472D01*
X4041746Y792722D01*
X4042306Y792097D01*
X4043053Y791847D01*
X4043800Y792097D01*
X4044360Y792722D01*
X4044733Y793472D01*
X4045013Y794472D01*
X4045106Y795597D01*
X4045013Y796722D01*
X4044733Y797722D01*
X4044360Y798472D01*
X4043800Y799097D01*
X4043053Y799347D01*
G01X4050553Y791597D02*
X4050366Y791722D01*
Y791972D01*
X4050553Y792097D01*
X4050740Y791972D01*
Y791722D01*
X4050553Y791597D01*
G01X4056000Y793347D02*
X4056560Y792472D01*
X4057306Y791972D01*
X4058146Y791847D01*
X4058893Y791972D01*
X4059640Y792597D01*
X4060106Y793347D01*
X4060200Y794097D01*
X4060013Y794972D01*
X4059360Y795597D01*
X4058706Y795847D01*
X4057866D01*
G01X4058706D02*
X4059266Y796222D01*
X4059733Y796847D01*
X4059920Y797597D01*
X4059733Y798347D01*
X4059266Y798972D01*
X4058426Y799347D01*
X4057586Y799222D01*
X4056746Y798722D01*
G01X4065553Y791847D02*
Y799347D01*
X4064433Y797847D01*
G01Y791847D02*
X4066673D01*
G01X4070626D02*
Y799347D01*
X4073053Y793097D01*
X4075480Y799347D01*
Y791847D01*
G01X4078126D02*
Y799347D01*
X4080553Y793097D01*
X4082980Y799347D01*
Y791847D01*
G01X4093780D02*
Y799347D01*
X4097326D01*
G01X4096020Y795722D02*
X4093780D01*
G01X4101933Y799347D02*
X4104173D01*
G01X4103053D02*
Y791847D01*
G01X4101933D02*
X4104173D01*
G01X4108406D02*
Y799347D01*
X4112700Y791847D01*
Y799347D01*
G01X4116933D02*
X4119173D01*
G01X4118053D02*
Y791847D01*
G01X4116933D02*
X4119173D01*
G01X4123593Y792847D02*
X4124340Y792222D01*
X4125180Y791847D01*
X4125926D01*
X4126673Y792222D01*
X4127233Y792847D01*
X4127513Y793722D01*
X4127326Y794597D01*
X4126860Y795347D01*
X4126020Y795847D01*
X4124900Y796097D01*
X4124246Y796597D01*
X4123966Y797472D01*
X4124153Y798347D01*
X4124620Y798972D01*
X4125273Y799347D01*
X4125926D01*
X4126580Y799097D01*
X4127140Y798472D01*
G01X4131093Y791847D02*
Y799347D01*
G01X4135013D02*
Y791847D01*
G01Y795597D02*
X4131093D01*
G01X4142420Y791847D02*
X4138686D01*
Y799347D01*
X4142420D01*
G01X4140926Y795722D02*
X4138686D01*
G01X4146000Y791847D02*
Y799347D01*
X4147866D01*
X4148613Y798972D01*
X4149173Y798472D01*
X4149640Y797722D01*
X4150013Y796847D01*
X4150106Y795597D01*
X4150013Y794347D01*
X4149640Y793472D01*
X4149173Y792722D01*
X4148613Y792222D01*
X4147866Y791847D01*
X4146000D01*
G01X4161186D02*
Y799347D01*
X4163426D01*
X4164173Y798972D01*
X4164733Y798097D01*
X4164920Y797097D01*
X4164733Y796097D01*
X4164266Y795347D01*
X4163426Y794972D01*
X4161186D01*
G01X4170553Y799347D02*
Y791847D01*
G01X4168406Y799347D02*
X4172700D01*
G01X4176093Y791847D02*
Y799347D01*
G01X4180013D02*
Y791847D01*
G01Y795597D02*
X4176093D01*
G01X4191933Y799347D02*
X4194173D01*
G01X4193053D02*
Y791847D01*
G01X4191933D02*
X4194173D01*
G01X4198593Y792847D02*
X4199340Y792222D01*
X4200180Y791847D01*
X4200926D01*
X4201673Y792222D01*
X4202233Y792847D01*
X4202513Y793722D01*
X4202326Y794597D01*
X4201860Y795347D01*
X4201020Y795847D01*
X4199900Y796097D01*
X4199246Y796597D01*
X4198966Y797472D01*
X4199153Y798347D01*
X4199620Y798972D01*
X4200273Y799347D01*
X4200926D01*
X4201580Y799097D01*
X4202140Y798472D01*
G01X4215553Y799347D02*
X4214806Y799097D01*
X4214246Y798472D01*
X4213873Y797722D01*
X4213593Y796722D01*
X4213500Y795597D01*
X4213593Y794472D01*
X4213873Y793472D01*
X4214246Y792722D01*
X4214806Y792097D01*
X4215553Y791847D01*
X4216300Y792097D01*
X4216860Y792722D01*
X4217233Y793472D01*
X4217513Y794472D01*
X4217606Y795597D01*
X4217513Y796722D01*
X4217233Y797722D01*
X4216860Y798472D01*
X4216300Y799097D01*
X4215553Y799347D01*
G01X4223053Y791597D02*
X4222866Y791722D01*
Y791972D01*
X4223053Y792097D01*
X4223240Y791972D01*
Y791722D01*
X4223053Y791597D01*
G01X4231673Y791847D02*
Y799347D01*
X4228220Y793972D01*
X4232886D01*
G01X4235626Y791847D02*
Y799347D01*
X4238053Y793097D01*
X4240480Y799347D01*
Y791847D01*
G01X4243126D02*
Y799347D01*
X4245553Y793097D01*
X4247980Y799347D01*
Y791847D01*
G01X4258126D02*
Y799347D01*
X4260553Y793097D01*
X4262980Y799347D01*
Y791847D01*
G01X4269920D02*
X4266186D01*
Y799347D01*
X4269920D01*
G01X4268426Y795722D02*
X4266186D01*
G01X4275553Y799347D02*
Y791847D01*
G01X4273406Y799347D02*
X4277700D01*
G01X4281186Y791847D02*
Y799347D01*
X4283520D01*
X4284266Y798972D01*
X4284733Y798472D01*
X4284920Y797472D01*
X4284733Y796472D01*
X4284173Y795847D01*
X4283520Y795472D01*
X4281186D01*
G01X4283520D02*
X4284920Y791847D01*
G01X4289433Y799347D02*
X4291673D01*
G01X4290553D02*
Y791847D01*
G01X4289433D02*
X4291673D01*
G01X4300106Y798722D02*
X4299546Y799097D01*
X4298893Y799347D01*
X4298146D01*
X4297306Y798972D01*
X4296653Y798347D01*
X4296186Y797597D01*
X4295813Y796347D01*
X4295720Y795222D01*
X4295906Y794097D01*
X4296186Y793347D01*
X4296746Y792597D01*
X4297400Y792097D01*
X4298053Y791847D01*
X4298706D01*
X4299360Y792097D01*
X4299920Y792472D01*
X4300386Y792972D01*
G01X4311000Y791847D02*
Y799347D01*
X4312866D01*
X4313613Y798972D01*
X4314173Y798472D01*
X4314640Y797722D01*
X4315013Y796847D01*
X4315106Y795597D01*
X4315013Y794347D01*
X4314640Y793472D01*
X4314173Y792722D01*
X4313613Y792222D01*
X4312866Y791847D01*
X4311000D01*
G01X4318686D02*
Y799347D01*
X4321020D01*
X4321766Y798972D01*
X4322233Y798472D01*
X4322420Y797472D01*
X4322233Y796472D01*
X4321673Y795847D01*
X4321020Y795472D01*
X4318686D01*
G01X4321020D02*
X4322420Y791847D01*
G01X4326933Y799347D02*
X4329173D01*
G01X4328053D02*
Y791847D01*
G01X4326933D02*
X4329173D01*
G01X4333686Y799347D02*
Y791847D01*
X4337420D01*
G01X4341186Y799347D02*
Y791847D01*
X4344920D01*
G01X4350086Y789347D02*
X4349153Y790597D01*
X4348686Y791847D01*
Y796847D01*
X4349153Y798097D01*
X4350086Y799347D01*
G01X4358053D02*
X4357306Y799097D01*
X4356746Y798472D01*
X4356373Y797722D01*
X4356093Y796722D01*
X4356000Y795597D01*
X4356093Y794472D01*
X4356373Y793472D01*
X4356746Y792722D01*
X4357306Y792097D01*
X4358053Y791847D01*
X4358800Y792097D01*
X4359360Y792722D01*
X4359733Y793472D01*
X4360013Y794472D01*
X4360106Y795597D01*
X4360013Y796722D01*
X4359733Y797722D01*
X4359360Y798472D01*
X4358800Y799097D01*
X4358053Y799347D01*
G01X4365553Y791597D02*
X4365366Y791722D01*
Y791972D01*
X4365553Y792097D01*
X4365740Y791972D01*
Y791722D01*
X4365553Y791597D01*
G01X4373053Y799347D02*
X4372306Y799097D01*
X4371746Y798472D01*
X4371373Y797722D01*
X4371093Y796722D01*
X4371000Y795597D01*
X4371093Y794472D01*
X4371373Y793472D01*
X4371746Y792722D01*
X4372306Y792097D01*
X4373053Y791847D01*
X4373800Y792097D01*
X4374360Y792722D01*
X4374733Y793472D01*
X4375013Y794472D01*
X4375106Y795597D01*
X4375013Y796722D01*
X4374733Y797722D01*
X4374360Y798472D01*
X4373800Y799097D01*
X4373053Y799347D01*
G01X4380553Y791847D02*
Y799347D01*
X4379433Y797847D01*
G01Y791847D02*
X4381673D01*
G01X4386000Y792972D02*
X4386560Y792347D01*
X4387213Y791972D01*
X4388053Y791847D01*
X4388893Y792097D01*
X4389546Y792597D01*
X4390013Y793472D01*
X4390106Y794472D01*
X4389920Y795472D01*
X4389453Y796097D01*
X4388800Y796597D01*
X4388146Y796722D01*
X4387493Y796597D01*
X4386653Y796097D01*
X4386933Y799347D01*
X4389453D01*
G01X4395366Y791847D02*
X4395553Y793472D01*
X4395833Y794847D01*
X4396206Y796097D01*
X4396673Y797472D01*
X4397420Y799347D01*
X4393686D01*
G01X4402213Y797722D02*
X4402680Y799347D01*
G01X4403893D02*
X4403426Y797722D01*
G01X4411020Y789347D02*
X4411953Y790597D01*
X4412420Y791847D01*
Y796847D01*
X4411953Y798097D01*
X4411020Y799347D01*
G01X3773590Y665792D02*
Y673292D01*
X3775924D01*
X3776670Y672917D01*
X3777137Y672417D01*
X3777324Y671417D01*
X3777137Y670417D01*
X3776577Y669792D01*
X3775924Y669417D01*
X3773590D01*
G01X3775924D02*
X3777324Y665792D01*
G01X3784824D02*
X3781090D01*
Y673292D01*
X3784824D01*
G01X3783330Y669667D02*
X3781090D01*
G01X3792510Y672667D02*
X3791950Y673042D01*
X3791297Y673292D01*
X3790550D01*
X3789710Y672917D01*
X3789057Y672292D01*
X3788590Y671542D01*
X3788217Y670292D01*
X3788124Y669167D01*
X3788310Y668042D01*
X3788590Y667292D01*
X3789150Y666542D01*
X3789804Y666042D01*
X3790457Y665792D01*
X3791110D01*
X3791764Y666042D01*
X3792324Y666417D01*
X3792790Y666917D01*
G01X3797957Y665792D02*
X3797210Y665917D01*
X3796557Y666417D01*
X3795997Y667167D01*
X3795624Y668042D01*
X3795437Y669042D01*
Y670042D01*
X3795624Y671042D01*
X3795997Y671917D01*
X3796557Y672667D01*
X3797210Y673167D01*
X3797957Y673292D01*
X3798704Y673167D01*
X3799357Y672667D01*
X3799917Y671917D01*
X3800290Y671042D01*
X3800477Y670042D01*
Y669042D01*
X3800290Y668042D01*
X3799917Y667167D01*
X3799357Y666417D01*
X3798704Y665917D01*
X3797957Y665792D01*
G01X3803030D02*
Y673292D01*
X3805457Y667042D01*
X3807884Y673292D01*
Y665792D01*
G01X3810530D02*
Y673292D01*
X3812957Y667042D01*
X3815384Y673292D01*
Y665792D01*
G01X3822324D02*
X3818590D01*
Y673292D01*
X3822324D01*
G01X3820830Y669667D02*
X3818590D01*
G01X3825810Y665792D02*
Y673292D01*
X3830104Y665792D01*
Y673292D01*
G01X3833404Y665792D02*
Y673292D01*
X3835270D01*
X3836017Y672917D01*
X3836577Y672417D01*
X3837044Y671667D01*
X3837417Y670792D01*
X3837510Y669542D01*
X3837417Y668292D01*
X3837044Y667417D01*
X3836577Y666667D01*
X3836017Y666167D01*
X3835270Y665792D01*
X3833404D01*
G01X3844824D02*
X3841090D01*
Y673292D01*
X3844824D01*
G01X3843330Y669667D02*
X3841090D01*
G01X3848404Y665792D02*
Y673292D01*
X3850270D01*
X3851017Y672917D01*
X3851577Y672417D01*
X3852044Y671667D01*
X3852417Y670792D01*
X3852510Y669542D01*
X3852417Y668292D01*
X3852044Y667417D01*
X3851577Y666667D01*
X3851017Y666167D01*
X3850270Y665792D01*
X3848404D01*
G01X3863404D02*
Y673292D01*
X3865270D01*
X3866017Y672917D01*
X3866577Y672417D01*
X3867044Y671667D01*
X3867417Y670792D01*
X3867510Y669542D01*
X3867417Y668292D01*
X3867044Y667417D01*
X3866577Y666667D01*
X3866017Y666167D01*
X3865270Y665792D01*
X3863404D01*
G01X3871090D02*
Y673292D01*
X3873424D01*
X3874170Y672917D01*
X3874637Y672417D01*
X3874824Y671417D01*
X3874637Y670417D01*
X3874077Y669792D01*
X3873424Y669417D01*
X3871090D01*
G01X3873424D02*
X3874824Y665792D01*
G01X3879337Y673292D02*
X3881577D01*
G01X3880457D02*
Y665792D01*
G01X3879337D02*
X3881577D01*
G01X3886090Y673292D02*
Y665792D01*
X3889824D01*
G01X3893590Y673292D02*
Y665792D01*
X3897324D01*
G01X3908497Y666792D02*
X3909244Y666167D01*
X3910084Y665792D01*
X3910830D01*
X3911577Y666167D01*
X3912137Y666792D01*
X3912417Y667667D01*
X3912230Y668542D01*
X3911764Y669292D01*
X3910924Y669792D01*
X3909804Y670042D01*
X3909150Y670542D01*
X3908870Y671417D01*
X3909057Y672292D01*
X3909524Y672917D01*
X3910177Y673292D01*
X3910830D01*
X3911484Y673042D01*
X3912044Y672417D01*
G01X3916837Y673292D02*
X3919077D01*
G01X3917957D02*
Y665792D01*
G01X3916837D02*
X3919077D01*
G01X3923684Y673292D02*
X3927230D01*
X3923684Y665792D01*
X3927230D01*
G01X3934824D02*
X3931090D01*
Y673292D01*
X3934824D01*
G01X3933330Y669667D02*
X3931090D01*
G01X3946184Y665792D02*
Y673292D01*
X3949730D01*
G01X3948424Y669667D02*
X3946184D01*
G01X3955457Y665792D02*
X3954710Y665917D01*
X3954057Y666417D01*
X3953497Y667167D01*
X3953124Y668042D01*
X3952937Y669042D01*
Y670042D01*
X3953124Y671042D01*
X3953497Y671917D01*
X3954057Y672667D01*
X3954710Y673167D01*
X3955457Y673292D01*
X3956204Y673167D01*
X3956857Y672667D01*
X3957417Y671917D01*
X3957790Y671042D01*
X3957977Y670042D01*
Y669042D01*
X3957790Y668042D01*
X3957417Y667167D01*
X3956857Y666417D01*
X3956204Y665917D01*
X3955457Y665792D01*
G01X3961090D02*
Y673292D01*
X3963424D01*
X3964170Y672917D01*
X3964637Y672417D01*
X3964824Y671417D01*
X3964637Y670417D01*
X3964077Y669792D01*
X3963424Y669417D01*
X3961090D01*
G01X3963424D02*
X3964824Y665792D01*
G01X3977957D02*
Y673292D01*
X3976837Y671792D01*
G01Y665792D02*
X3979077D01*
G01X3985457Y665542D02*
X3985270Y665667D01*
Y665917D01*
X3985457Y666042D01*
X3985644Y665917D01*
Y665667D01*
X3985457Y665542D01*
G01X3992957Y673292D02*
X3992210Y673042D01*
X3991650Y672417D01*
X3991277Y671667D01*
X3990997Y670667D01*
X3990904Y669542D01*
X3990997Y668417D01*
X3991277Y667417D01*
X3991650Y666667D01*
X3992210Y666042D01*
X3992957Y665792D01*
X3993704Y666042D01*
X3994264Y666667D01*
X3994637Y667417D01*
X3994917Y668417D01*
X3995010Y669542D01*
X3994917Y670667D01*
X3994637Y671667D01*
X3994264Y672417D01*
X3993704Y673042D01*
X3992957Y673292D01*
G01X4000457Y665792D02*
Y673292D01*
X3999337Y671792D01*
G01Y665792D02*
X4001577D01*
G01X4006184Y668917D02*
X4006837Y669792D01*
X4007397Y670292D01*
X4008144Y670542D01*
X4008797Y670292D01*
X4009264Y669792D01*
X4009637Y669042D01*
X4009730Y668167D01*
X4009637Y667417D01*
X4009264Y666667D01*
X4008704Y666042D01*
X4008050Y665792D01*
X4007304Y666042D01*
X4006650Y666792D01*
X4006277Y667917D01*
X4006184Y669167D01*
X4006370Y670792D01*
X4006650Y671667D01*
X4007117Y672542D01*
X4007770Y673167D01*
X4008424Y673292D01*
X4009077Y673042D01*
X4009544Y672417D01*
G01X4013030Y665792D02*
Y673292D01*
X4015457Y667042D01*
X4017884Y673292D01*
Y665792D01*
G01X4020530D02*
Y673292D01*
X4022957Y667042D01*
X4025384Y673292D01*
Y665792D01*
G01X4036184D02*
Y673292D01*
X4039730D01*
G01X4038424Y669667D02*
X4036184D01*
G01X4044337Y673292D02*
X4046577D01*
G01X4045457D02*
Y665792D01*
G01X4044337D02*
X4046577D01*
G01X4050810D02*
Y673292D01*
X4055104Y665792D01*
Y673292D01*
G01X4059337D02*
X4061577D01*
G01X4060457D02*
Y665792D01*
G01X4059337D02*
X4061577D01*
G01X4065997Y666792D02*
X4066744Y666167D01*
X4067584Y665792D01*
X4068330D01*
X4069077Y666167D01*
X4069637Y666792D01*
X4069917Y667667D01*
X4069730Y668542D01*
X4069264Y669292D01*
X4068424Y669792D01*
X4067304Y670042D01*
X4066650Y670542D01*
X4066370Y671417D01*
X4066557Y672292D01*
X4067024Y672917D01*
X4067677Y673292D01*
X4068330D01*
X4068984Y673042D01*
X4069544Y672417D01*
G01X4073497Y665792D02*
Y673292D01*
G01X4077417D02*
Y665792D01*
G01Y669542D02*
X4073497D01*
G01X4084824Y665792D02*
X4081090D01*
Y673292D01*
X4084824D01*
G01X4083330Y669667D02*
X4081090D01*
G01X4088404Y665792D02*
Y673292D01*
X4090270D01*
X4091017Y672917D01*
X4091577Y672417D01*
X4092044Y671667D01*
X4092417Y670792D01*
X4092510Y669542D01*
X4092417Y668292D01*
X4092044Y667417D01*
X4091577Y666667D01*
X4091017Y666167D01*
X4090270Y665792D01*
X4088404D01*
G01X4103590D02*
Y673292D01*
X4105830D01*
X4106577Y672917D01*
X4107137Y672042D01*
X4107324Y671042D01*
X4107137Y670042D01*
X4106670Y669292D01*
X4105830Y668917D01*
X4103590D01*
G01X4112957Y673292D02*
Y665792D01*
G01X4110810Y673292D02*
X4115104D01*
G01X4118497Y665792D02*
Y673292D01*
G01X4122417D02*
Y665792D01*
G01Y669542D02*
X4118497D01*
G01X4134337Y673292D02*
X4136577D01*
G01X4135457D02*
Y665792D01*
G01X4134337D02*
X4136577D01*
G01X4140997Y666792D02*
X4141744Y666167D01*
X4142584Y665792D01*
X4143330D01*
X4144077Y666167D01*
X4144637Y666792D01*
X4144917Y667667D01*
X4144730Y668542D01*
X4144264Y669292D01*
X4143424Y669792D01*
X4142304Y670042D01*
X4141650Y670542D01*
X4141370Y671417D01*
X4141557Y672292D01*
X4142024Y672917D01*
X4142677Y673292D01*
X4143330D01*
X4143984Y673042D01*
X4144544Y672417D01*
G01X4157957Y665792D02*
Y673292D01*
X4156837Y671792D01*
G01Y665792D02*
X4159077D01*
G01X4165457Y665542D02*
X4165270Y665667D01*
Y665917D01*
X4165457Y666042D01*
X4165644Y665917D01*
Y665667D01*
X4165457Y665542D01*
G01X4172957Y665792D02*
Y673292D01*
X4171837Y671792D01*
G01Y665792D02*
X4174077D01*
G01X4178404Y666917D02*
X4178964Y666292D01*
X4179617Y665917D01*
X4180457Y665792D01*
X4181297Y666042D01*
X4181950Y666542D01*
X4182417Y667417D01*
X4182510Y668417D01*
X4182324Y669417D01*
X4181857Y670042D01*
X4181204Y670542D01*
X4180550Y670667D01*
X4179897Y670542D01*
X4179057Y670042D01*
X4179337Y673292D01*
X4181857D01*
G01X4187957Y665792D02*
Y673292D01*
X4186837Y671792D01*
G01Y665792D02*
X4189077D01*
G01X4194430Y668292D02*
X4196670D01*
G01X4195457Y669917D02*
Y666667D01*
G01X4201277Y665542D02*
X4204637Y673292D01*
G01X4209244Y668292D02*
X4211670D01*
G01X4217957Y673292D02*
X4217210Y673042D01*
X4216650Y672417D01*
X4216277Y671667D01*
X4215997Y670667D01*
X4215904Y669542D01*
X4215997Y668417D01*
X4216277Y667417D01*
X4216650Y666667D01*
X4217210Y666042D01*
X4217957Y665792D01*
X4218704Y666042D01*
X4219264Y666667D01*
X4219637Y667417D01*
X4219917Y668417D01*
X4220010Y669542D01*
X4219917Y670667D01*
X4219637Y671667D01*
X4219264Y672417D01*
X4218704Y673042D01*
X4217957Y673292D01*
G01X4225457Y665542D02*
X4225270Y665667D01*
Y665917D01*
X4225457Y666042D01*
X4225644Y665917D01*
Y665667D01*
X4225457Y665542D01*
G01X4232957Y673292D02*
X4232210Y673042D01*
X4231650Y672417D01*
X4231277Y671667D01*
X4230997Y670667D01*
X4230904Y669542D01*
X4230997Y668417D01*
X4231277Y667417D01*
X4231650Y666667D01*
X4232210Y666042D01*
X4232957Y665792D01*
X4233704Y666042D01*
X4234264Y666667D01*
X4234637Y667417D01*
X4234917Y668417D01*
X4235010Y669542D01*
X4234917Y670667D01*
X4234637Y671667D01*
X4234264Y672417D01*
X4233704Y673042D01*
X4232957Y673292D01*
G01X4238684Y672042D02*
X4239244Y672792D01*
X4239897Y673167D01*
X4240644Y673292D01*
X4241577Y673042D01*
X4242230Y672417D01*
X4242417Y671667D01*
X4242324Y670917D01*
X4241950Y670292D01*
X4240084Y669042D01*
X4239244Y668167D01*
X4238684Y666917D01*
X4238497Y665792D01*
X4242417D01*
G01X4245904Y666917D02*
X4246464Y666292D01*
X4247117Y665917D01*
X4247957Y665792D01*
X4248797Y666042D01*
X4249450Y666542D01*
X4249917Y667417D01*
X4250010Y668417D01*
X4249824Y669417D01*
X4249357Y670042D01*
X4248704Y670542D01*
X4248050Y670667D01*
X4247397Y670542D01*
X4246557Y670042D01*
X4246837Y673292D01*
X4249357D01*
G01X4253030Y665792D02*
Y673292D01*
X4255457Y667042D01*
X4257884Y673292D01*
Y665792D01*
G01X4260530D02*
Y673292D01*
X4262957Y667042D01*
X4265384Y673292D01*
Y665792D01*
G01X3772601Y761521D02*
Y769021D01*
X3775028Y762771D01*
X3777455Y769021D01*
Y761521D01*
G01X3780195D02*
X3782528Y769021D01*
X3784861Y761521D01*
G01X3784021Y764146D02*
X3781035D01*
G01X3788161Y761521D02*
Y769021D01*
X3790495D01*
X3791241Y768646D01*
X3791708Y768146D01*
X3791895Y767146D01*
X3791708Y766146D01*
X3791148Y765521D01*
X3790495Y765146D01*
X3788161D01*
G01X3790495D02*
X3791895Y761521D01*
G01X3795475D02*
Y769021D01*
G01X3799021D02*
X3795475Y764396D01*
G01X3799581Y761521D02*
X3797061Y766521D01*
G01X3805028Y761271D02*
X3804841Y761396D01*
Y761646D01*
X3805028Y761771D01*
X3805215Y761646D01*
Y761396D01*
X3805028Y761271D01*
G01Y764646D02*
X3804841Y764771D01*
Y765021D01*
X3805028Y765146D01*
X3805215Y765021D01*
Y764771D01*
X3805028Y764646D01*
G01X3810661Y761521D02*
Y769021D01*
X3812995D01*
X3813741Y768646D01*
X3814208Y768146D01*
X3814395Y767146D01*
X3814208Y766146D01*
X3813648Y765521D01*
X3812995Y765146D01*
X3810661D01*
G01X3812995D02*
X3814395Y761521D01*
G01X3821895D02*
X3818161D01*
Y769021D01*
X3821895D01*
G01X3820401Y765396D02*
X3818161D01*
G01X3829581Y768396D02*
X3829021Y768771D01*
X3828368Y769021D01*
X3827621D01*
X3826781Y768646D01*
X3826128Y768021D01*
X3825661Y767271D01*
X3825288Y766021D01*
X3825195Y764896D01*
X3825381Y763771D01*
X3825661Y763021D01*
X3826221Y762271D01*
X3826875Y761771D01*
X3827528Y761521D01*
X3828181D01*
X3828835Y761771D01*
X3829395Y762146D01*
X3829861Y762646D01*
G01X3835028Y761521D02*
X3834281Y761646D01*
X3833628Y762146D01*
X3833068Y762896D01*
X3832695Y763771D01*
X3832508Y764771D01*
Y765771D01*
X3832695Y766771D01*
X3833068Y767646D01*
X3833628Y768396D01*
X3834281Y768896D01*
X3835028Y769021D01*
X3835775Y768896D01*
X3836428Y768396D01*
X3836988Y767646D01*
X3837361Y766771D01*
X3837548Y765771D01*
Y764771D01*
X3837361Y763771D01*
X3836988Y762896D01*
X3836428Y762146D01*
X3835775Y761646D01*
X3835028Y761521D01*
G01X3840101D02*
Y769021D01*
X3842528Y762771D01*
X3844955Y769021D01*
Y761521D01*
G01X3847601D02*
Y769021D01*
X3850028Y762771D01*
X3852455Y769021D01*
Y761521D01*
G01X3859395D02*
X3855661D01*
Y769021D01*
X3859395D01*
G01X3857901Y765396D02*
X3855661D01*
G01X3862881Y761521D02*
Y769021D01*
X3867175Y761521D01*
Y769021D01*
G01X3870475Y761521D02*
Y769021D01*
X3872341D01*
X3873088Y768646D01*
X3873648Y768146D01*
X3874115Y767396D01*
X3874488Y766521D01*
X3874581Y765271D01*
X3874488Y764021D01*
X3874115Y763146D01*
X3873648Y762396D01*
X3873088Y761896D01*
X3872341Y761521D01*
X3870475D01*
G01X3881895D02*
X3878161D01*
Y769021D01*
X3881895D01*
G01X3880401Y765396D02*
X3878161D01*
G01X3885475Y761521D02*
Y769021D01*
X3887341D01*
X3888088Y768646D01*
X3888648Y768146D01*
X3889115Y767396D01*
X3889488Y766521D01*
X3889581Y765271D01*
X3889488Y764021D01*
X3889115Y763146D01*
X3888648Y762396D01*
X3888088Y761896D01*
X3887341Y761521D01*
X3885475D01*
G01X3900475D02*
Y769021D01*
X3902341D01*
X3903088Y768646D01*
X3903648Y768146D01*
X3904115Y767396D01*
X3904488Y766521D01*
X3904581Y765271D01*
X3904488Y764021D01*
X3904115Y763146D01*
X3903648Y762396D01*
X3903088Y761896D01*
X3902341Y761521D01*
X3900475D01*
G01X3908161D02*
Y769021D01*
X3910495D01*
X3911241Y768646D01*
X3911708Y768146D01*
X3911895Y767146D01*
X3911708Y766146D01*
X3911148Y765521D01*
X3910495Y765146D01*
X3908161D01*
G01X3910495D02*
X3911895Y761521D01*
G01X3916408Y769021D02*
X3918648D01*
G01X3917528D02*
Y761521D01*
G01X3916408D02*
X3918648D01*
G01X3923161Y769021D02*
Y761521D01*
X3926895D01*
G01X3930661Y769021D02*
Y761521D01*
X3934395D01*
G01X3945568Y762521D02*
X3946315Y761896D01*
X3947155Y761521D01*
X3947901D01*
X3948648Y761896D01*
X3949208Y762521D01*
X3949488Y763396D01*
X3949301Y764271D01*
X3948835Y765021D01*
X3947995Y765521D01*
X3946875Y765771D01*
X3946221Y766271D01*
X3945941Y767146D01*
X3946128Y768021D01*
X3946595Y768646D01*
X3947248Y769021D01*
X3947901D01*
X3948555Y768771D01*
X3949115Y768146D01*
G01X3953908Y769021D02*
X3956148D01*
G01X3955028D02*
Y761521D01*
G01X3953908D02*
X3956148D01*
G01X3960755Y769021D02*
X3964301D01*
X3960755Y761521D01*
X3964301D01*
G01X3971895D02*
X3968161D01*
Y769021D01*
X3971895D01*
G01X3970401Y765396D02*
X3968161D01*
G01X3983255Y761521D02*
Y769021D01*
X3986801D01*
G01X3985495Y765396D02*
X3983255D01*
G01X3992528Y761521D02*
X3991781Y761646D01*
X3991128Y762146D01*
X3990568Y762896D01*
X3990195Y763771D01*
X3990008Y764771D01*
Y765771D01*
X3990195Y766771D01*
X3990568Y767646D01*
X3991128Y768396D01*
X3991781Y768896D01*
X3992528Y769021D01*
X3993275Y768896D01*
X3993928Y768396D01*
X3994488Y767646D01*
X3994861Y766771D01*
X3995048Y765771D01*
Y764771D01*
X3994861Y763771D01*
X3994488Y762896D01*
X3993928Y762146D01*
X3993275Y761646D01*
X3992528Y761521D01*
G01X3998161D02*
Y769021D01*
X4000495D01*
X4001241Y768646D01*
X4001708Y768146D01*
X4001895Y767146D01*
X4001708Y766146D01*
X4001148Y765521D01*
X4000495Y765146D01*
X3998161D01*
G01X4000495D02*
X4001895Y761521D01*
G01X4015028Y769021D02*
X4014281Y768771D01*
X4013721Y768146D01*
X4013348Y767396D01*
X4013068Y766396D01*
X4012975Y765271D01*
X4013068Y764146D01*
X4013348Y763146D01*
X4013721Y762396D01*
X4014281Y761771D01*
X4015028Y761521D01*
X4015775Y761771D01*
X4016335Y762396D01*
X4016708Y763146D01*
X4016988Y764146D01*
X4017081Y765271D01*
X4016988Y766396D01*
X4016708Y767396D01*
X4016335Y768146D01*
X4015775Y768771D01*
X4015028Y769021D01*
G01X4022528Y761271D02*
X4022341Y761396D01*
Y761646D01*
X4022528Y761771D01*
X4022715Y761646D01*
Y761396D01*
X4022528Y761271D01*
G01X4027975Y762646D02*
X4028535Y762021D01*
X4029188Y761646D01*
X4030028Y761521D01*
X4030868Y761771D01*
X4031521Y762271D01*
X4031988Y763146D01*
X4032081Y764146D01*
X4031895Y765146D01*
X4031428Y765771D01*
X4030775Y766271D01*
X4030121Y766396D01*
X4029468Y766271D01*
X4028628Y765771D01*
X4028908Y769021D01*
X4031428D01*
G01X4035101Y761521D02*
Y769021D01*
X4037528Y762771D01*
X4039955Y769021D01*
Y761521D01*
G01X4042601D02*
Y769021D01*
X4045028Y762771D01*
X4047455Y769021D01*
Y761521D01*
G01X4058255D02*
Y769021D01*
X4061801D01*
G01X4060495Y765396D02*
X4058255D01*
G01X4066408Y769021D02*
X4068648D01*
G01X4067528D02*
Y761521D01*
G01X4066408D02*
X4068648D01*
G01X4072881D02*
Y769021D01*
X4077175Y761521D01*
Y769021D01*
G01X4081408D02*
X4083648D01*
G01X4082528D02*
Y761521D01*
G01X4081408D02*
X4083648D01*
G01X4088068Y762521D02*
X4088815Y761896D01*
X4089655Y761521D01*
X4090401D01*
X4091148Y761896D01*
X4091708Y762521D01*
X4091988Y763396D01*
X4091801Y764271D01*
X4091335Y765021D01*
X4090495Y765521D01*
X4089375Y765771D01*
X4088721Y766271D01*
X4088441Y767146D01*
X4088628Y768021D01*
X4089095Y768646D01*
X4089748Y769021D01*
X4090401D01*
X4091055Y768771D01*
X4091615Y768146D01*
G01X4095568Y761521D02*
Y769021D01*
G01X4099488D02*
Y761521D01*
G01Y765271D02*
X4095568D01*
G01X4106895Y761521D02*
X4103161D01*
Y769021D01*
X4106895D01*
G01X4105401Y765396D02*
X4103161D01*
G01X4110475Y761521D02*
Y769021D01*
X4112341D01*
X4113088Y768646D01*
X4113648Y768146D01*
X4114115Y767396D01*
X4114488Y766521D01*
X4114581Y765271D01*
X4114488Y764021D01*
X4114115Y763146D01*
X4113648Y762396D01*
X4113088Y761896D01*
X4112341Y761521D01*
X4110475D01*
G01X4125661D02*
Y769021D01*
X4127901D01*
X4128648Y768646D01*
X4129208Y767771D01*
X4129395Y766771D01*
X4129208Y765771D01*
X4128741Y765021D01*
X4127901Y764646D01*
X4125661D01*
G01X4135028Y769021D02*
Y761521D01*
G01X4132881Y769021D02*
X4137175D01*
G01X4140568Y761521D02*
Y769021D01*
G01X4144488D02*
Y761521D01*
G01Y765271D02*
X4140568D01*
G01X4156408Y769021D02*
X4158648D01*
G01X4157528D02*
Y761521D01*
G01X4156408D02*
X4158648D01*
G01X4163068Y762521D02*
X4163815Y761896D01*
X4164655Y761521D01*
X4165401D01*
X4166148Y761896D01*
X4166708Y762521D01*
X4166988Y763396D01*
X4166801Y764271D01*
X4166335Y765021D01*
X4165495Y765521D01*
X4164375Y765771D01*
X4163721Y766271D01*
X4163441Y767146D01*
X4163628Y768021D01*
X4164095Y768646D01*
X4164748Y769021D01*
X4165401D01*
X4166055Y768771D01*
X4166615Y768146D01*
G01X4180028Y769021D02*
X4179281Y768771D01*
X4178721Y768146D01*
X4178348Y767396D01*
X4178068Y766396D01*
X4177975Y765271D01*
X4178068Y764146D01*
X4178348Y763146D01*
X4178721Y762396D01*
X4179281Y761771D01*
X4180028Y761521D01*
X4180775Y761771D01*
X4181335Y762396D01*
X4181708Y763146D01*
X4181988Y764146D01*
X4182081Y765271D01*
X4181988Y766396D01*
X4181708Y767396D01*
X4181335Y768146D01*
X4180775Y768771D01*
X4180028Y769021D01*
G01X4187528Y761271D02*
X4187341Y761396D01*
Y761646D01*
X4187528Y761771D01*
X4187715Y761646D01*
Y761396D01*
X4187528Y761271D01*
G01X4193255Y764646D02*
X4193908Y765521D01*
X4194468Y766021D01*
X4195215Y766271D01*
X4195868Y766021D01*
X4196335Y765521D01*
X4196708Y764771D01*
X4196801Y763896D01*
X4196708Y763146D01*
X4196335Y762396D01*
X4195775Y761771D01*
X4195121Y761521D01*
X4194375Y761771D01*
X4193721Y762521D01*
X4193348Y763646D01*
X4193255Y764896D01*
X4193441Y766521D01*
X4193721Y767396D01*
X4194188Y768271D01*
X4194841Y768896D01*
X4195495Y769021D01*
X4196148Y768771D01*
X4196615Y768146D01*
G01X4200101Y761521D02*
Y769021D01*
X4202528Y762771D01*
X4204955Y769021D01*
Y761521D01*
G01X4207601D02*
Y769021D01*
X4210028Y762771D01*
X4212455Y769021D01*
Y761521D01*
G01X4222601D02*
Y769021D01*
X4225028Y762771D01*
X4227455Y769021D01*
Y761521D01*
G01X4234395D02*
X4230661D01*
Y769021D01*
X4234395D01*
G01X4232901Y765396D02*
X4230661D01*
G01X4240028Y769021D02*
Y761521D01*
G01X4237881Y769021D02*
X4242175D01*
G01X4245661Y761521D02*
Y769021D01*
X4247995D01*
X4248741Y768646D01*
X4249208Y768146D01*
X4249395Y767146D01*
X4249208Y766146D01*
X4248648Y765521D01*
X4247995Y765146D01*
X4245661D01*
G01X4247995D02*
X4249395Y761521D01*
G01X4253908Y769021D02*
X4256148D01*
G01X4255028D02*
Y761521D01*
G01X4253908D02*
X4256148D01*
G01X4264581Y768396D02*
X4264021Y768771D01*
X4263368Y769021D01*
X4262621D01*
X4261781Y768646D01*
X4261128Y768021D01*
X4260661Y767271D01*
X4260288Y766021D01*
X4260195Y764896D01*
X4260381Y763771D01*
X4260661Y763021D01*
X4261221Y762271D01*
X4261875Y761771D01*
X4262528Y761521D01*
X4263181D01*
X4263835Y761771D01*
X4264395Y762146D01*
X4264861Y762646D01*
G01X4275475Y761521D02*
Y769021D01*
X4277341D01*
X4278088Y768646D01*
X4278648Y768146D01*
X4279115Y767396D01*
X4279488Y766521D01*
X4279581Y765271D01*
X4279488Y764021D01*
X4279115Y763146D01*
X4278648Y762396D01*
X4278088Y761896D01*
X4277341Y761521D01*
X4275475D01*
G01X4283161D02*
Y769021D01*
X4285495D01*
X4286241Y768646D01*
X4286708Y768146D01*
X4286895Y767146D01*
X4286708Y766146D01*
X4286148Y765521D01*
X4285495Y765146D01*
X4283161D01*
G01X4285495D02*
X4286895Y761521D01*
G01X4291408Y769021D02*
X4293648D01*
G01X4292528D02*
Y761521D01*
G01X4291408D02*
X4293648D01*
G01X4298161Y769021D02*
Y761521D01*
X4301895D01*
G01X4305661Y769021D02*
Y761521D01*
X4309395D01*
G01X4314561Y759021D02*
X4313628Y760271D01*
X4313161Y761521D01*
Y766521D01*
X4313628Y767771D01*
X4314561Y769021D01*
G01X4322528D02*
X4321781Y768771D01*
X4321221Y768146D01*
X4320848Y767396D01*
X4320568Y766396D01*
X4320475Y765271D01*
X4320568Y764146D01*
X4320848Y763146D01*
X4321221Y762396D01*
X4321781Y761771D01*
X4322528Y761521D01*
X4323275Y761771D01*
X4323835Y762396D01*
X4324208Y763146D01*
X4324488Y764146D01*
X4324581Y765271D01*
X4324488Y766396D01*
X4324208Y767396D01*
X4323835Y768146D01*
X4323275Y768771D01*
X4322528Y769021D01*
G01X4330028Y761271D02*
X4329841Y761396D01*
Y761646D01*
X4330028Y761771D01*
X4330215Y761646D01*
Y761396D01*
X4330028Y761271D01*
G01X4337528Y769021D02*
X4336781Y768771D01*
X4336221Y768146D01*
X4335848Y767396D01*
X4335568Y766396D01*
X4335475Y765271D01*
X4335568Y764146D01*
X4335848Y763146D01*
X4336221Y762396D01*
X4336781Y761771D01*
X4337528Y761521D01*
X4338275Y761771D01*
X4338835Y762396D01*
X4339208Y763146D01*
X4339488Y764146D01*
X4339581Y765271D01*
X4339488Y766396D01*
X4339208Y767396D01*
X4338835Y768146D01*
X4338275Y768771D01*
X4337528Y769021D01*
G01X4343255Y767771D02*
X4343815Y768521D01*
X4344468Y768896D01*
X4345215Y769021D01*
X4346148Y768771D01*
X4346801Y768146D01*
X4346988Y767396D01*
X4346895Y766646D01*
X4346521Y766021D01*
X4344655Y764771D01*
X4343815Y763896D01*
X4343255Y762646D01*
X4343068Y761521D01*
X4346988D01*
G01X4350475Y763021D02*
X4351035Y762146D01*
X4351781Y761646D01*
X4352621Y761521D01*
X4353368Y761646D01*
X4354115Y762271D01*
X4354581Y763021D01*
X4354675Y763771D01*
X4354488Y764646D01*
X4353835Y765271D01*
X4353181Y765521D01*
X4352341D01*
G01X4353181D02*
X4353741Y765896D01*
X4354208Y766521D01*
X4354395Y767271D01*
X4354208Y768021D01*
X4353741Y768646D01*
X4352901Y769021D01*
X4352061Y768896D01*
X4351221Y768396D01*
G01X4358255Y764646D02*
X4358908Y765521D01*
X4359468Y766021D01*
X4360215Y766271D01*
X4360868Y766021D01*
X4361335Y765521D01*
X4361708Y764771D01*
X4361801Y763896D01*
X4361708Y763146D01*
X4361335Y762396D01*
X4360775Y761771D01*
X4360121Y761521D01*
X4359375Y761771D01*
X4358721Y762521D01*
X4358348Y763646D01*
X4358255Y764896D01*
X4358441Y766521D01*
X4358721Y767396D01*
X4359188Y768271D01*
X4359841Y768896D01*
X4360495Y769021D01*
X4361148Y768771D01*
X4361615Y768146D01*
G01X4366688Y767396D02*
X4367155Y769021D01*
G01X4368368D02*
X4367901Y767396D01*
G01X4375495Y759021D02*
X4376428Y760271D01*
X4376895Y761521D01*
Y766521D01*
X4376428Y767771D01*
X4375495Y769021D01*
G01X3846934Y2025986D02*
Y2038486D01*
X3850964Y2028069D01*
X3854994Y2038486D01*
Y2025986D01*
G01X3859489D02*
X3863364Y2038486D01*
X3867239Y2025986D01*
G01X3865844Y2030361D02*
X3860884D01*
G01X3872509Y2025986D02*
X3879019Y2038486D01*
G01X3872509D02*
X3879019Y2025986D01*
G01X3883514Y2021819D02*
X3892814D01*
G01X3897154Y2025986D02*
Y2038486D01*
X3900254D01*
X3901494Y2037861D01*
X3902424Y2037028D01*
X3903199Y2035778D01*
X3903819Y2034319D01*
X3903974Y2032236D01*
X3903819Y2030153D01*
X3903199Y2028694D01*
X3902424Y2027444D01*
X3901494Y2026611D01*
X3900254Y2025986D01*
X3897154D01*
G01X3916064D02*
X3909864D01*
Y2038486D01*
X3916064D01*
G01X3913584Y2032444D02*
X3909864D01*
G01X3922264Y2025986D02*
Y2038486D01*
X3925984D01*
X3927224Y2037861D01*
X3928154Y2036403D01*
X3928464Y2034736D01*
X3928154Y2033069D01*
X3927379Y2031819D01*
X3925984Y2031194D01*
X3922264D01*
G01X3937764Y2038486D02*
Y2025986D01*
G01X3934199Y2038486D02*
X3941329D01*
G01X3946909Y2025986D02*
Y2038486D01*
G01X3953419D02*
Y2025986D01*
G01Y2032236D02*
X3946909D01*
G01X3841855Y2396666D02*
Y2409166D01*
X3845885Y2398749D01*
X3849915Y2409166D01*
Y2396666D01*
G01X3854410D02*
X3858285Y2409166D01*
X3862160Y2396666D01*
G01X3860765Y2401041D02*
X3855805D01*
G01X3867430Y2396666D02*
X3873940Y2409166D01*
G01X3867430D02*
X3873940Y2396666D01*
G01X3878435Y2392499D02*
X3887735D01*
G01X3892075Y2396666D02*
Y2409166D01*
X3895175D01*
X3896415Y2408541D01*
X3897345Y2407708D01*
X3898120Y2406458D01*
X3898740Y2404999D01*
X3898895Y2402916D01*
X3898740Y2400833D01*
X3898120Y2399374D01*
X3897345Y2398124D01*
X3896415Y2397291D01*
X3895175Y2396666D01*
X3892075D01*
G01X3910985D02*
X3904785D01*
Y2409166D01*
X3910985D01*
G01X3908505Y2403124D02*
X3904785D01*
G01X3917185Y2396666D02*
Y2409166D01*
X3920905D01*
X3922145Y2408541D01*
X3923075Y2407083D01*
X3923385Y2405416D01*
X3923075Y2403749D01*
X3922300Y2402499D01*
X3920905Y2401874D01*
X3917185D01*
G01X3932685Y2409166D02*
Y2396666D01*
G01X3929120Y2409166D02*
X3936250D01*
G01X3941830Y2396666D02*
Y2409166D01*
G01X3948340D02*
Y2396666D01*
G01Y2402916D02*
X3941830D01*
G01X3864485Y2371666D02*
Y2384166D01*
X3862625Y2381666D01*
G01Y2371666D02*
X3866345D01*
G01X3876885Y2384166D02*
X3875645Y2383749D01*
X3874715Y2382708D01*
X3874095Y2381458D01*
X3873630Y2379791D01*
X3873475Y2377916D01*
X3873630Y2376041D01*
X3874095Y2374374D01*
X3874715Y2373124D01*
X3875645Y2372083D01*
X3876885Y2371666D01*
X3878125Y2372083D01*
X3879055Y2373124D01*
X3879675Y2374374D01*
X3880140Y2376041D01*
X3880295Y2377916D01*
X3880140Y2379791D01*
X3879675Y2381458D01*
X3879055Y2382708D01*
X3878125Y2383749D01*
X3876885Y2384166D01*
G01X3886650Y2373124D02*
X3887735Y2372083D01*
X3888975Y2371666D01*
X3890215Y2372083D01*
X3891300Y2373332D01*
X3892075Y2375208D01*
X3892385Y2377083D01*
Y2379374D01*
X3892075Y2381249D01*
X3891300Y2382916D01*
X3890370Y2383749D01*
X3889285Y2384166D01*
X3888045Y2383749D01*
X3887115Y2382916D01*
X3886495Y2381666D01*
X3886185Y2379999D01*
X3886495Y2378541D01*
X3887270Y2377083D01*
X3888200Y2376249D01*
X3889285Y2376041D01*
X3890525Y2376457D01*
X3891455Y2377499D01*
X3892385Y2379374D01*
G01X3901685Y2371249D02*
X3901375Y2371458D01*
Y2371874D01*
X3901685Y2372083D01*
X3901995Y2371874D01*
Y2371458D01*
X3901685Y2371249D01*
G01X3911140Y2382083D02*
X3912070Y2383332D01*
X3913155Y2383958D01*
X3914395Y2384166D01*
X3915945Y2383749D01*
X3917030Y2382708D01*
X3917340Y2381458D01*
X3917185Y2380207D01*
X3916565Y2379166D01*
X3913465Y2377083D01*
X3912070Y2375624D01*
X3911140Y2373541D01*
X3910830Y2371666D01*
X3917340D01*
G01X3923075Y2373541D02*
X3924005Y2372499D01*
X3925090Y2371874D01*
X3926485Y2371666D01*
X3927880Y2372083D01*
X3928965Y2372916D01*
X3929740Y2374374D01*
X3929895Y2376041D01*
X3929585Y2377708D01*
X3928810Y2378749D01*
X3927725Y2379583D01*
X3926640Y2379791D01*
X3925555Y2379583D01*
X3924160Y2378749D01*
X3924625Y2384166D01*
X3928810D01*
G01X3864966Y2818348D02*
Y2830848D01*
X3868996Y2820431D01*
X3873026Y2830848D01*
Y2818348D01*
G01X3877521D02*
X3881396Y2830848D01*
X3885271Y2818348D01*
G01X3883876Y2822723D02*
X3878916D01*
G01X3890541Y2818348D02*
X3897051Y2830848D01*
G01X3890541D02*
X3897051Y2818348D01*
G01X3901546Y2814181D02*
X3910846D01*
G01X3915186Y2818348D02*
Y2830848D01*
X3918286D01*
X3919526Y2830223D01*
X3920456Y2829390D01*
X3921231Y2828140D01*
X3921851Y2826681D01*
X3922006Y2824598D01*
X3921851Y2822515D01*
X3921231Y2821056D01*
X3920456Y2819806D01*
X3919526Y2818973D01*
X3918286Y2818348D01*
X3915186D01*
G01X3934096D02*
X3927896D01*
Y2830848D01*
X3934096D01*
G01X3931616Y2824806D02*
X3927896D01*
G01X3940296Y2818348D02*
Y2830848D01*
X3944016D01*
X3945256Y2830223D01*
X3946186Y2828765D01*
X3946496Y2827098D01*
X3946186Y2825431D01*
X3945411Y2824181D01*
X3944016Y2823556D01*
X3940296D01*
G01X3955796Y2830848D02*
Y2818348D01*
G01X3952231Y2830848D02*
X3959361D01*
G01X3964941Y2818348D02*
Y2830848D01*
G01X3971451D02*
Y2818348D01*
G01Y2824598D02*
X3964941D01*
G01X3877401Y1665462D02*
Y1677962D01*
X3881431Y1667545D01*
X3885461Y1677962D01*
Y1665462D01*
G01X3889956D02*
X3893831Y1677962D01*
X3897706Y1665462D01*
G01X3896311Y1669837D02*
X3891351D01*
G01X3902976Y1665462D02*
X3909486Y1677962D01*
G01X3902976D02*
X3909486Y1665462D01*
G01X3913981Y1661295D02*
X3923281D01*
G01X3927621Y1665462D02*
Y1677962D01*
X3930721D01*
X3931961Y1677337D01*
X3932891Y1676504D01*
X3933666Y1675254D01*
X3934286Y1673795D01*
X3934441Y1671712D01*
X3934286Y1669629D01*
X3933666Y1668170D01*
X3932891Y1666920D01*
X3931961Y1666087D01*
X3930721Y1665462D01*
X3927621D01*
G01X3946531D02*
X3940331D01*
Y1677962D01*
X3946531D01*
G01X3944051Y1671920D02*
X3940331D01*
G01X3952731Y1665462D02*
Y1677962D01*
X3956451D01*
X3957691Y1677337D01*
X3958621Y1675879D01*
X3958931Y1674212D01*
X3958621Y1672545D01*
X3957846Y1671295D01*
X3956451Y1670670D01*
X3952731D01*
G01X3968231Y1677962D02*
Y1665462D01*
G01X3964666Y1677962D02*
X3971796D01*
G01X3977376Y1665462D02*
Y1677962D01*
G01X3983886D02*
Y1665462D01*
G01Y1671712D02*
X3977376D01*
G01X3873129Y2002444D02*
X3874214Y2001403D01*
X3875454Y2000986D01*
X3876694Y2001403D01*
X3877779Y2002652D01*
X3878554Y2004528D01*
X3878864Y2006403D01*
Y2008694D01*
X3878554Y2010569D01*
X3877779Y2012236D01*
X3876849Y2013069D01*
X3875764Y2013486D01*
X3874524Y2013069D01*
X3873594Y2012236D01*
X3872974Y2010986D01*
X3872664Y2009319D01*
X3872974Y2007861D01*
X3873749Y2006403D01*
X3874679Y2005569D01*
X3875764Y2005361D01*
X3877004Y2005777D01*
X3877934Y2006819D01*
X3878864Y2008694D01*
G01X3884754Y2003486D02*
X3885684Y2002027D01*
X3886924Y2001194D01*
X3888319Y2000986D01*
X3889559Y2001194D01*
X3890799Y2002236D01*
X3891574Y2003486D01*
X3891729Y2004736D01*
X3891419Y2006194D01*
X3890334Y2007236D01*
X3889249Y2007653D01*
X3887854D01*
G01X3889249D02*
X3890179Y2008278D01*
X3890954Y2009319D01*
X3891264Y2010569D01*
X3890954Y2011819D01*
X3890179Y2012861D01*
X3888784Y2013486D01*
X3887389Y2013278D01*
X3885994Y2012444D01*
G01X3900564Y2000569D02*
X3900254Y2000778D01*
Y2001194D01*
X3900564Y2001403D01*
X3900874Y2001194D01*
Y2000778D01*
X3900564Y2000569D01*
G01X3909554Y2003486D02*
X3910484Y2002027D01*
X3911724Y2001194D01*
X3913119Y2000986D01*
X3914359Y2001194D01*
X3915599Y2002236D01*
X3916374Y2003486D01*
X3916529Y2004736D01*
X3916219Y2006194D01*
X3915134Y2007236D01*
X3914049Y2007653D01*
X3912654D01*
G01X3914049D02*
X3914979Y2008278D01*
X3915754Y2009319D01*
X3916064Y2010569D01*
X3915754Y2011819D01*
X3914979Y2012861D01*
X3913584Y2013486D01*
X3912189Y2013278D01*
X3910794Y2012444D01*
G01X3921954Y2002861D02*
X3922884Y2001819D01*
X3923969Y2001194D01*
X3925364Y2000986D01*
X3926759Y2001403D01*
X3927844Y2002236D01*
X3928619Y2003694D01*
X3928774Y2005361D01*
X3928464Y2007028D01*
X3927689Y2008069D01*
X3926604Y2008903D01*
X3925519Y2009111D01*
X3924434Y2008903D01*
X3923039Y2008069D01*
X3923504Y2013486D01*
X3927689D01*
G01X3890851Y2748556D02*
X3891936Y2750015D01*
X3892866Y2750848D01*
X3894106Y2751265D01*
X3895191Y2750848D01*
X3895966Y2750015D01*
X3896586Y2748765D01*
X3896741Y2747306D01*
X3896586Y2746056D01*
X3895966Y2744806D01*
X3895036Y2743765D01*
X3893951Y2743348D01*
X3892711Y2743765D01*
X3891626Y2745014D01*
X3891006Y2746890D01*
X3890851Y2748973D01*
X3891161Y2751681D01*
X3891626Y2753140D01*
X3892401Y2754598D01*
X3893486Y2755640D01*
X3894571Y2755848D01*
X3895656Y2755431D01*
X3896431Y2754390D01*
G01X3903561Y2744806D02*
X3904646Y2743765D01*
X3905886Y2743348D01*
X3907126Y2743765D01*
X3908211Y2745014D01*
X3908986Y2746890D01*
X3909296Y2748765D01*
Y2751056D01*
X3908986Y2752931D01*
X3908211Y2754598D01*
X3907281Y2755431D01*
X3906196Y2755848D01*
X3904956Y2755431D01*
X3904026Y2754598D01*
X3903406Y2753348D01*
X3903096Y2751681D01*
X3903406Y2750223D01*
X3904181Y2748765D01*
X3905111Y2747931D01*
X3906196Y2747723D01*
X3907436Y2748139D01*
X3908366Y2749181D01*
X3909296Y2751056D01*
G01X3918596Y2742931D02*
X3918286Y2743140D01*
Y2743556D01*
X3918596Y2743765D01*
X3918906Y2743556D01*
Y2743140D01*
X3918596Y2742931D01*
G01X3932856Y2743348D02*
Y2755848D01*
X3927121Y2746890D01*
X3934871D01*
G01X3939986Y2745223D02*
X3940916Y2744181D01*
X3942001Y2743556D01*
X3943396Y2743348D01*
X3944791Y2743765D01*
X3945876Y2744598D01*
X3946651Y2746056D01*
X3946806Y2747723D01*
X3946496Y2749390D01*
X3945721Y2750431D01*
X3944636Y2751265D01*
X3943551Y2751473D01*
X3942466Y2751265D01*
X3941071Y2750431D01*
X3941536Y2755848D01*
X3945721D01*
G01X3890851Y2773556D02*
X3891936Y2775015D01*
X3892866Y2775848D01*
X3894106Y2776265D01*
X3895191Y2775848D01*
X3895966Y2775015D01*
X3896586Y2773765D01*
X3896741Y2772306D01*
X3896586Y2771056D01*
X3895966Y2769806D01*
X3895036Y2768765D01*
X3893951Y2768348D01*
X3892711Y2768765D01*
X3891626Y2770014D01*
X3891006Y2771890D01*
X3890851Y2773973D01*
X3891161Y2776681D01*
X3891626Y2778140D01*
X3892401Y2779598D01*
X3893486Y2780640D01*
X3894571Y2780848D01*
X3895656Y2780431D01*
X3896431Y2779390D01*
G01X3903561Y2769806D02*
X3904646Y2768765D01*
X3905886Y2768348D01*
X3907126Y2768765D01*
X3908211Y2770014D01*
X3908986Y2771890D01*
X3909296Y2773765D01*
Y2776056D01*
X3908986Y2777931D01*
X3908211Y2779598D01*
X3907281Y2780431D01*
X3906196Y2780848D01*
X3904956Y2780431D01*
X3904026Y2779598D01*
X3903406Y2778348D01*
X3903096Y2776681D01*
X3903406Y2775223D01*
X3904181Y2773765D01*
X3905111Y2772931D01*
X3906196Y2772723D01*
X3907436Y2773139D01*
X3908366Y2774181D01*
X3909296Y2776056D01*
G01X3918596Y2767931D02*
X3918286Y2768140D01*
Y2768556D01*
X3918596Y2768765D01*
X3918906Y2768556D01*
Y2768140D01*
X3918596Y2767931D01*
G01X3932856Y2768348D02*
Y2780848D01*
X3927121Y2771890D01*
X3934871D01*
G01X3939986Y2770223D02*
X3940916Y2769181D01*
X3942001Y2768556D01*
X3943396Y2768348D01*
X3944791Y2768765D01*
X3945876Y2769598D01*
X3946651Y2771056D01*
X3946806Y2772723D01*
X3946496Y2774390D01*
X3945721Y2775431D01*
X3944636Y2776265D01*
X3943551Y2776473D01*
X3942466Y2776265D01*
X3941071Y2775431D01*
X3941536Y2780848D01*
X3945721D01*
G01X3890851Y2798556D02*
X3891936Y2800015D01*
X3892866Y2800848D01*
X3894106Y2801265D01*
X3895191Y2800848D01*
X3895966Y2800015D01*
X3896586Y2798765D01*
X3896741Y2797306D01*
X3896586Y2796056D01*
X3895966Y2794806D01*
X3895036Y2793765D01*
X3893951Y2793348D01*
X3892711Y2793765D01*
X3891626Y2795014D01*
X3891006Y2796890D01*
X3890851Y2798973D01*
X3891161Y2801681D01*
X3891626Y2803140D01*
X3892401Y2804598D01*
X3893486Y2805640D01*
X3894571Y2805848D01*
X3895656Y2805431D01*
X3896431Y2804390D01*
G01X3903561Y2794806D02*
X3904646Y2793765D01*
X3905886Y2793348D01*
X3907126Y2793765D01*
X3908211Y2795014D01*
X3908986Y2796890D01*
X3909296Y2798765D01*
Y2801056D01*
X3908986Y2802931D01*
X3908211Y2804598D01*
X3907281Y2805431D01*
X3906196Y2805848D01*
X3904956Y2805431D01*
X3904026Y2804598D01*
X3903406Y2803348D01*
X3903096Y2801681D01*
X3903406Y2800223D01*
X3904181Y2798765D01*
X3905111Y2797931D01*
X3906196Y2797723D01*
X3907436Y2798139D01*
X3908366Y2799181D01*
X3909296Y2801056D01*
G01X3918596Y2792931D02*
X3918286Y2793140D01*
Y2793556D01*
X3918596Y2793765D01*
X3918906Y2793556D01*
Y2793140D01*
X3918596Y2792931D01*
G01X3932856Y2793348D02*
Y2805848D01*
X3927121Y2796890D01*
X3934871D01*
G01X3939986Y2795223D02*
X3940916Y2794181D01*
X3942001Y2793556D01*
X3943396Y2793348D01*
X3944791Y2793765D01*
X3945876Y2794598D01*
X3946651Y2796056D01*
X3946806Y2797723D01*
X3946496Y2799390D01*
X3945721Y2800431D01*
X3944636Y2801265D01*
X3943551Y2801473D01*
X3942466Y2801265D01*
X3941071Y2800431D01*
X3941536Y2805848D01*
X3945721D01*
G01X3905921Y1640462D02*
X3906231Y1643170D01*
X3906696Y1645462D01*
X3907316Y1647545D01*
X3908091Y1649837D01*
X3909331Y1652962D01*
X3903131D01*
G01X3918631Y1640462D02*
X3919716Y1640670D01*
X3920956Y1641295D01*
X3921731Y1642337D01*
X3922041Y1643795D01*
X3921731Y1645253D01*
X3920801Y1646504D01*
X3919406Y1647129D01*
X3917856D01*
X3916926Y1647545D01*
X3916151Y1648587D01*
X3915841Y1650045D01*
X3916306Y1651504D01*
X3917391Y1652545D01*
X3918631Y1652962D01*
X3919871Y1652545D01*
X3920956Y1651504D01*
X3921421Y1650045D01*
X3921111Y1648587D01*
X3920336Y1647545D01*
X3919406Y1647129D01*
X3917856D01*
X3916461Y1646504D01*
X3915531Y1645253D01*
X3915221Y1643795D01*
X3915531Y1642337D01*
X3916306Y1641295D01*
X3917546Y1640670D01*
X3918631Y1640462D01*
G01X3931031Y1640045D02*
X3930721Y1640254D01*
Y1640670D01*
X3931031Y1640879D01*
X3931341Y1640670D01*
Y1640254D01*
X3931031Y1640045D01*
G01X3943121Y1640462D02*
X3943431Y1643170D01*
X3943896Y1645462D01*
X3944516Y1647545D01*
X3945291Y1649837D01*
X3946531Y1652962D01*
X3940331D01*
G01X3952421Y1642337D02*
X3953351Y1641295D01*
X3954436Y1640670D01*
X3955831Y1640462D01*
X3957226Y1640879D01*
X3958311Y1641712D01*
X3959086Y1643170D01*
X3959241Y1644837D01*
X3958931Y1646504D01*
X3958156Y1647545D01*
X3957071Y1648379D01*
X3955986Y1648587D01*
X3954901Y1648379D01*
X3953506Y1647545D01*
X3953971Y1652962D01*
X3958156D01*
G01X3980234Y2025986D02*
Y2038486D01*
X3984264Y2028069D01*
X3988294Y2038486D01*
Y2025986D01*
G01X3993719D02*
Y2038486D01*
X3999609D01*
G01X3997439Y2032444D02*
X3993719D01*
G01X4009994Y2032236D02*
X4013094D01*
Y2028486D01*
X4012164Y2027236D01*
X4011079Y2026403D01*
X4009529Y2025986D01*
X4007979Y2026403D01*
X4006894Y2027236D01*
X4005964Y2028486D01*
X4005344Y2029944D01*
X4005034Y2031611D01*
Y2033069D01*
X4005344Y2034319D01*
X4005964Y2035778D01*
X4006894Y2037028D01*
X4007824Y2037861D01*
X4009064Y2038486D01*
X4010149D01*
X4011389Y2038069D01*
X4012319Y2037236D01*
G01X4016814Y2021819D02*
X4026114D01*
G01X4030609Y2027652D02*
X4031849Y2026611D01*
X4033244Y2025986D01*
X4034484D01*
X4035724Y2026611D01*
X4036654Y2027652D01*
X4037119Y2029111D01*
X4036809Y2030569D01*
X4036034Y2031819D01*
X4034639Y2032653D01*
X4032779Y2033069D01*
X4031694Y2033903D01*
X4031229Y2035361D01*
X4031539Y2036819D01*
X4032314Y2037861D01*
X4033399Y2038486D01*
X4034484D01*
X4035569Y2038069D01*
X4036499Y2037028D01*
G01X4046264Y2038486D02*
Y2025986D01*
G01X4042699Y2038486D02*
X4049829D01*
G01X4055254D02*
Y2029528D01*
X4055874Y2027652D01*
X4057114Y2026403D01*
X4058664Y2025986D01*
X4060214Y2026403D01*
X4061454Y2027652D01*
X4062074Y2029528D01*
Y2038486D01*
G01X4072304Y2032653D02*
X4072924Y2033278D01*
X4073389Y2034319D01*
X4073699Y2035778D01*
X4073389Y2037028D01*
X4072769Y2037861D01*
X4071684Y2038486D01*
X4067499D01*
Y2025986D01*
X4072614D01*
X4073699Y2026819D01*
X4074319Y2028069D01*
X4074629Y2029528D01*
X4074319Y2030986D01*
X4073389Y2032236D01*
X4072304Y2032653D01*
X4067499D01*
G01X3975155Y2396666D02*
Y2409166D01*
X3979185Y2398749D01*
X3983215Y2409166D01*
Y2396666D01*
G01X3988640D02*
Y2409166D01*
X3994530D01*
G01X3992360Y2403124D02*
X3988640D01*
G01X4004915Y2402916D02*
X4008015D01*
Y2399166D01*
X4007085Y2397916D01*
X4006000Y2397083D01*
X4004450Y2396666D01*
X4002900Y2397083D01*
X4001815Y2397916D01*
X4000885Y2399166D01*
X4000265Y2400624D01*
X3999955Y2402291D01*
Y2403749D01*
X4000265Y2404999D01*
X4000885Y2406458D01*
X4001815Y2407708D01*
X4002745Y2408541D01*
X4003985Y2409166D01*
X4005070D01*
X4006310Y2408749D01*
X4007240Y2407916D01*
G01X4011735Y2392499D02*
X4021035D01*
G01X4025530Y2398332D02*
X4026770Y2397291D01*
X4028165Y2396666D01*
X4029405D01*
X4030645Y2397291D01*
X4031575Y2398332D01*
X4032040Y2399791D01*
X4031730Y2401249D01*
X4030955Y2402499D01*
X4029560Y2403333D01*
X4027700Y2403749D01*
X4026615Y2404583D01*
X4026150Y2406041D01*
X4026460Y2407499D01*
X4027235Y2408541D01*
X4028320Y2409166D01*
X4029405D01*
X4030490Y2408749D01*
X4031420Y2407708D01*
G01X4041185Y2409166D02*
Y2396666D01*
G01X4037620Y2409166D02*
X4044750D01*
G01X4050175D02*
Y2400208D01*
X4050795Y2398332D01*
X4052035Y2397083D01*
X4053585Y2396666D01*
X4055135Y2397083D01*
X4056375Y2398332D01*
X4056995Y2400208D01*
Y2409166D01*
G01X4067225Y2403333D02*
X4067845Y2403958D01*
X4068310Y2404999D01*
X4068620Y2406458D01*
X4068310Y2407708D01*
X4067690Y2408541D01*
X4066605Y2409166D01*
X4062420D01*
Y2396666D01*
X4067535D01*
X4068620Y2397499D01*
X4069240Y2398749D01*
X4069550Y2400208D01*
X4069240Y2401666D01*
X4068310Y2402916D01*
X4067225Y2403333D01*
X4062420D01*
G01X3998266Y2818348D02*
Y2830848D01*
X4002296Y2820431D01*
X4006326Y2830848D01*
Y2818348D01*
G01X4011751D02*
Y2830848D01*
X4017641D01*
G01X4015471Y2824806D02*
X4011751D01*
G01X4028026Y2824598D02*
X4031126D01*
Y2820848D01*
X4030196Y2819598D01*
X4029111Y2818765D01*
X4027561Y2818348D01*
X4026011Y2818765D01*
X4024926Y2819598D01*
X4023996Y2820848D01*
X4023376Y2822306D01*
X4023066Y2823973D01*
Y2825431D01*
X4023376Y2826681D01*
X4023996Y2828140D01*
X4024926Y2829390D01*
X4025856Y2830223D01*
X4027096Y2830848D01*
X4028181D01*
X4029421Y2830431D01*
X4030351Y2829598D01*
G01X4034846Y2814181D02*
X4044146D01*
G01X4048641Y2820014D02*
X4049881Y2818973D01*
X4051276Y2818348D01*
X4052516D01*
X4053756Y2818973D01*
X4054686Y2820014D01*
X4055151Y2821473D01*
X4054841Y2822931D01*
X4054066Y2824181D01*
X4052671Y2825015D01*
X4050811Y2825431D01*
X4049726Y2826265D01*
X4049261Y2827723D01*
X4049571Y2829181D01*
X4050346Y2830223D01*
X4051431Y2830848D01*
X4052516D01*
X4053601Y2830431D01*
X4054531Y2829390D01*
G01X4064296Y2830848D02*
Y2818348D01*
G01X4060731Y2830848D02*
X4067861D01*
G01X4073286D02*
Y2821890D01*
X4073906Y2820014D01*
X4075146Y2818765D01*
X4076696Y2818348D01*
X4078246Y2818765D01*
X4079486Y2820014D01*
X4080106Y2821890D01*
Y2830848D01*
G01X4090336Y2825015D02*
X4090956Y2825640D01*
X4091421Y2826681D01*
X4091731Y2828140D01*
X4091421Y2829390D01*
X4090801Y2830223D01*
X4089716Y2830848D01*
X4085531D01*
Y2818348D01*
X4090646D01*
X4091731Y2819181D01*
X4092351Y2820431D01*
X4092661Y2821890D01*
X4092351Y2823348D01*
X4091421Y2824598D01*
X4090336Y2825015D01*
X4085531D01*
G01X4010701Y1665462D02*
Y1677962D01*
X4014731Y1667545D01*
X4018761Y1677962D01*
Y1665462D01*
G01X4024186D02*
Y1677962D01*
X4030076D01*
G01X4027906Y1671920D02*
X4024186D01*
G01X4040461Y1671712D02*
X4043561D01*
Y1667962D01*
X4042631Y1666712D01*
X4041546Y1665879D01*
X4039996Y1665462D01*
X4038446Y1665879D01*
X4037361Y1666712D01*
X4036431Y1667962D01*
X4035811Y1669420D01*
X4035501Y1671087D01*
Y1672545D01*
X4035811Y1673795D01*
X4036431Y1675254D01*
X4037361Y1676504D01*
X4038291Y1677337D01*
X4039531Y1677962D01*
X4040616D01*
X4041856Y1677545D01*
X4042786Y1676712D01*
G01X4047281Y1661295D02*
X4056581D01*
G01X4061076Y1667128D02*
X4062316Y1666087D01*
X4063711Y1665462D01*
X4064951D01*
X4066191Y1666087D01*
X4067121Y1667128D01*
X4067586Y1668587D01*
X4067276Y1670045D01*
X4066501Y1671295D01*
X4065106Y1672129D01*
X4063246Y1672545D01*
X4062161Y1673379D01*
X4061696Y1674837D01*
X4062006Y1676295D01*
X4062781Y1677337D01*
X4063866Y1677962D01*
X4064951D01*
X4066036Y1677545D01*
X4066966Y1676504D01*
G01X4076731Y1677962D02*
Y1665462D01*
G01X4073166Y1677962D02*
X4080296D01*
G01X4085721D02*
Y1669004D01*
X4086341Y1667128D01*
X4087581Y1665879D01*
X4089131Y1665462D01*
X4090681Y1665879D01*
X4091921Y1667128D01*
X4092541Y1669004D01*
Y1677962D01*
G01X4102771Y1672129D02*
X4103391Y1672754D01*
X4103856Y1673795D01*
X4104166Y1675254D01*
X4103856Y1676504D01*
X4103236Y1677337D01*
X4102151Y1677962D01*
X4097966D01*
Y1665462D01*
X4103081D01*
X4104166Y1666295D01*
X4104786Y1667545D01*
X4105096Y1669004D01*
X4104786Y1670462D01*
X4103856Y1671712D01*
X4102771Y1672129D01*
X4097966D01*
G01X4025649Y2005153D02*
X4029679D01*
G01X4020570Y2375833D02*
X4024600D01*
G01X4043681Y2747515D02*
X4047711D01*
G01X4043681Y2772515D02*
X4047711D01*
G01X4043681Y2797515D02*
X4047711D01*
G01X4056116Y1644629D02*
X4060146D01*
G01X4112485Y2396666D02*
X4111245Y2396874D01*
X4110160Y2397707D01*
X4109230Y2398958D01*
X4108610Y2400416D01*
X4108300Y2402083D01*
Y2403749D01*
X4108610Y2405416D01*
X4109230Y2406874D01*
X4110160Y2408124D01*
X4111245Y2408958D01*
X4112485Y2409166D01*
X4113725Y2408958D01*
X4114810Y2408124D01*
X4115740Y2406874D01*
X4116360Y2405416D01*
X4116670Y2403749D01*
Y2402083D01*
X4116360Y2400416D01*
X4115740Y2398958D01*
X4114810Y2397707D01*
X4113725Y2396874D01*
X4112485Y2396666D01*
G01X4113725Y2399999D02*
X4115585Y2396666D01*
G01X4124885Y2409166D02*
Y2396666D01*
G01X4121320Y2409166D02*
X4128450D01*
G01X4137285Y2396666D02*
Y2402291D01*
X4134185Y2409166D01*
G01X4140385D02*
X4137285Y2402291D01*
G01X4129964Y2000986D02*
X4131049Y2001194D01*
X4132289Y2001819D01*
X4133064Y2002861D01*
X4133374Y2004319D01*
X4133064Y2005777D01*
X4132134Y2007028D01*
X4130739Y2007653D01*
X4129189D01*
X4128259Y2008069D01*
X4127484Y2009111D01*
X4127174Y2010569D01*
X4127639Y2012028D01*
X4128724Y2013069D01*
X4129964Y2013486D01*
X4131204Y2013069D01*
X4132289Y2012028D01*
X4132754Y2010569D01*
X4132444Y2009111D01*
X4131669Y2008069D01*
X4130739Y2007653D01*
X4129189D01*
X4127794Y2007028D01*
X4126864Y2005777D01*
X4126554Y2004319D01*
X4126864Y2002861D01*
X4127639Y2001819D01*
X4128879Y2001194D01*
X4129964Y2000986D01*
G01X4117564Y2025986D02*
X4116324Y2026194D01*
X4115239Y2027027D01*
X4114309Y2028278D01*
X4113689Y2029736D01*
X4113379Y2031403D01*
Y2033069D01*
X4113689Y2034736D01*
X4114309Y2036194D01*
X4115239Y2037444D01*
X4116324Y2038278D01*
X4117564Y2038486D01*
X4118804Y2038278D01*
X4119889Y2037444D01*
X4120819Y2036194D01*
X4121439Y2034736D01*
X4121749Y2033069D01*
Y2031403D01*
X4121439Y2029736D01*
X4120819Y2028278D01*
X4119889Y2027027D01*
X4118804Y2026194D01*
X4117564Y2025986D01*
G01X4118804Y2029319D02*
X4120664Y2025986D01*
G01X4129964Y2038486D02*
Y2025986D01*
G01X4126399Y2038486D02*
X4133529D01*
G01X4142364Y2025986D02*
Y2031611D01*
X4139264Y2038486D01*
G01X4145464D02*
X4142364Y2031611D01*
G01X4124885Y2371666D02*
X4125970Y2371874D01*
X4127210Y2372499D01*
X4127985Y2373541D01*
X4128295Y2374999D01*
X4127985Y2376457D01*
X4127055Y2377708D01*
X4125660Y2378333D01*
X4124110D01*
X4123180Y2378749D01*
X4122405Y2379791D01*
X4122095Y2381249D01*
X4122560Y2382708D01*
X4123645Y2383749D01*
X4124885Y2384166D01*
X4126125Y2383749D01*
X4127210Y2382708D01*
X4127675Y2381249D01*
X4127365Y2379791D01*
X4126590Y2378749D01*
X4125660Y2378333D01*
X4124110D01*
X4122715Y2377708D01*
X4121785Y2376457D01*
X4121475Y2374999D01*
X4121785Y2373541D01*
X4122560Y2372499D01*
X4123800Y2371874D01*
X4124885Y2371666D01*
G01X4148031Y1665462D02*
X4146791Y1665670D01*
X4145706Y1666503D01*
X4144776Y1667754D01*
X4144156Y1669212D01*
X4143846Y1670879D01*
Y1672545D01*
X4144156Y1674212D01*
X4144776Y1675670D01*
X4145706Y1676920D01*
X4146791Y1677754D01*
X4148031Y1677962D01*
X4149271Y1677754D01*
X4150356Y1676920D01*
X4151286Y1675670D01*
X4151906Y1674212D01*
X4152216Y1672545D01*
Y1670879D01*
X4151906Y1669212D01*
X4151286Y1667754D01*
X4150356Y1666503D01*
X4149271Y1665670D01*
X4148031Y1665462D01*
G01X4149271Y1668795D02*
X4151131Y1665462D01*
G01X4160431Y1677962D02*
Y1665462D01*
G01X4156866Y1677962D02*
X4163996D01*
G01X4172831Y1665462D02*
Y1671087D01*
X4169731Y1677962D01*
G01X4175931D02*
X4172831Y1671087D01*
G01X4132651Y2753765D02*
X4133581Y2755014D01*
X4134666Y2755640D01*
X4135906Y2755848D01*
X4137456Y2755431D01*
X4138541Y2754390D01*
X4138851Y2753140D01*
X4138696Y2751889D01*
X4138076Y2750848D01*
X4134976Y2748765D01*
X4133581Y2747306D01*
X4132651Y2745223D01*
X4132341Y2743348D01*
X4138851D01*
G01X4144586Y2745223D02*
X4145516Y2744181D01*
X4146601Y2743556D01*
X4147996Y2743348D01*
X4149391Y2743765D01*
X4150476Y2744598D01*
X4151251Y2746056D01*
X4151406Y2747723D01*
X4151096Y2749390D01*
X4150321Y2750431D01*
X4149236Y2751265D01*
X4148151Y2751473D01*
X4147066Y2751265D01*
X4145671Y2750431D01*
X4146136Y2755848D01*
X4150321D01*
G01X4157451Y2748556D02*
X4158536Y2750015D01*
X4159466Y2750848D01*
X4160706Y2751265D01*
X4161791Y2750848D01*
X4162566Y2750015D01*
X4163186Y2748765D01*
X4163341Y2747306D01*
X4163186Y2746056D01*
X4162566Y2744806D01*
X4161636Y2743765D01*
X4160551Y2743348D01*
X4159311Y2743765D01*
X4158226Y2745014D01*
X4157606Y2746890D01*
X4157451Y2748973D01*
X4157761Y2751681D01*
X4158226Y2753140D01*
X4159001Y2754598D01*
X4160086Y2755640D01*
X4161171Y2755848D01*
X4162256Y2755431D01*
X4163031Y2754390D01*
G01X4132651Y2773556D02*
X4133736Y2775015D01*
X4134666Y2775848D01*
X4135906Y2776265D01*
X4136991Y2775848D01*
X4137766Y2775015D01*
X4138386Y2773765D01*
X4138541Y2772306D01*
X4138386Y2771056D01*
X4137766Y2769806D01*
X4136836Y2768765D01*
X4135751Y2768348D01*
X4134511Y2768765D01*
X4133426Y2770014D01*
X4132806Y2771890D01*
X4132651Y2773973D01*
X4132961Y2776681D01*
X4133426Y2778140D01*
X4134201Y2779598D01*
X4135286Y2780640D01*
X4136371Y2780848D01*
X4137456Y2780431D01*
X4138231Y2779390D01*
G01X4149856Y2768348D02*
Y2780848D01*
X4144121Y2771890D01*
X4151871D01*
G01X4160396Y2768348D02*
X4161481Y2768556D01*
X4162721Y2769181D01*
X4163496Y2770223D01*
X4163806Y2771681D01*
X4163496Y2773139D01*
X4162566Y2774390D01*
X4161171Y2775015D01*
X4159621D01*
X4158691Y2775431D01*
X4157916Y2776473D01*
X4157606Y2777931D01*
X4158071Y2779390D01*
X4159156Y2780431D01*
X4160396Y2780848D01*
X4161636Y2780431D01*
X4162721Y2779390D01*
X4163186Y2777931D01*
X4162876Y2776473D01*
X4162101Y2775431D01*
X4161171Y2775015D01*
X4159621D01*
X4158226Y2774390D01*
X4157296Y2773139D01*
X4156986Y2771681D01*
X4157296Y2770223D01*
X4158071Y2769181D01*
X4159311Y2768556D01*
X4160396Y2768348D01*
G01X4132186Y2795848D02*
X4133116Y2794389D01*
X4134356Y2793556D01*
X4135751Y2793348D01*
X4136991Y2793556D01*
X4138231Y2794598D01*
X4139006Y2795848D01*
X4139161Y2797098D01*
X4138851Y2798556D01*
X4137766Y2799598D01*
X4136681Y2800015D01*
X4135286D01*
G01X4136681D02*
X4137611Y2800640D01*
X4138386Y2801681D01*
X4138696Y2802931D01*
X4138386Y2804181D01*
X4137611Y2805223D01*
X4136216Y2805848D01*
X4134821Y2805640D01*
X4133426Y2804806D01*
G01X4147996Y2793348D02*
X4149081Y2793556D01*
X4150321Y2794181D01*
X4151096Y2795223D01*
X4151406Y2796681D01*
X4151096Y2798139D01*
X4150166Y2799390D01*
X4148771Y2800015D01*
X4147221D01*
X4146291Y2800431D01*
X4145516Y2801473D01*
X4145206Y2802931D01*
X4145671Y2804390D01*
X4146756Y2805431D01*
X4147996Y2805848D01*
X4149236Y2805431D01*
X4150321Y2804390D01*
X4150786Y2802931D01*
X4150476Y2801473D01*
X4149701Y2800431D01*
X4148771Y2800015D01*
X4147221D01*
X4145826Y2799390D01*
X4144896Y2798139D01*
X4144586Y2796681D01*
X4144896Y2795223D01*
X4145671Y2794181D01*
X4146911Y2793556D01*
X4147996Y2793348D01*
G01X4162256D02*
Y2805848D01*
X4156521Y2796890D01*
X4164271D01*
G01X4135596Y2818348D02*
X4134356Y2818556D01*
X4133271Y2819389D01*
X4132341Y2820640D01*
X4131721Y2822098D01*
X4131411Y2823765D01*
Y2825431D01*
X4131721Y2827098D01*
X4132341Y2828556D01*
X4133271Y2829806D01*
X4134356Y2830640D01*
X4135596Y2830848D01*
X4136836Y2830640D01*
X4137921Y2829806D01*
X4138851Y2828556D01*
X4139471Y2827098D01*
X4139781Y2825431D01*
Y2823765D01*
X4139471Y2822098D01*
X4138851Y2820640D01*
X4137921Y2819389D01*
X4136836Y2818556D01*
X4135596Y2818348D01*
G01X4136836Y2821681D02*
X4138696Y2818348D01*
G01X4147996Y2830848D02*
Y2818348D01*
G01X4144431Y2830848D02*
X4151561D01*
G01X4160396Y2818348D02*
Y2823973D01*
X4157296Y2830848D01*
G01X4163496D02*
X4160396Y2823973D01*
G01X4160431Y1640462D02*
X4161516Y1640670D01*
X4162756Y1641295D01*
X4163531Y1642337D01*
X4163841Y1643795D01*
X4163531Y1645253D01*
X4162601Y1646504D01*
X4161206Y1647129D01*
X4159656D01*
X4158726Y1647545D01*
X4157951Y1648587D01*
X4157641Y1650045D01*
X4158106Y1651504D01*
X4159191Y1652545D01*
X4160431Y1652962D01*
X4161671Y1652545D01*
X4162756Y1651504D01*
X4163221Y1650045D01*
X4162911Y1648587D01*
X4162136Y1647545D01*
X4161206Y1647129D01*
X4159656D01*
X4158261Y1646504D01*
X4157331Y1645253D01*
X4157021Y1643795D01*
X4157331Y1642337D01*
X4158106Y1641295D01*
X4159346Y1640670D01*
X4160431Y1640462D01*
G54D18*
X51043Y144095D03*
X57933Y66811D03*
X160295D03*
X153405Y144095D03*
X183435Y630650D03*
X190325Y374862D03*
X262657Y66811D03*
X255767Y144095D03*
X279360Y630650D03*
X286250Y374862D03*
X358129Y144095D03*
X365019Y66811D03*
X508130Y144095D03*
X515020Y66811D03*
X617382D03*
X610492Y144095D03*
X647411Y374862D03*
X640521Y630650D03*
X719744Y66811D03*
X712854Y144095D03*
X736446Y630650D03*
X743336Y374862D03*
X815216Y144095D03*
X822106Y66811D03*
X972106D03*
X965216Y144095D03*
X1074468Y66811D03*
X1067578Y144095D03*
X1104498Y374862D03*
X1097608Y630650D03*
X1169940Y144095D03*
X1176830Y66811D03*
X1200423Y374862D03*
X1193533Y630650D03*
X1272302Y144095D03*
X1279192Y66811D03*
X1429193D03*
X1422303Y144095D03*
X1531555Y66811D03*
X1524665Y144095D03*
X1561585Y374862D03*
X1554695Y630650D03*
X1627027Y144095D03*
X1633917Y66811D03*
X1657510Y374862D03*
X1650620Y630650D03*
X1736279Y66811D03*
X1729389Y144095D03*
X2785168Y302113D03*
Y335263D03*
G54D27*
X849441Y1367717D03*
X2785168Y467863D03*
G54D19*
X51750Y617861D03*
X48207D03*
X44664D03*
X51750Y620661D03*
X48207D03*
X44664D03*
X55294Y617861D03*
Y620661D03*
X73872Y1348187D03*
X81752D03*
X73872Y1360099D03*
X81752D03*
X73872Y1384297D03*
Y1372385D03*
X81752Y1384297D03*
Y1372385D03*
X86112Y1348187D03*
X98352D03*
X93992D03*
X86112Y1360099D03*
X98352D03*
X93992D03*
X86112Y1384297D03*
Y1372385D03*
X98352Y1384297D03*
Y1372385D03*
X93992D03*
Y1384297D03*
X86112Y1396583D03*
X93992D03*
X98352D03*
X86112Y1408495D03*
X93992D03*
X98352D03*
X110592Y1348187D03*
X106232D03*
X110592Y1360099D03*
X106232D03*
X110592Y1384297D03*
X106232D03*
Y1372385D03*
X110592D03*
Y1396583D03*
X106232D03*
X110592Y1408495D03*
X106232D03*
X118472Y1348187D03*
X122832D03*
X130712D03*
X118472Y1360099D03*
X122832D03*
X130712D03*
X118472Y1384297D03*
Y1372385D03*
X122832Y1384297D03*
Y1372385D03*
X130712Y1384297D03*
Y1372385D03*
X118472Y1396583D03*
X122832D03*
X130712D03*
X118472Y1408495D03*
X122832D03*
X130712D03*
X143208Y1084547D03*
Y1092027D03*
X146948Y1077066D03*
Y1080806D03*
Y1084547D03*
Y1092027D03*
Y1088287D03*
X143208D03*
Y1095767D03*
X146948D03*
Y1103247D03*
X143208D03*
X146948Y1099507D03*
X143208D03*
X146948Y1106988D03*
X143208D03*
Y1110728D03*
Y1118208D03*
X146948Y1110728D03*
Y1118208D03*
Y1114468D03*
Y1121948D03*
X143208Y1114468D03*
Y1121948D03*
X150689Y1133169D03*
X143208Y1136909D03*
X146948D03*
Y1133169D03*
Y1140649D03*
X139468Y1136909D03*
X143208Y1125688D03*
Y1133169D03*
Y1140649D03*
X146948Y1125688D03*
Y1129429D03*
X143208D03*
X146948Y1136909D03*
X143208D03*
Y1144389D03*
Y1151870D03*
X146948Y1144389D03*
Y1151870D03*
Y1148129D03*
X143208D03*
X140707Y1170569D03*
X143208Y1159350D03*
X146949Y1166830D03*
X146948Y1159350D03*
X146947Y1170570D03*
X143207D03*
X148818Y1191141D03*
X145078D03*
X148818Y1183661D03*
X140707Y1178050D03*
X145078Y1187401D03*
Y1183661D03*
X148818Y1187401D03*
X146947Y1174310D03*
Y1178051D03*
X143207D03*
X148818Y1198621D03*
X145078D03*
X148818Y1206102D03*
X145078D03*
X141337Y1191142D03*
X145078Y1194881D03*
Y1202362D03*
X148818Y1194881D03*
Y1202362D03*
X141337Y1198622D03*
X145078Y1198621D03*
Y1191141D03*
X148818D03*
Y1198621D03*
X145078Y1213582D03*
X148818D03*
Y1221062D03*
X145078D03*
D03*
X148818D03*
X141337Y1206103D03*
X145078Y1209842D03*
Y1217322D03*
X148818Y1209842D03*
Y1217322D03*
X141337Y1213583D03*
Y1221063D03*
X148818Y1213582D03*
X145078D03*
Y1206102D03*
X148818D03*
Y1228543D03*
X145078D03*
Y1239763D03*
X148818D03*
Y1224803D03*
X145078Y1232283D03*
Y1236023D03*
X148818Y1232283D03*
Y1236023D03*
X145078Y1224803D03*
X141337Y1228542D03*
X145078Y1228543D03*
X148818D03*
X145078Y1247243D03*
X148818D03*
D03*
X145078D03*
X148818Y1254724D03*
X145078Y1250984D03*
X148818Y1243503D03*
Y1250984D03*
X141336Y1247242D03*
Y1239762D03*
X145078Y1243503D03*
X148818Y1239763D03*
X145078D03*
X135072Y1348187D03*
X142952D03*
X147312D03*
X135072Y1360099D03*
X147312D03*
X142952D03*
X135072Y1384297D03*
Y1372385D03*
X147312Y1384297D03*
Y1372385D03*
X142952Y1384297D03*
Y1372385D03*
X135072Y1396583D03*
X147312D03*
X142952D03*
X135072Y1408495D03*
X147312D03*
X142952D03*
X154429Y1073326D03*
X161909D03*
X165649D03*
X158169D03*
X150689D03*
X154429Y1092027D03*
X161909Y1077066D03*
X165649Y1080807D03*
Y1088287D03*
X161909D03*
Y1092027D03*
X150688Y1077066D03*
X154429D03*
X158169Y1080807D03*
X150689D03*
X158169Y1084547D03*
X150689D03*
X158169Y1088287D03*
X154429D03*
X150689D03*
X165649Y1084547D03*
Y1092027D03*
X158169D03*
X150689D03*
X165649Y1077066D03*
X161909Y1084547D03*
X158169Y1077066D03*
X154429Y1084547D03*
X161909Y1080807D03*
X154429D03*
X158169Y1099507D03*
X150689D03*
X158169Y1103247D03*
X150689D03*
X158169Y1106988D03*
X161909Y1095767D03*
X165649Y1099507D03*
Y1103247D03*
Y1106988D03*
X161909D03*
X154429D03*
X150689D03*
X154429Y1095767D03*
X165649D03*
X161909Y1103247D03*
X158169Y1095767D03*
X154429Y1103247D03*
X150689Y1095767D03*
X161909Y1099507D03*
X154429D03*
X158169Y1110728D03*
Y1114468D03*
X154429D03*
X150689D03*
X158169Y1118208D03*
Y1121948D03*
X154429D03*
X150689D03*
X165649Y1114468D03*
X161909D03*
Y1118208D03*
Y1121948D03*
X165649Y1110728D03*
X161909D03*
X154429D03*
Y1118208D03*
X150689Y1110728D03*
Y1118208D03*
X165649Y1133169D03*
X154429D03*
X161909D03*
X158169D03*
X161909Y1140649D03*
X158169Y1125688D03*
Y1129429D03*
X154429D03*
X150689D03*
Y1136909D03*
X154429Y1140649D03*
X150689D03*
X165649D03*
X161909Y1125688D03*
X165649Y1129429D03*
X161909D03*
X165649Y1136909D03*
X158169Y1140649D03*
X154429Y1125688D03*
X150689D03*
Y1133169D03*
X165649D03*
X161909D03*
X154429D03*
X150689Y1151870D03*
X158169Y1155610D03*
X154429D03*
X150689D03*
X161909Y1144389D03*
Y1148129D03*
Y1151870D03*
Y1155610D03*
X150689Y1144389D03*
X158169Y1151869D03*
X154429D03*
X150689Y1148129D03*
X165649D03*
Y1144389D03*
Y1155610D03*
X150689Y1159350D03*
X158169Y1166830D03*
X154429D03*
X150688D03*
X154429Y1170570D03*
X150688D03*
X161909Y1159350D03*
X165649Y1166830D03*
Y1170570D03*
X152559Y1187401D03*
X163779D03*
X156299D03*
X167519D03*
X160039D03*
X156299Y1183661D03*
X152559D03*
X161909Y1174310D03*
Y1178051D03*
X165649Y1181791D03*
X161909D03*
X165649Y1178050D03*
Y1174310D03*
X158169D03*
X154429D03*
X150688Y1178051D03*
Y1174310D03*
X156299Y1179921D03*
X160039Y1183661D03*
X163779D03*
X156299Y1187401D03*
X163779D03*
X152559D03*
X160039Y1176180D03*
X156299D03*
X167519Y1202362D03*
Y1194881D03*
X163779Y1202362D03*
Y1194881D03*
X152559D03*
Y1202362D03*
X156299Y1194881D03*
Y1202362D03*
X160039Y1194881D03*
Y1202362D03*
X156299Y1198621D03*
X152559D03*
X163779D03*
X160039D03*
X152559Y1191141D03*
X156299D03*
X160039D03*
X163779D03*
X156299Y1202362D03*
Y1194881D03*
X152559Y1202362D03*
Y1194881D03*
X163779D03*
Y1202362D03*
X152559Y1209842D03*
X156299D03*
Y1217322D03*
X152559D03*
X163779D03*
Y1209842D03*
X167519Y1217322D03*
Y1209842D03*
X160039Y1206102D03*
X156299D03*
X152559D03*
X163779D03*
X160039Y1209842D03*
Y1217322D03*
X156299Y1213582D03*
X152559D03*
X160039Y1221062D03*
X156299D03*
X152559D03*
X163779Y1213582D03*
Y1221062D03*
X160039Y1213582D03*
X156299Y1217322D03*
Y1209842D03*
X152559D03*
X163779D03*
Y1217322D03*
X152559D03*
X167519Y1236023D03*
Y1232283D03*
X152559D03*
Y1236023D03*
X160039Y1232283D03*
X163779Y1228543D03*
X156299D03*
Y1224803D03*
X163779D03*
X160039Y1236023D03*
Y1228543D03*
X152559D03*
X160039Y1224803D03*
X152559D03*
X156299Y1232283D03*
Y1236023D03*
X163779D03*
Y1232283D03*
X160039Y1236023D03*
X163779Y1224803D03*
X156299D03*
Y1228543D03*
X163779D03*
X160039Y1232283D03*
X152559Y1236023D03*
Y1232283D03*
X160039Y1254724D03*
X152559D03*
X163779Y1247243D03*
X160039Y1250984D03*
X163779Y1243503D03*
X156299Y1247243D03*
Y1243503D03*
X152559Y1250984D03*
X167519Y1254724D03*
Y1250984D03*
X152559D03*
Y1254724D03*
X160039D03*
X156299Y1243503D03*
X160039Y1239763D03*
X152559D03*
Y1243503D03*
X156299Y1250984D03*
X160039Y1247243D03*
Y1243503D03*
X152559Y1247243D03*
X156299Y1239763D03*
X163779Y1250984D03*
X156299Y1254724D03*
X163779D03*
Y1239763D03*
X156299Y1247243D03*
X163779Y1243503D03*
X160039Y1250984D03*
X163779Y1247243D03*
X152559Y1258465D03*
X160039D03*
X159552Y1348187D03*
X155192D03*
X159552Y1360099D03*
X155192D03*
X159552Y1372385D03*
Y1384297D03*
X155192D03*
Y1372385D03*
X159552Y1396583D03*
X155192D03*
X159552Y1408495D03*
X155192D03*
X182480Y1075196D03*
X174999D03*
X174998Y1071455D03*
X182479D03*
X178740Y1075196D03*
X171259D03*
X174999D03*
X182480D03*
X178740Y1086417D03*
Y1082677D03*
X182480Y1078936D03*
X174999D03*
X182480Y1093897D03*
X174999D03*
X178740Y1090157D03*
Y1078936D03*
X174999Y1086417D03*
Y1082677D03*
X171259Y1078936D03*
X174999Y1090157D03*
X171259D03*
X182480Y1086417D03*
Y1082677D03*
Y1090157D03*
X174999Y1078936D03*
X182480D03*
X178740Y1082677D03*
Y1086417D03*
X169389Y1084547D03*
Y1080807D03*
X182480Y1097637D03*
X178740Y1105117D03*
Y1101376D03*
X174999Y1097637D03*
Y1093897D03*
X182480D03*
X178740D03*
Y1097637D03*
X174999Y1101377D03*
X169389Y1106988D03*
X171259Y1093897D03*
Y1097637D03*
X174999Y1105117D03*
X182480Y1101377D03*
Y1105117D03*
Y1097637D03*
X174999D03*
X178740Y1101376D03*
Y1105117D03*
X169389Y1103247D03*
X174999Y1108858D03*
X178740D03*
X169389Y1121948D03*
X176870Y1114468D03*
Y1118208D03*
Y1121948D03*
X178740Y1112598D03*
X173129Y1110728D03*
X169389D03*
X180610Y1114468D03*
Y1118208D03*
Y1121948D03*
X182480Y1112598D03*
Y1108858D03*
X169389Y1136909D03*
X173129D03*
X180610D03*
X173129Y1133169D03*
X169389D03*
X176870Y1140649D03*
Y1125688D03*
Y1129429D03*
Y1133169D03*
Y1136909D03*
X173129Y1140649D03*
X169389D03*
X173129Y1129428D03*
X169389D03*
X180610Y1140649D03*
Y1125688D03*
Y1129429D03*
Y1133169D03*
X173129Y1136909D03*
X169389D03*
X180610Y1148129D03*
X173129Y1144389D03*
X169389D03*
X173129Y1148129D03*
Y1155610D03*
Y1151870D03*
X180610Y1155610D03*
Y1151870D03*
Y1144389D03*
X176870Y1151870D03*
Y1148129D03*
Y1144389D03*
X169389Y1151870D03*
Y1148129D03*
X176870Y1170570D03*
X173129Y1159350D03*
Y1166830D03*
Y1170570D03*
X180610Y1166830D03*
Y1159350D03*
Y1170570D03*
X176870Y1166830D03*
Y1159350D03*
X169389D03*
X171259Y1191141D03*
X174999D03*
X180610Y1174310D03*
Y1181791D03*
X173129Y1174310D03*
Y1178051D03*
Y1181791D03*
X171259Y1187401D03*
X174999D03*
X180610Y1178051D03*
X167519Y1183661D03*
X178740Y1187401D03*
X182480D03*
X176870Y1185531D03*
X173129D03*
X167519Y1187401D03*
X176870Y1174310D03*
Y1178051D03*
Y1181791D03*
X174999Y1198621D03*
X171259D03*
Y1206102D03*
X174999D03*
X171259Y1202362D03*
X167519Y1198621D03*
X171259Y1194881D03*
X174999Y1202362D03*
Y1194881D03*
X167519Y1191141D03*
X178740D03*
Y1194881D03*
Y1198621D03*
Y1202362D03*
X182480Y1191141D03*
Y1198621D03*
Y1202362D03*
X174999Y1198621D03*
Y1191141D03*
X167519Y1194881D03*
X171259Y1198621D03*
Y1191141D03*
X167519Y1202362D03*
X174999Y1213582D03*
X171259D03*
Y1209842D03*
X174999Y1217322D03*
X171259Y1221062D03*
X174999D03*
X171259Y1217322D03*
X174999Y1209842D03*
X167519Y1213582D03*
Y1206102D03*
Y1221062D03*
X178740Y1206102D03*
Y1209842D03*
Y1213582D03*
Y1221062D03*
X182480D03*
X178740Y1217322D03*
X182480Y1206102D03*
Y1209842D03*
Y1213582D03*
Y1217322D03*
X167519Y1209842D03*
X171259Y1213582D03*
Y1206102D03*
X174999D03*
X167519Y1217322D03*
X174999Y1213582D03*
X182480Y1232283D03*
Y1236023D03*
X174999D03*
X178740Y1224803D03*
X171259Y1228543D03*
X174999Y1232283D03*
X171259Y1224803D03*
X178740Y1228543D03*
D03*
X171259Y1224803D03*
X182480Y1236023D03*
Y1232283D03*
X174999D03*
X171259Y1228543D03*
X178740Y1224803D03*
Y1232283D03*
Y1236023D03*
X174999Y1228543D03*
X171259Y1232283D03*
X174999Y1224803D03*
X171259Y1236023D03*
X182480Y1228543D03*
Y1224803D03*
X167519Y1228543D03*
Y1224803D03*
X174999Y1236023D03*
X167519Y1232283D03*
Y1236023D03*
X174999Y1254724D03*
X182480D03*
X178740Y1243503D03*
X171259D03*
X174999Y1250984D03*
X171259Y1247243D03*
X182480Y1250984D03*
X178740Y1247243D03*
X167519Y1254724D03*
X182480Y1239763D03*
Y1243503D03*
Y1247243D03*
X171259Y1250984D03*
X178740D03*
Y1239763D03*
X174999Y1243503D03*
Y1247243D03*
X178740Y1254724D03*
X171259D03*
X174999Y1239763D03*
X171259D03*
X167519D03*
Y1243503D03*
Y1247243D03*
Y1250984D03*
X178740Y1247243D03*
X182480Y1254724D03*
Y1250984D03*
X171259Y1247243D03*
X174999Y1250984D03*
X171259Y1243503D03*
X174999Y1254724D03*
X178740Y1243503D03*
X175000Y1258465D03*
X182480D03*
X167519D03*
X167432Y1348187D03*
X171792D03*
X179672D03*
X167432Y1360099D03*
X171792D03*
X179672D03*
X167432Y1384297D03*
Y1372385D03*
X171792Y1384297D03*
Y1372385D03*
X179672Y1384297D03*
Y1372385D03*
X171792Y1396583D03*
X179672D03*
X167432D03*
Y1408495D03*
X171792D03*
X179672D03*
X197440Y1075196D03*
X189960D03*
X197439Y1071455D03*
X189959D03*
X186220Y1075196D03*
X193700D03*
X189960D03*
X197440D03*
Y1078936D03*
X193700Y1082677D03*
Y1086417D03*
X189960Y1078936D03*
X186220Y1086417D03*
Y1082677D03*
X201181Y1086417D03*
Y1082677D03*
X197440Y1093897D03*
X189960D03*
X193700Y1090157D03*
X189960Y1086417D03*
Y1082677D03*
X193700Y1078936D03*
X186220D03*
X189960Y1090157D03*
X186220D03*
X197440Y1086417D03*
Y1082677D03*
Y1090157D03*
X186220Y1082677D03*
Y1086417D03*
X189960Y1078936D03*
X193700Y1086417D03*
Y1082677D03*
X197440Y1078936D03*
Y1097637D03*
X201181Y1105117D03*
Y1101376D03*
X186220D03*
X193700D03*
X186220Y1105117D03*
X189960Y1097637D03*
X193700Y1105117D03*
D03*
X197440Y1093897D03*
X189960Y1097637D03*
X186220Y1105117D03*
X197440Y1097637D03*
X193700Y1093897D03*
X189960Y1101377D03*
X186220Y1097637D03*
X189960Y1105117D03*
X186220Y1093897D03*
X193700Y1097637D03*
X197440Y1101377D03*
Y1105117D03*
X193700Y1101376D03*
X186220D03*
X189960Y1093897D03*
X195570Y1121948D03*
X191830Y1118208D03*
X188090D03*
X184350D03*
X191830Y1121948D03*
X188090D03*
X184350D03*
X195570Y1118208D03*
X186220Y1108858D03*
X189960D03*
X193700D03*
X197440D03*
X188090Y1114468D03*
X184350D03*
X191830D03*
X195570D03*
X191830Y1125688D03*
X188090D03*
X184350D03*
X188090Y1129429D03*
X184350D03*
X188090Y1133169D03*
X184350D03*
X188090Y1136909D03*
Y1140649D03*
X184350D03*
X195570Y1133169D03*
Y1129429D03*
Y1125688D03*
Y1136909D03*
X191830Y1140649D03*
Y1136909D03*
X195570Y1140649D03*
X184350Y1136909D03*
X191830Y1133169D03*
Y1129429D03*
X188090Y1144389D03*
Y1151870D03*
X191830Y1155610D03*
Y1148129D03*
X195570Y1151869D03*
Y1144389D03*
X191830D03*
Y1151869D03*
X195570Y1148129D03*
Y1155610D03*
X184350Y1144389D03*
X188090Y1155610D03*
X184350Y1151870D03*
X188090Y1148129D03*
Y1159350D03*
Y1170570D03*
X191830Y1166830D03*
X195570Y1159350D03*
Y1170570D03*
X191830Y1159350D03*
Y1170570D03*
X195570Y1166830D03*
X184350Y1159350D03*
Y1170570D03*
X188090Y1166830D03*
Y1185531D03*
Y1178051D03*
X195570Y1189271D03*
X191830Y1181791D03*
Y1174310D03*
X195570Y1185531D03*
Y1178051D03*
X191830Y1185531D03*
Y1178051D03*
X195570Y1181791D03*
Y1174310D03*
X184350Y1185531D03*
X188090Y1181791D03*
Y1174310D03*
X184350Y1178051D03*
X188090Y1193011D03*
Y1196751D03*
Y1200491D03*
Y1204232D03*
X191830D03*
Y1196751D03*
Y1200491D03*
X184350Y1193011D03*
Y1196751D03*
X195570Y1200491D03*
Y1196751D03*
Y1193011D03*
Y1204232D03*
X186220Y1198621D03*
X191830Y1193011D03*
X193700Y1209842D03*
X191830Y1207972D03*
X189960Y1209842D03*
X195570Y1207972D03*
X193700Y1213582D03*
X191830Y1219192D03*
X186220Y1221062D03*
X189960D03*
X193700D03*
X197440D03*
X186220Y1206102D03*
Y1209842D03*
Y1213582D03*
X197440Y1209842D03*
X195570Y1215452D03*
X197440Y1217322D03*
X186220D03*
X189960D03*
Y1213582D03*
X197440Y1232283D03*
Y1236023D03*
X201181Y1228543D03*
Y1224803D03*
X189960Y1232283D03*
X193700Y1224803D03*
X186220Y1228543D03*
X189960Y1236023D03*
X193700Y1228543D03*
X186220Y1224803D03*
X197440Y1236023D03*
X186220Y1224803D03*
X193700Y1228543D03*
X197440Y1232283D03*
Y1224803D03*
X193700Y1232283D03*
X189960Y1228543D03*
X186220Y1232283D03*
X189960Y1224803D03*
X193700Y1236023D03*
X186220D03*
X197440Y1228543D03*
X189960Y1236023D03*
X186220Y1228543D03*
X193700Y1224803D03*
X189960Y1232283D03*
Y1254724D03*
X197440D03*
X186220Y1243503D03*
Y1247243D03*
X189960Y1250984D03*
X193700Y1243503D03*
Y1247243D03*
X197440Y1250984D03*
X201181Y1247243D03*
Y1243503D03*
X197440Y1239763D03*
Y1247243D03*
Y1243503D03*
X193700Y1254724D03*
X186220D03*
X193700Y1239763D03*
X186220D03*
X189960D03*
X186220Y1250984D03*
X189960Y1247243D03*
X193700Y1250984D03*
X189960Y1243503D03*
X197440Y1254724D03*
Y1250984D03*
X193700Y1247243D03*
Y1243503D03*
X189960Y1254724D03*
Y1250984D03*
X186220Y1247243D03*
Y1243503D03*
X189960Y1258465D03*
X197441D03*
X184032Y1348187D03*
X191912D03*
X196272D03*
X184032Y1360099D03*
X196272D03*
X191912D03*
X184032Y1384297D03*
Y1372385D03*
X196272Y1384297D03*
Y1372385D03*
X191912Y1384297D03*
Y1372385D03*
X184032Y1396583D03*
X191912D03*
X196272D03*
X184032Y1408495D03*
X191912D03*
X196272D03*
X212401Y1075196D03*
X204921D03*
X201181D03*
X208661D03*
X204920Y1071455D03*
X212400D03*
X204921Y1075196D03*
X212401D03*
Y1078936D03*
X204921D03*
X208661Y1086417D03*
Y1082677D03*
X216141D03*
Y1086417D03*
X204921Y1093897D03*
X212401D03*
X208661Y1078936D03*
X204921Y1090157D03*
X212401Y1086417D03*
Y1082677D03*
Y1090157D03*
X208661D03*
X201181D03*
X204921Y1086417D03*
Y1082677D03*
X201181Y1078936D03*
X212401D03*
X208661Y1082677D03*
X201181D03*
Y1086417D03*
X208661D03*
X204921Y1078936D03*
X216141Y1105117D03*
Y1101376D03*
X208661Y1105117D03*
X212401Y1097637D03*
X208661Y1101376D03*
X204921Y1097637D03*
D03*
X208661Y1101376D03*
X212401Y1097637D03*
X204921Y1101377D03*
X208661Y1097637D03*
X201181D03*
X204921Y1105117D03*
X212401Y1101377D03*
Y1105117D03*
X201181Y1093897D03*
X208661D03*
Y1105117D03*
X212401Y1093897D03*
X201181Y1101376D03*
X204921Y1093897D03*
X201181Y1105117D03*
X199311Y1118208D03*
Y1121948D03*
X206791Y1118208D03*
X203051D03*
Y1121948D03*
X206791D03*
X210531Y1118208D03*
X214271Y1110728D03*
Y1114468D03*
X210531Y1121948D03*
X214271Y1118208D03*
Y1121948D03*
X201181Y1108858D03*
X204921D03*
X208661D03*
X212401D03*
X203051Y1114468D03*
X199311D03*
X206791D03*
X210531D03*
X199311Y1140649D03*
X203051D03*
X206791D03*
X199311Y1125688D03*
X203051D03*
X206791D03*
Y1133169D03*
X203051D03*
X199311D03*
X210531D03*
Y1140649D03*
X214271D03*
Y1125688D03*
X210531D03*
X214271Y1133169D03*
X206791Y1136909D03*
X203051D03*
X199311D03*
X214271D03*
X210531D03*
X199311Y1129429D03*
X206791D03*
X214271D03*
X210531D03*
X203051D03*
Y1148129D03*
X199311D03*
X206791D03*
X214271D03*
X210531D03*
X199311Y1155610D03*
X206791D03*
X214271D03*
X210531D03*
X203051D03*
X206791Y1144389D03*
X203051D03*
X199311D03*
X214271D03*
X210531D03*
X214271Y1151870D03*
X210531D03*
X206791D03*
X203051D03*
X199311D03*
X206791Y1166830D03*
X203051Y1159350D03*
X199311Y1166830D03*
X203051Y1170570D03*
X214271Y1166830D03*
X210531Y1159350D03*
Y1170570D03*
X214271D03*
X210531Y1166830D03*
X214271Y1159350D03*
X206791Y1170570D03*
X203051Y1166830D03*
X199311Y1170570D03*
X206791Y1159350D03*
X199311D03*
X206791Y1181791D03*
X203051D03*
X199311D03*
X206791Y1189271D03*
X203051D03*
X199311D03*
X214271Y1181791D03*
X210531D03*
X214271Y1189271D03*
X210531D03*
X199311Y1174310D03*
X206791D03*
X214271D03*
X203051D03*
X210531D03*
X203051Y1185531D03*
X199311D03*
X206791D03*
X214271D03*
X210531D03*
X206791Y1178051D03*
X203051D03*
X199311D03*
X214271D03*
X210531D03*
X206791Y1196751D03*
X203051D03*
X199311D03*
Y1204232D03*
X203051D03*
X206791D03*
X214271Y1196751D03*
X210531D03*
Y1204232D03*
X214271D03*
Y1193011D03*
X210531D03*
X199311D03*
X203051D03*
X206791D03*
X214271Y1200491D03*
X210531D03*
X199311D03*
X206791D03*
X203051D03*
X206791Y1207972D03*
X203051D03*
X199311D03*
X210531D03*
Y1211712D03*
X214271Y1207972D03*
X212401Y1221062D03*
X208661D03*
X204921D03*
X201181D03*
Y1213582D03*
X214271Y1211712D03*
X208661Y1213582D03*
X203051Y1215452D03*
X214271D03*
X201181Y1217322D03*
X208661D03*
X210531Y1215452D03*
X204921Y1213582D03*
X216141Y1228543D03*
Y1224803D03*
X204921Y1236023D03*
X208661Y1224803D03*
X212401Y1236023D03*
X208661Y1228543D03*
X212401Y1232283D03*
X204921D03*
D03*
X201181Y1224803D03*
X212401Y1232283D03*
X208661Y1228543D03*
X212401D03*
Y1224803D03*
X208661Y1232283D03*
X204921Y1228543D03*
X201181Y1232283D03*
X204921Y1224803D03*
X201181Y1236023D03*
X208661D03*
X212401D03*
X208661Y1224803D03*
X201181Y1228543D03*
X204921Y1236023D03*
Y1254724D03*
X212401D03*
Y1250984D03*
X208661Y1247243D03*
X204921Y1250984D03*
X208661Y1243503D03*
X216141D03*
Y1247243D03*
X208661Y1250984D03*
X201181Y1239763D03*
X212401D03*
Y1247243D03*
Y1243503D03*
X201181Y1254724D03*
X208661Y1239763D03*
X204921D03*
Y1243503D03*
X201181Y1250984D03*
X204921Y1247243D03*
X208661Y1254724D03*
Y1243503D03*
X204921Y1250984D03*
X208661Y1247243D03*
X212401Y1254724D03*
X201181Y1243503D03*
X212401Y1250984D03*
X201181Y1247243D03*
X204921Y1254724D03*
X212401Y1258465D03*
X204921D03*
X204152Y1348187D03*
Y1360099D03*
Y1384297D03*
Y1372385D03*
Y1396583D03*
Y1408495D03*
X213969Y1445013D03*
Y1453293D03*
Y1456013D03*
Y1464293D03*
X219881Y1075196D03*
X227362D03*
X219880Y1071455D03*
X227361D03*
X223622Y1075196D03*
X231102D03*
X216141D03*
X227362D03*
X219881D03*
X223622Y1086417D03*
X227362Y1078936D03*
X223622Y1082677D03*
X231102Y1086417D03*
Y1082677D03*
X219881Y1078936D03*
Y1093897D03*
X227362D03*
Y1086417D03*
Y1082677D03*
Y1090157D03*
X223622D03*
X219881Y1086417D03*
Y1082677D03*
Y1090157D03*
X223622Y1078936D03*
X231102Y1090157D03*
Y1078936D03*
X216141Y1090157D03*
Y1078936D03*
X219881D03*
X216141Y1086417D03*
X231102Y1082677D03*
Y1086417D03*
X223622Y1082677D03*
X227362Y1078936D03*
X216141Y1082677D03*
X223622Y1086417D03*
X231102Y1105117D03*
Y1101376D03*
X227362Y1097637D03*
X223621Y1105117D03*
Y1101376D03*
X219881Y1097637D03*
X216141Y1101376D03*
X231102D03*
X227362Y1093897D03*
X219881Y1097637D03*
X223621Y1101376D03*
Y1105117D03*
X223622Y1093897D03*
X231102D03*
Y1097637D03*
X227362Y1101377D03*
Y1105117D03*
X219881Y1101377D03*
Y1105117D03*
X223622Y1097637D03*
X216141D03*
Y1093897D03*
Y1105117D03*
X219881Y1093897D03*
X227362Y1097637D03*
X231102Y1105117D03*
X225492Y1118208D03*
Y1121948D03*
X218011Y1118208D03*
X221751D03*
X218011Y1121948D03*
X221751D03*
X229232D03*
Y1118208D03*
Y1114468D03*
X216141Y1108858D03*
X219881D03*
X223622D03*
X227362D03*
X231102D03*
X225492Y1114468D03*
X221752D03*
X218011D03*
X225492Y1133169D03*
Y1140649D03*
Y1125688D03*
X218011Y1140649D03*
X221751D03*
X218011Y1125688D03*
X221751D03*
Y1133169D03*
X218011D03*
X229330Y1132677D03*
X229232Y1140649D03*
Y1125688D03*
X225492Y1136909D03*
X221751D03*
X218011D03*
X229232D03*
Y1129429D03*
X218011D03*
X221751D03*
X225492D03*
Y1148129D03*
X221751D03*
X218011D03*
X229232D03*
X221751Y1155610D03*
X229232D03*
X218011D03*
X225492D03*
Y1144389D03*
X221751D03*
X218011D03*
X229232D03*
Y1151870D03*
X221752D03*
X218011D03*
X225492D03*
Y1170570D03*
Y1159350D03*
X218011Y1170570D03*
X221752Y1166830D03*
X218011Y1159350D03*
X229232Y1166830D03*
X225492D03*
X221751Y1170570D03*
X218011Y1166830D03*
X221751Y1159350D03*
X229232Y1170570D03*
Y1159350D03*
X225492Y1181791D03*
Y1189271D03*
X221751Y1181791D03*
X218011D03*
X221751Y1189271D03*
X218011D03*
X229232Y1181791D03*
Y1189271D03*
X221751Y1174310D03*
X229232D03*
X225492D03*
X218011D03*
X225492Y1185531D03*
X218011D03*
X221751D03*
X229232D03*
X225492Y1178051D03*
X221751D03*
X218011D03*
X229232D03*
X218011Y1204232D03*
X229232Y1196751D03*
Y1204232D03*
X225492Y1196751D03*
Y1204232D03*
X221751D03*
Y1196751D03*
X218011D03*
Y1193011D03*
X221751D03*
X225492D03*
X229232D03*
X218011Y1200491D03*
X221751D03*
X225492D03*
X229232D03*
X225492Y1207972D03*
X218011Y1211712D03*
X221751Y1207972D03*
X218011D03*
X229232D03*
X231102Y1221062D03*
X227362D03*
X219881Y1217322D03*
X223622Y1221062D03*
X219881D03*
X216141D03*
X218011Y1215452D03*
X229232Y1211712D03*
Y1215452D03*
X225492Y1211712D03*
X221752D03*
Y1215452D03*
X231102Y1224803D03*
Y1228543D03*
X227362Y1236023D03*
X223622Y1228543D03*
X227362Y1232283D03*
X223622Y1224803D03*
X219881Y1236023D03*
Y1232283D03*
X231102Y1228543D03*
Y1224803D03*
X219881Y1232283D03*
Y1236023D03*
X227362Y1228543D03*
Y1224803D03*
X223622Y1232283D03*
X219881Y1228543D03*
Y1224803D03*
X223622Y1236023D03*
X231102Y1232283D03*
Y1236023D03*
X216141Y1232283D03*
Y1236023D03*
Y1224803D03*
X223622D03*
X227362Y1232283D03*
X223622Y1228543D03*
X216141D03*
X227362Y1236023D03*
Y1250984D03*
X219881D03*
X223622Y1247243D03*
Y1243503D03*
X231102Y1247243D03*
Y1243503D03*
X227362Y1254724D03*
X219881D03*
X223622D03*
X231102D03*
X223622Y1239763D03*
X231102D03*
X227362Y1243503D03*
Y1247243D03*
X219881Y1239763D03*
X223622Y1250984D03*
X219881Y1247243D03*
Y1243503D03*
X231102Y1250984D03*
X227362Y1239763D03*
X216141Y1250984D03*
Y1254724D03*
Y1239763D03*
X231102Y1243503D03*
Y1247243D03*
X223622Y1243503D03*
X216141Y1247243D03*
X223622D03*
X216141Y1243503D03*
X219881Y1250984D03*
Y1254724D03*
X227362D03*
Y1250984D03*
X219882Y1258465D03*
X227363D03*
X227249Y1445013D03*
Y1464293D03*
Y1456013D03*
Y1453293D03*
X249802Y1075196D03*
X242321D03*
X234841Y1075195D03*
X246062Y1075196D03*
X234841Y1071454D03*
X242321Y1071455D03*
X238582Y1075196D03*
X234841Y1075195D03*
X242321Y1075196D03*
X238581Y1086416D03*
X234841Y1078935D03*
X238581Y1082676D03*
X242321Y1078936D03*
X246061Y1086417D03*
Y1082677D03*
X249802Y1078936D03*
Y1093897D03*
X242321D03*
X234841D03*
X234842Y1090157D03*
X246062D03*
Y1078936D03*
X238582D03*
Y1090157D03*
X242322Y1082677D03*
Y1086417D03*
X234842Y1082677D03*
Y1086417D03*
X242322Y1090157D03*
X242321Y1078936D03*
X246061Y1082677D03*
X238581Y1082676D03*
X234841Y1078935D03*
X246061Y1086417D03*
X238581Y1086416D03*
X246062Y1101376D03*
Y1105117D03*
X249802Y1097637D03*
X238582Y1105117D03*
Y1101376D03*
X234841Y1097637D03*
X242321D03*
X246062D03*
Y1093897D03*
X242322Y1105117D03*
X234842Y1101377D03*
X238582Y1097637D03*
Y1093897D03*
X242322Y1101377D03*
X234842Y1105117D03*
X234841Y1093897D03*
X246062Y1105117D03*
X242321Y1097637D03*
X234841D03*
X238582Y1101376D03*
X246062D03*
X238582Y1105117D03*
X242321Y1093897D03*
X236712Y1121948D03*
X240452D03*
X244192D03*
X234842Y1108858D03*
X238582D03*
X242322D03*
X246062D03*
X240452Y1114468D03*
X244192D03*
X236712Y1118208D03*
X244192D03*
X236712Y1114468D03*
X240452Y1118208D03*
X236712Y1133464D03*
X240452Y1133169D03*
X236712Y1140649D03*
X240452D03*
X236712Y1125688D03*
X240452D03*
X244192Y1133169D03*
Y1140649D03*
Y1125688D03*
X240452Y1136909D03*
X236712D03*
X244192D03*
Y1129429D03*
X240452D03*
X236712D03*
Y1148129D03*
X240452D03*
X244192D03*
X240452Y1155610D03*
X236712D03*
X244192D03*
X240452Y1151869D03*
X236712D03*
X244192D03*
X240452Y1144389D03*
X236712D03*
X244192D03*
X240452Y1166830D03*
X236712Y1170570D03*
Y1159350D03*
X244192Y1170570D03*
Y1159350D03*
X236712Y1166830D03*
X240452Y1170570D03*
Y1159350D03*
X244192Y1166830D03*
X240452Y1181791D03*
X236712D03*
Y1189271D03*
X240452D03*
X244192Y1181791D03*
Y1189271D03*
X240452Y1174310D03*
X236712D03*
X244192D03*
X240452Y1185531D03*
X236712D03*
X244192D03*
X240452Y1178051D03*
X236712D03*
X244192D03*
X240452Y1204232D03*
X236712D03*
Y1196751D03*
X240452D03*
X244192Y1204232D03*
Y1196751D03*
X240452Y1193011D03*
X236712D03*
X244192D03*
X236712Y1200491D03*
X244192D03*
X240452D03*
X246062Y1221062D03*
X240452Y1207972D03*
Y1211712D03*
X242322Y1221062D03*
X244192Y1211712D03*
Y1207972D03*
X236712D03*
X234842Y1221062D03*
X238582D03*
X244192Y1215452D03*
X240452D03*
X242322Y1217322D03*
X236712Y1211712D03*
Y1215452D03*
X238582Y1217322D03*
X249803Y1236023D03*
X246062Y1224803D03*
Y1228543D03*
X249803Y1232283D03*
X234842Y1236023D03*
Y1232283D03*
X242322D03*
Y1236023D03*
X238582Y1228543D03*
Y1224803D03*
D03*
Y1228543D03*
X242322Y1236023D03*
Y1232283D03*
X246062Y1228543D03*
X234842Y1232283D03*
X246062Y1224803D03*
Y1232283D03*
Y1236023D03*
X238582Y1232283D03*
X234842Y1228543D03*
Y1224803D03*
X238582Y1236023D03*
X242322Y1228543D03*
Y1224803D03*
X234842Y1236023D03*
X238582Y1243503D03*
X234842Y1250984D03*
X242322D03*
X238582Y1247243D03*
X242322Y1254724D03*
X234842D03*
X246062Y1247243D03*
Y1243503D03*
X249803Y1254724D03*
Y1250984D03*
X246062Y1254724D03*
Y1239763D03*
X238582Y1254724D03*
Y1239763D03*
X234842D03*
X238582Y1250984D03*
X234842Y1243503D03*
Y1247243D03*
X242322Y1243503D03*
Y1239763D03*
Y1247243D03*
X246062Y1250984D03*
X238582Y1247243D03*
X246062Y1243503D03*
X242322Y1250984D03*
X234842D03*
X246062Y1247243D03*
X234842Y1254724D03*
X238582Y1243503D03*
X242322Y1254724D03*
X234842Y1258465D03*
X242322D03*
X239383Y1348187D03*
X247263D03*
Y1360099D03*
X239383D03*
X247263Y1384297D03*
Y1372385D03*
X239383Y1384297D03*
Y1372385D03*
X264762Y1075196D03*
X257282D03*
X253543D03*
X261023D03*
X249802Y1071455D03*
X257282D03*
X249802Y1075196D03*
X257282D03*
X261022Y1082677D03*
X253542Y1086416D03*
X257282Y1078936D03*
X253542Y1082676D03*
X261022Y1086417D03*
X264762Y1078936D03*
Y1093897D03*
X257282D03*
X253543Y1090157D03*
X249803Y1082677D03*
Y1090157D03*
Y1086417D03*
X253543Y1078936D03*
X257283Y1090157D03*
Y1082677D03*
Y1086417D03*
X261023Y1090157D03*
Y1078936D03*
X249802D03*
X261022Y1086417D03*
X253542Y1082676D03*
X257282Y1078936D03*
X253542Y1086416D03*
X261022Y1082677D03*
X264762Y1097637D03*
X261023Y1101376D03*
Y1105117D03*
X253543Y1101376D03*
Y1105117D03*
X257282Y1097637D03*
X249803Y1105117D03*
Y1101377D03*
X253543Y1093897D03*
X257283Y1101377D03*
X253543Y1097637D03*
X257283Y1105117D03*
X261023Y1093897D03*
Y1097637D03*
X249802D03*
X257282D03*
X249802Y1093897D03*
X253543Y1105117D03*
Y1101376D03*
X257282Y1093897D03*
X261023Y1105117D03*
Y1101376D03*
X255413Y1121948D03*
X251673D03*
X247933D03*
X262893D03*
X259153D03*
X249803Y1108858D03*
X253543D03*
X257283D03*
X261023D03*
X262893Y1118208D03*
X259153Y1114468D03*
X262893D03*
X255413Y1118208D03*
Y1114468D03*
X247933D03*
X259153Y1118208D03*
X251673Y1114468D03*
X247933Y1118208D03*
X251673D03*
X247933Y1133169D03*
X251673D03*
X255413D03*
X247933Y1140649D03*
X251673D03*
X255413D03*
X247933Y1125688D03*
X251673D03*
X255413D03*
X259153Y1133169D03*
X262893D03*
Y1140649D03*
X259153Y1125688D03*
X262893D03*
X259153Y1140649D03*
X255413Y1136909D03*
X251673D03*
X247933D03*
X259153D03*
X262893D03*
X247933Y1129429D03*
X259153D03*
X262893D03*
X255413D03*
X251673D03*
X259153Y1148129D03*
X262893D03*
Y1155610D03*
X247933Y1148129D03*
X251673D03*
X255413D03*
X247933Y1155610D03*
X255413D03*
X251673D03*
X259153D03*
X251673Y1144389D03*
X247933D03*
X255413D03*
X259153Y1151869D03*
X262893D03*
X247933D03*
X255413D03*
X251673D03*
X262893Y1144389D03*
X259153D03*
X262893Y1166830D03*
X251673Y1170570D03*
X255413Y1166830D03*
X247933D03*
X251673Y1159350D03*
X259153D03*
Y1170570D03*
X251673Y1166830D03*
X255413Y1170570D03*
X247933D03*
X255413Y1159350D03*
X247933D03*
X259153Y1166830D03*
X262893Y1170570D03*
Y1159350D03*
X247933Y1181791D03*
X251673D03*
X255413D03*
X247933Y1189271D03*
X251673D03*
X255413D03*
X262893D03*
Y1174310D03*
X259153Y1181791D03*
X262893D03*
X259153Y1189271D03*
X255413Y1174310D03*
X247933D03*
X251673D03*
X259153D03*
X247933Y1185531D03*
X255413D03*
X251673D03*
X259153D03*
X262893D03*
X251673Y1178051D03*
X247933D03*
X255413D03*
X259153D03*
X262893D03*
X247933Y1204232D03*
X255413D03*
X251673D03*
X247933Y1196751D03*
X251673D03*
X255413D03*
X259153Y1204232D03*
X262893D03*
X259153Y1196751D03*
X262893D03*
X251673Y1193011D03*
X255413D03*
X247933D03*
X262893D03*
X259153D03*
Y1200491D03*
X262893D03*
X251673D03*
X247933D03*
X255413D03*
X247933Y1207972D03*
X251673D03*
X255413Y1211712D03*
Y1207972D03*
X249803Y1221062D03*
X253543D03*
X262893Y1207972D03*
X259153D03*
X262893Y1211712D03*
X259153D03*
X261023Y1221062D03*
X257283D03*
X255413Y1215452D03*
X262893D03*
X247932Y1215451D03*
X259153Y1215452D03*
X251673D03*
X247932Y1211711D03*
X251673D03*
X264763Y1232283D03*
Y1236023D03*
X253543Y1224803D03*
X261023Y1228543D03*
X257283Y1236023D03*
Y1232283D03*
X253543Y1228543D03*
X261023Y1224803D03*
D03*
X253543Y1228543D03*
X249803Y1232283D03*
X257283D03*
Y1236023D03*
X249803Y1228543D03*
X257283D03*
X249803Y1224803D03*
X253543Y1236023D03*
X257283Y1224803D03*
X261023Y1236023D03*
X253543Y1232283D03*
X261023D03*
Y1228543D03*
X253543Y1224803D03*
X249803Y1236023D03*
X257283Y1254724D03*
X253543Y1243503D03*
Y1247243D03*
X257283Y1250984D03*
X261023Y1247243D03*
Y1243503D03*
X264763Y1254724D03*
Y1250984D03*
X249803Y1243503D03*
X253543Y1250984D03*
Y1254724D03*
X249803Y1247243D03*
X253543Y1239763D03*
X249803D03*
X257283Y1243503D03*
Y1247243D03*
X261023Y1250984D03*
Y1239763D03*
Y1254724D03*
X257283Y1239763D03*
X261023Y1243503D03*
X249803Y1250984D03*
X261023Y1247243D03*
X257283Y1250984D03*
X253543Y1247243D03*
X257283Y1254724D03*
X249803D03*
X253543Y1243503D03*
X249803Y1258465D03*
X257283D03*
X263863Y1348187D03*
X259503D03*
X251623D03*
X263863Y1360099D03*
X259503D03*
X251623D03*
X263863Y1384297D03*
Y1372385D03*
X259503Y1384297D03*
Y1372385D03*
X251623D03*
Y1384297D03*
X263863Y1396583D03*
X259503D03*
X251623D03*
X263863Y1408495D03*
X259503D03*
X251623D03*
X279723Y1075196D03*
X272243D03*
X279723Y1071455D03*
X264762D03*
X272243D03*
X268503Y1075196D03*
X275984D03*
X279723D03*
X264762D03*
X272243D03*
X268502Y1086416D03*
X272243Y1078936D03*
X268502Y1082676D03*
X275982Y1086417D03*
Y1082677D03*
X279723Y1078936D03*
Y1093897D03*
X272243D03*
X279724Y1082677D03*
Y1086417D03*
Y1090157D03*
X275984Y1078936D03*
X272244Y1082677D03*
X275984Y1090157D03*
X272244Y1086417D03*
X264763Y1082677D03*
X268503Y1078936D03*
Y1090157D03*
X264763Y1086417D03*
X272244Y1090157D03*
X264763D03*
X275982Y1082677D03*
Y1086417D03*
X268502Y1082676D03*
X272243Y1078936D03*
X268502Y1086416D03*
X279723Y1078936D03*
X264762D03*
X279723Y1097637D03*
X275984Y1101376D03*
X268503D03*
X275984Y1105117D03*
X272243Y1097637D03*
X268503Y1105117D03*
Y1093897D03*
Y1097637D03*
X272244Y1101377D03*
Y1105117D03*
X279724Y1101377D03*
X275984Y1097637D03*
X279724Y1105117D03*
X275984Y1093897D03*
X264763Y1101377D03*
Y1105117D03*
X264762Y1097637D03*
X268503Y1105117D03*
X272243Y1097637D03*
X275984Y1105117D03*
X279723Y1093897D03*
X272243D03*
X279723Y1097637D03*
X268503Y1101376D03*
X275984D03*
X264762Y1093897D03*
X274114Y1118208D03*
Y1121948D03*
X270373Y1118208D03*
X266633Y1121948D03*
X270373D03*
X277854Y1118208D03*
Y1121948D03*
X264763Y1108858D03*
X268503D03*
X272244D03*
X275984D03*
X279724D03*
X270373Y1114468D03*
X274114D03*
X277854D03*
Y1129429D03*
X274114Y1125688D03*
X270373Y1136909D03*
X266633Y1133169D03*
X270373D03*
X266633Y1140649D03*
X270373Y1125688D03*
Y1129429D03*
X266633Y1125688D03*
X270373Y1140649D03*
X277854Y1136909D03*
Y1133169D03*
Y1140649D03*
Y1125688D03*
X266633Y1136909D03*
Y1129429D03*
X274114D03*
Y1140649D03*
Y1136909D03*
Y1155610D03*
Y1151869D03*
Y1148129D03*
X266633D03*
X270373Y1144389D03*
Y1148129D03*
Y1151869D03*
X277854Y1144389D03*
Y1148129D03*
Y1151870D03*
X270373Y1155610D03*
X266633D03*
X277854D03*
X266633Y1151869D03*
Y1144389D03*
X274114D03*
Y1166830D03*
Y1159350D03*
Y1170570D03*
X277854Y1159350D03*
Y1166830D03*
Y1170570D03*
X266633D03*
X270373D03*
X266633Y1159350D03*
X270373D03*
Y1166830D03*
X266633D03*
Y1181791D03*
X270373Y1189271D03*
X277854Y1178051D03*
Y1189271D03*
Y1185531D03*
X270373Y1174310D03*
X277854Y1181791D03*
X274114D03*
Y1174310D03*
X266633Y1189271D03*
X270373Y1178051D03*
Y1185531D03*
X266633Y1174310D03*
X277854D03*
X266633Y1185531D03*
Y1178051D03*
X270373Y1181791D03*
X274114Y1185531D03*
Y1189271D03*
Y1178051D03*
Y1204232D03*
Y1196751D03*
X270393Y1196732D03*
X270373Y1204232D03*
X266633D03*
X270373Y1200491D03*
X266633Y1196751D03*
X270373Y1193011D03*
X277854D03*
X266633D03*
Y1200491D03*
X274114D03*
Y1193011D03*
X277854Y1204232D03*
Y1196751D03*
Y1200491D03*
X274114Y1207972D03*
X270373Y1211712D03*
X266633Y1207972D03*
Y1211712D03*
X264763Y1221062D03*
X270373Y1207972D03*
X277854Y1211712D03*
X279724Y1221062D03*
X275984D03*
X272244D03*
X268503D03*
X274114Y1215452D03*
X277854D03*
X266633D03*
X274114Y1211712D03*
X277854Y1207972D03*
X279724Y1236023D03*
Y1232283D03*
X272244D03*
X275984Y1228543D03*
X272244Y1236023D03*
X275984Y1224803D03*
X268503D03*
Y1228543D03*
X264763Y1232283D03*
X268503Y1224803D03*
X275984D03*
X272244Y1236023D03*
X279724Y1232283D03*
Y1236023D03*
X275984Y1228543D03*
X272244Y1232283D03*
X279724Y1224803D03*
X272244D03*
X268503Y1236023D03*
Y1232283D03*
X272244Y1228543D03*
X264763Y1224803D03*
X275984Y1232283D03*
Y1236023D03*
X264763Y1228543D03*
X279724D03*
X268503D03*
X264763Y1236023D03*
X272244Y1254724D03*
X275984Y1247243D03*
Y1243503D03*
X272244Y1250984D03*
X268503Y1247243D03*
Y1243503D03*
X279724Y1254724D03*
Y1250984D03*
X264763Y1254724D03*
Y1250984D03*
X268503Y1243503D03*
Y1247243D03*
X272244Y1254724D03*
Y1250984D03*
X275984Y1243503D03*
Y1247243D03*
X279724Y1250984D03*
Y1239763D03*
Y1247243D03*
X268503Y1239763D03*
X275984D03*
X272244Y1243503D03*
Y1247243D03*
X264763Y1239763D03*
Y1247243D03*
X268503Y1250984D03*
X264763Y1243503D03*
X272244Y1239763D03*
X275984Y1250984D03*
X279724Y1243503D03*
X268503Y1254724D03*
X275984D03*
X279724D03*
Y1258465D03*
X264763D03*
X272244D03*
X276103Y1348187D03*
X271743D03*
X276103Y1360099D03*
X271743D03*
X276103Y1384297D03*
Y1372385D03*
X271743Y1384297D03*
Y1372385D03*
X276103Y1396583D03*
X271743D03*
Y1408495D03*
X276103D03*
X294684Y1075196D03*
X287203D03*
X294684Y1071455D03*
X290944Y1075196D03*
X287203Y1071455D03*
X283464Y1075196D03*
X287203D03*
X294684D03*
X283463Y1086416D03*
Y1082676D03*
X290943Y1082677D03*
X287203Y1078936D03*
X290943Y1086417D03*
X294684Y1078936D03*
X298424Y1082676D03*
Y1086416D03*
X294684Y1093897D03*
X287203D03*
X294684Y1082677D03*
Y1090157D03*
X294685Y1086417D03*
X287204Y1090157D03*
X290944Y1078936D03*
X287204Y1082677D03*
Y1086417D03*
X283464Y1078936D03*
Y1090157D03*
X290943D03*
Y1086417D03*
X287203Y1078936D03*
X290943Y1082677D03*
X283463Y1082676D03*
Y1086416D03*
X294684Y1078936D03*
Y1097637D03*
X298425Y1101376D03*
Y1105117D03*
X287203Y1097637D03*
X290944Y1105117D03*
Y1101376D03*
X283464Y1105117D03*
Y1101376D03*
X290944Y1093897D03*
X283464D03*
X287204Y1101377D03*
X283464Y1097637D03*
X287204Y1105117D03*
X290944Y1097637D03*
X294684Y1101377D03*
X294685Y1105117D03*
X283464Y1101376D03*
X294684Y1093897D03*
X287203D03*
X294684Y1097637D03*
X283464Y1105117D03*
X290944Y1101376D03*
Y1105117D03*
X287203Y1097637D03*
X294684Y1116338D03*
Y1123818D03*
X298425Y1116338D03*
Y1123818D03*
X294684Y1120078D03*
Y1112598D03*
X283464Y1108858D03*
X287204D03*
X290944D03*
X294685D03*
X290944Y1112598D03*
Y1116338D03*
Y1120078D03*
Y1123818D03*
X294684D03*
Y1116338D03*
X285334Y1118208D03*
X281594D03*
X285334Y1114468D03*
X281594D03*
X294684Y1131299D03*
X298425D03*
X294685Y1127558D03*
Y1135039D03*
X281594Y1140649D03*
Y1136909D03*
X290944Y1127558D03*
Y1131299D03*
Y1135039D03*
Y1138779D03*
X294684Y1131299D03*
X289074Y1140649D03*
X285334D03*
Y1136909D03*
X292815Y1140649D03*
X281594Y1148129D03*
Y1155610D03*
Y1151869D03*
X285334D03*
X289074D03*
Y1155610D03*
Y1144389D03*
X292814Y1151869D03*
Y1144389D03*
X285334Y1155610D03*
X281594Y1144389D03*
X285334Y1148129D03*
Y1144389D03*
X289074Y1148129D03*
X292815D03*
Y1155610D03*
X281594Y1159350D03*
X289074Y1166830D03*
Y1170570D03*
Y1159350D03*
X281594Y1170570D03*
Y1166830D03*
X292814Y1159350D03*
Y1166830D03*
X285334Y1170570D03*
Y1166830D03*
Y1159350D03*
X292815Y1170570D03*
X292814Y1181791D03*
X285334Y1185531D03*
X289074Y1174310D03*
Y1178051D03*
Y1185531D03*
X281594Y1189271D03*
Y1185531D03*
X285334Y1181791D03*
X281594Y1178051D03*
Y1174310D03*
X292814D03*
Y1189271D03*
X285334Y1174310D03*
X289074Y1189271D03*
X285334D03*
X281594Y1181791D03*
X285334Y1178051D03*
X289074Y1181791D03*
X294685Y1198621D03*
X298425D03*
X294685Y1206102D03*
X298425D03*
X294685Y1194881D03*
Y1202362D03*
X281594Y1196751D03*
Y1204232D03*
X290944Y1191141D03*
X281594Y1193011D03*
X285334D03*
X290944Y1194881D03*
Y1198621D03*
Y1202362D03*
X294685Y1198621D03*
X285334Y1196751D03*
Y1204232D03*
X281594Y1200491D03*
X285334D03*
X294685Y1213582D03*
X298425D03*
X294685Y1209842D03*
Y1221062D03*
Y1217322D03*
X290944Y1221062D03*
X287204D03*
X283464D03*
X290944Y1206102D03*
Y1209842D03*
Y1213582D03*
Y1217322D03*
X294685Y1213582D03*
Y1206102D03*
X285334Y1207972D03*
Y1215452D03*
Y1211712D03*
X281594Y1215452D03*
Y1207972D03*
X298425Y1228543D03*
X294685Y1232283D03*
X298425Y1224803D03*
X294685Y1236023D03*
X290944Y1228543D03*
Y1224803D03*
X287204Y1236023D03*
X283464Y1228543D03*
Y1224803D03*
X287204Y1232283D03*
D03*
X283464Y1224803D03*
X294685Y1228543D03*
Y1224803D03*
X290944Y1232283D03*
Y1236023D03*
X283464Y1232283D03*
X287204Y1228543D03*
X283464Y1236023D03*
X287204Y1224803D03*
X283464Y1228543D03*
X287204Y1236023D03*
X294685D03*
X290944Y1224803D03*
X294685Y1232283D03*
X290944Y1228543D03*
X287204Y1254724D03*
X290944Y1243503D03*
Y1247243D03*
X287204Y1250984D03*
X283464Y1247243D03*
Y1243503D03*
X294685Y1254724D03*
Y1250984D03*
X298425Y1243503D03*
Y1247243D03*
X287204Y1254724D03*
X283464Y1243503D03*
X294685Y1247243D03*
Y1243503D03*
X283464Y1250984D03*
X287204Y1247243D03*
Y1243503D03*
Y1239763D03*
X294685D03*
X290944Y1250984D03*
X283464Y1254724D03*
X290944D03*
X283464Y1239763D03*
X290944D03*
X283464Y1247243D03*
X287204Y1250984D03*
X294685Y1254724D03*
Y1250984D03*
X290944Y1247243D03*
Y1243503D03*
X294685Y1258465D03*
X287204D03*
X288343Y1348187D03*
X296223D03*
X283983D03*
X288343Y1360099D03*
X296223D03*
X283983D03*
X288343Y1384297D03*
Y1372385D03*
X296223Y1384297D03*
Y1372385D03*
X283983D03*
Y1384297D03*
X288343Y1396583D03*
X296223D03*
X283983D03*
X288343Y1408495D03*
X296223D03*
X283983D03*
X309644Y1075196D03*
X302164D03*
X309645Y1071455D03*
X302165D03*
X298425Y1075196D03*
X305906D03*
X302164D03*
X309644D03*
Y1078936D03*
X305904Y1086417D03*
X302164Y1078936D03*
X305904Y1082677D03*
X313384Y1086417D03*
Y1082677D03*
X302164Y1093897D03*
X309644D03*
X298424Y1090157D03*
X302164Y1082677D03*
X298426Y1078936D03*
X302164Y1090157D03*
X302165Y1086417D03*
X305904Y1090157D03*
X309644Y1082677D03*
X305906Y1078936D03*
X309645Y1086417D03*
X309644Y1090157D03*
X305904Y1082677D03*
X302164Y1078936D03*
X305904Y1086417D03*
X309644Y1078936D03*
X298424Y1086416D03*
Y1082676D03*
X313385Y1105117D03*
Y1101377D03*
X305905Y1101376D03*
Y1105117D03*
X302164Y1097637D03*
X309644D03*
X302165Y1101377D03*
X298425Y1097637D03*
X302165Y1105117D03*
X309645D03*
Y1101377D03*
X305905Y1097637D03*
X298425Y1093897D03*
X305905D03*
X298425Y1105117D03*
Y1101376D03*
X309644Y1097637D03*
X302164D03*
X305905Y1105117D03*
X309644Y1093897D03*
X305905Y1101376D03*
X302164Y1093897D03*
X302165Y1112598D03*
X305905Y1120078D03*
Y1112598D03*
X302165Y1120078D03*
X313385Y1112598D03*
Y1120078D03*
X302165Y1123818D03*
X309645D03*
X305904Y1108857D03*
X309644Y1108858D03*
X302165Y1116338D03*
X298425Y1108858D03*
X302165D03*
X298425Y1112598D03*
X309645D03*
Y1116338D03*
Y1120078D03*
X305905Y1116338D03*
X298425Y1120078D03*
X305905Y1123818D03*
X302165Y1120078D03*
X305905Y1112598D03*
X298425Y1116338D03*
X305905Y1120078D03*
X302165Y1112598D03*
X298425Y1123818D03*
X313385Y1135039D03*
Y1127558D03*
X302165Y1127559D03*
Y1135039D03*
X305905D03*
Y1127559D03*
X309645Y1135039D03*
Y1127558D03*
Y1131299D03*
X311515Y1136909D03*
X307775Y1140649D03*
X304035D03*
X305905Y1131299D03*
X300295Y1140649D03*
X298425Y1135039D03*
X302165Y1131299D03*
X298425Y1127558D03*
X305905Y1127559D03*
Y1135039D03*
X302165D03*
Y1127559D03*
X298425Y1131299D03*
X311515Y1140649D03*
X296555Y1151869D03*
X304035Y1155610D03*
Y1148129D03*
X300295Y1155610D03*
Y1151869D03*
Y1148129D03*
Y1144389D03*
X296555D03*
X311515D03*
X307775Y1148129D03*
X311515Y1151869D03*
X307775Y1155610D03*
X304035Y1144389D03*
Y1151869D03*
X307775Y1144389D03*
Y1151869D03*
X296555Y1155610D03*
X311515Y1148129D03*
Y1155610D03*
X307775Y1159350D03*
X296555D03*
X300295D03*
X296555Y1166830D03*
X304035Y1170570D03*
X300295D03*
Y1166830D03*
X311515D03*
X307775Y1170570D03*
X311515Y1159350D03*
X304035Y1166830D03*
Y1159350D03*
X307775Y1166830D03*
X296555Y1170570D03*
X311515D03*
X300295Y1185531D03*
Y1181791D03*
Y1178051D03*
Y1174310D03*
X296555D03*
X298425Y1187401D03*
X304035Y1185531D03*
Y1178051D03*
X300295Y1189271D03*
X311515Y1174310D03*
X307775Y1178051D03*
X311515Y1181791D03*
X307775Y1185531D03*
X311515Y1189271D03*
X304035Y1174310D03*
Y1181791D03*
Y1189271D03*
X307775Y1174310D03*
Y1181791D03*
Y1189271D03*
X311515Y1178051D03*
Y1185531D03*
X313385Y1202362D03*
X302165D03*
X305905D03*
X304035Y1193011D03*
X302165Y1198621D03*
X298425Y1202362D03*
Y1194881D03*
X309645Y1198621D03*
X307775Y1193011D03*
X311515Y1196751D03*
X305905Y1198621D03*
X309645Y1202362D03*
X298425Y1198621D03*
X305905Y1202362D03*
X302165D03*
X311515Y1193011D03*
X302165Y1217322D03*
Y1209842D03*
X305905Y1217322D03*
Y1209842D03*
X313385Y1217322D03*
Y1209842D03*
X305905Y1206102D03*
X302165Y1213582D03*
X298425Y1209842D03*
X302165Y1206102D03*
X298425Y1221062D03*
X302165D03*
X298425Y1217322D03*
X309645D03*
Y1209842D03*
X305905Y1213582D03*
X309645D03*
Y1206102D03*
Y1221062D03*
X305905D03*
X298425Y1213582D03*
X305905Y1209842D03*
Y1217322D03*
X302165Y1209842D03*
X298425Y1206102D03*
X302165Y1217322D03*
X313385Y1228543D03*
Y1224803D03*
X305905Y1228543D03*
X309645Y1236023D03*
Y1232283D03*
X302165D03*
Y1236023D03*
X305905Y1224803D03*
X298425Y1236023D03*
Y1232283D03*
X302165Y1228543D03*
Y1224803D03*
X305905Y1232283D03*
X309645Y1228543D03*
Y1224803D03*
X305905Y1236023D03*
X302165Y1232283D03*
X309645D03*
X298425Y1224803D03*
Y1228543D03*
X309645Y1236023D03*
X305905Y1228543D03*
Y1224803D03*
X302165Y1236023D03*
Y1254724D03*
X309645D03*
X302165Y1250984D03*
X305905Y1247243D03*
Y1243503D03*
X309645Y1250984D03*
X313385Y1243503D03*
Y1247243D03*
X309645D03*
Y1243503D03*
X298425Y1250984D03*
X302165Y1247243D03*
Y1243503D03*
X305905Y1239763D03*
X302165D03*
X305905Y1250984D03*
X298425Y1254724D03*
X305905D03*
X298425Y1239763D03*
X309645D03*
Y1254724D03*
X298425Y1247243D03*
X309645Y1250984D03*
X298425Y1243503D03*
X305905D03*
Y1247243D03*
X302165Y1254724D03*
Y1250984D03*
X309645Y1258465D03*
X302165D03*
X308463Y1348187D03*
X300583D03*
X308463Y1360099D03*
X300583D03*
X308463Y1372385D03*
X300583D03*
Y1384297D03*
X308463D03*
Y1396583D03*
X300583D03*
X308463Y1408495D03*
X300583D03*
X317124Y1075196D03*
X317125Y1071455D03*
X320866Y1075196D03*
X313386D03*
X317124D03*
X320866Y1082676D03*
X317124Y1078936D03*
X324606Y1082676D03*
Y1090157D03*
X320866D03*
X317125Y1093897D03*
X320866Y1086417D03*
Y1078936D03*
X313384Y1090157D03*
X317125D03*
X317126Y1086417D03*
X317125Y1082677D03*
X313386Y1078936D03*
X324606Y1086417D03*
X328347Y1082677D03*
Y1090158D03*
X324606Y1078936D03*
X320866Y1090157D03*
X324606D03*
Y1082676D03*
X317124Y1078936D03*
X313384Y1082677D03*
Y1086417D03*
X320866Y1082676D03*
X317125Y1097637D03*
X324606Y1101377D03*
X320866D03*
Y1108858D03*
X324606D03*
X320866Y1093897D03*
X313385D03*
X324606D03*
Y1105117D03*
Y1097637D03*
X328347Y1101378D03*
X320866Y1105117D03*
Y1097637D03*
X317126Y1105117D03*
X317125Y1101377D03*
X313385Y1097637D03*
Y1101377D03*
X317125Y1093897D03*
X320866Y1101377D03*
X313385Y1105117D03*
X324606Y1101377D03*
X317125Y1097637D03*
X320866Y1123818D03*
Y1116338D03*
X317125Y1120078D03*
X324606Y1116338D03*
X317125Y1112598D03*
X324606Y1123818D03*
X317125Y1116338D03*
X324606Y1112598D03*
Y1120078D03*
X328347Y1116339D03*
Y1123819D03*
X320866Y1112598D03*
Y1120078D03*
X317125Y1123818D03*
X328347Y1108859D03*
X313385Y1108858D03*
X317125D03*
X313385Y1123818D03*
Y1116338D03*
Y1120078D03*
X324606Y1123818D03*
Y1108858D03*
X320866D03*
X317125Y1112598D03*
X324606Y1116338D03*
X313385Y1112598D03*
X317125Y1120078D03*
X320866Y1116338D03*
Y1123818D03*
Y1131299D03*
X317125Y1127558D03*
X324606Y1131299D03*
X317125Y1135039D03*
X328347Y1131300D03*
X320866Y1127558D03*
Y1135039D03*
X322736Y1140649D03*
X318996D03*
X315255Y1136909D03*
X318996D03*
X313384Y1131299D03*
X317125D03*
X324606Y1127558D03*
Y1135039D03*
X326476Y1140649D03*
X313385Y1127558D03*
X317125Y1135039D03*
X313385D03*
X324606Y1131299D03*
X317125Y1127558D03*
X320866Y1131299D03*
X322736Y1136909D03*
X326476D03*
X315255Y1140649D03*
X322736Y1155610D03*
X318996Y1144389D03*
X315255D03*
X318996Y1155610D03*
X315255Y1151869D03*
X318996D03*
Y1148129D03*
X326476D03*
Y1155610D03*
X322736Y1148129D03*
Y1144389D03*
Y1151870D03*
X326476Y1144389D03*
X315255Y1148129D03*
X326476Y1151870D03*
X315255Y1155610D03*
X322736Y1170570D03*
Y1166830D03*
X315255Y1159350D03*
X318996D03*
X315255Y1166830D03*
X318996Y1170570D03*
Y1166830D03*
X326476D03*
Y1170570D03*
X322736Y1159350D03*
X326476D03*
X315255Y1170570D03*
Y1181791D03*
Y1189271D03*
X318996D03*
Y1185531D03*
Y1181791D03*
Y1178051D03*
X315255Y1174310D03*
X318996D03*
X326476Y1178051D03*
Y1185531D03*
X322736Y1178051D03*
Y1185531D03*
Y1174310D03*
Y1181791D03*
Y1189271D03*
X326476Y1174310D03*
X315255Y1178051D03*
X326476Y1181791D03*
X315255Y1185531D03*
X326476Y1189271D03*
X317125Y1202362D03*
X324606Y1198621D03*
X320866D03*
X324606Y1206102D03*
X320866D03*
X328347Y1198621D03*
X322736Y1193011D03*
X320866Y1202362D03*
X318996Y1193011D03*
X313385Y1198621D03*
X317125D03*
X326416Y1193011D03*
X324606Y1202362D03*
X320866Y1198621D03*
X313385Y1202362D03*
X324606Y1198621D03*
X317125Y1202362D03*
X315255Y1193011D03*
X324606Y1213582D03*
X317125Y1209842D03*
Y1217322D03*
X324606Y1221062D03*
X320866Y1213582D03*
Y1221062D03*
X328347Y1206102D03*
X317125D03*
X313385D03*
X328347Y1221062D03*
Y1213582D03*
X320866Y1217322D03*
Y1209842D03*
X313385Y1221062D03*
X317125D03*
X313385Y1213582D03*
X317125D03*
X324606Y1209842D03*
Y1217322D03*
X317125D03*
Y1209842D03*
X324606Y1213582D03*
X320866Y1221062D03*
X313385Y1209842D03*
X320866Y1206102D03*
Y1213582D03*
X324606Y1221062D03*
Y1206102D03*
X313385Y1217322D03*
X320866Y1228543D03*
X317125Y1232283D03*
X324606Y1228543D03*
X317125Y1236023D03*
X320866Y1239763D03*
X324606D03*
X320866Y1236023D03*
Y1224803D03*
Y1232283D03*
X313385D03*
X317125Y1228543D03*
Y1224803D03*
X313385Y1236023D03*
X324606Y1232283D03*
Y1236023D03*
Y1224803D03*
X328347Y1228543D03*
X317125Y1236023D03*
X313385Y1224803D03*
X324606Y1228543D03*
X317125Y1232283D03*
X313385Y1228543D03*
X320866D03*
X317125Y1254724D03*
X324606Y1247243D03*
X317125Y1250984D03*
X320866Y1247243D03*
X328347Y1239762D03*
Y1247243D03*
X320866Y1250984D03*
Y1243503D03*
X313385Y1250984D03*
X317125Y1247243D03*
Y1243503D03*
X324606D03*
Y1250984D03*
X313385Y1254724D03*
X317125Y1239763D03*
X313385D03*
X320866Y1254724D03*
X317125D03*
X324606Y1239763D03*
X313385Y1247243D03*
X320866D03*
X317125Y1250984D03*
X320866Y1239763D03*
X313385Y1243503D03*
X324606Y1247243D03*
X317125Y1258465D03*
X320703Y1348187D03*
X312823D03*
X325063D03*
X320703Y1360099D03*
X312823D03*
X325063D03*
X320703Y1372385D03*
Y1384297D03*
X312823Y1372385D03*
Y1384297D03*
X325063Y1372385D03*
Y1384297D03*
Y1396583D03*
X320703D03*
X312823D03*
X320703Y1408495D03*
X312823D03*
X325063D03*
X337303Y1348187D03*
X332943D03*
Y1360099D03*
X337303D03*
X332943Y1384297D03*
Y1372385D03*
X337303D03*
Y1384297D03*
X332943Y1396583D03*
X337303D03*
X332943Y1408495D03*
X337303D03*
X349543Y1348187D03*
X357423D03*
X345183D03*
X349543Y1360099D03*
X357423D03*
X345183D03*
Y1372385D03*
Y1384297D03*
X349543D03*
Y1372385D03*
X357423D03*
Y1384297D03*
X345183Y1396583D03*
X349543D03*
X357423D03*
X345183Y1408495D03*
X349543D03*
X357423D03*
X369663Y1348187D03*
X361783D03*
X369663Y1360099D03*
X361783D03*
X369663Y1372385D03*
Y1384297D03*
X361783D03*
Y1372385D03*
X369663Y1396583D03*
X361783D03*
X369663Y1408495D03*
X361783D03*
X425023Y441086D03*
Y433999D03*
Y437543D03*
X422223Y441086D03*
Y433999D03*
Y437543D03*
X425023Y444629D03*
X422223D03*
X438162Y1348187D03*
Y1360099D03*
Y1384297D03*
Y1372385D03*
X450402Y1348187D03*
X458282D03*
X446042D03*
X450402Y1360099D03*
X458282D03*
X446042D03*
X458282Y1372385D03*
X446042D03*
X458282Y1384297D03*
X446042D03*
X450402D03*
Y1372385D03*
X458282Y1396583D03*
X450402D03*
X458282Y1408495D03*
X450402D03*
X462642Y1348187D03*
X474882D03*
X470522D03*
X462642Y1360099D03*
X474882D03*
X470522D03*
X462642Y1384297D03*
X470522D03*
X474882D03*
X462642Y1372385D03*
X470522D03*
X474882D03*
X470522Y1396583D03*
X474882D03*
X462642D03*
X470522Y1408495D03*
X474882D03*
X462642D03*
X482762Y1348187D03*
X487122D03*
X482762Y1360099D03*
X487122D03*
Y1372385D03*
Y1384297D03*
X482762D03*
Y1372385D03*
Y1396583D03*
X487122D03*
X482762Y1408495D03*
X487122D03*
X501750Y620661D03*
X505293D03*
X501750Y617861D03*
X505293D03*
X507242Y1348187D03*
X495002D03*
X499362D03*
X507242Y1360099D03*
X495002D03*
X499362D03*
Y1372385D03*
Y1384297D03*
X495002D03*
X507242D03*
X495002Y1372385D03*
X507242D03*
Y1396583D03*
X495002D03*
X499362D03*
X507242Y1408495D03*
X495002D03*
X499362D03*
X512380Y617861D03*
X508836Y620661D03*
Y617861D03*
X512380Y620661D03*
X519482Y1348187D03*
X511602D03*
X519482Y1360099D03*
X511602D03*
X519482Y1384297D03*
Y1372385D03*
X511602D03*
Y1384297D03*
X519482Y1396583D03*
X511602D03*
X519482Y1408495D03*
X511602D03*
X536082Y1348187D03*
X523842D03*
X531722D03*
X536082Y1360099D03*
X523842D03*
X531722D03*
Y1384297D03*
Y1372385D03*
X523842Y1384297D03*
Y1372385D03*
X536082Y1384297D03*
Y1372385D03*
X531722Y1396583D03*
X536082D03*
X523842D03*
X531722Y1408495D03*
X536082D03*
X523842D03*
X548322Y1348187D03*
X556202D03*
X543962D03*
X548322Y1360099D03*
X556202D03*
X543962D03*
Y1372385D03*
Y1384297D03*
X556202D03*
X548322D03*
X556202Y1372385D03*
X548322D03*
X556202Y1396583D03*
X543962D03*
X548322D03*
X556202Y1408495D03*
X543962D03*
X548322D03*
X568442Y1348187D03*
X560562D03*
X568442Y1360099D03*
X560562D03*
Y1384297D03*
X568442D03*
X560562Y1372385D03*
X568442D03*
Y1396583D03*
X560562D03*
X568442Y1408495D03*
X560562D03*
X600295Y1084547D03*
Y1092027D03*
X604035Y1077066D03*
Y1080806D03*
Y1084547D03*
Y1092027D03*
X600295Y1088287D03*
X604035D03*
Y1103247D03*
X600295D03*
Y1095767D03*
X604035D03*
X600295Y1099507D03*
X604035D03*
X600295Y1106988D03*
X604035D03*
X600295Y1110728D03*
Y1118208D03*
X604035Y1110728D03*
Y1118208D03*
Y1121948D03*
X600295D03*
Y1114468D03*
X604035D03*
X600295Y1125688D03*
Y1133169D03*
Y1140649D03*
X604035Y1125688D03*
Y1133169D03*
Y1140649D03*
X600295Y1136909D03*
X604035D03*
X600295Y1129429D03*
X604035D03*
X600295Y1144389D03*
Y1151870D03*
X604035Y1144389D03*
Y1151870D03*
Y1148129D03*
X600295D03*
Y1159350D03*
X604036Y1166830D03*
X604035Y1159350D03*
X597795Y1170570D03*
X604034D03*
X600294D03*
X605905Y1191141D03*
X602165D03*
X604034Y1174310D03*
X597795Y1178050D03*
X602165Y1183661D03*
Y1187401D03*
X604034Y1178051D03*
X600294D03*
X605905Y1198621D03*
X602165D03*
Y1206102D03*
X605905D03*
X602165Y1202362D03*
Y1194881D03*
X598424Y1198622D03*
Y1191142D03*
X602165Y1191141D03*
Y1198621D03*
Y1213582D03*
Y1221062D03*
X605905Y1213582D03*
Y1221062D03*
X602165Y1217322D03*
Y1209842D03*
X598424Y1221063D03*
Y1213583D03*
Y1206103D03*
X602165Y1221062D03*
Y1206102D03*
Y1213582D03*
X605905Y1228543D03*
X602165D03*
Y1239763D03*
X605905D03*
X602165Y1224803D03*
Y1236023D03*
Y1232283D03*
X598424Y1228542D03*
X602165Y1228543D03*
Y1247243D03*
X605905D03*
X602165Y1243503D03*
Y1250984D03*
X598423Y1239762D03*
Y1247242D03*
X602165Y1247243D03*
Y1239763D03*
X611516Y1073326D03*
X618996D03*
X615256D03*
X607776D03*
X618996Y1088287D03*
Y1092027D03*
X607775Y1077066D03*
X611516D03*
X615256Y1080807D03*
X607776D03*
X615256Y1084547D03*
X607776D03*
X615256Y1088287D03*
X611516D03*
X607776D03*
X611516Y1092027D03*
X618996Y1077066D03*
Y1084547D03*
Y1080807D03*
X615256Y1077066D03*
X611516Y1080807D03*
Y1084547D03*
X607776Y1092027D03*
X615256D03*
X611516Y1106988D03*
X607776D03*
X611516Y1095767D03*
X615256Y1099507D03*
X607776D03*
X615256Y1103247D03*
X607776D03*
X615256Y1106988D03*
X618996Y1095767D03*
Y1106988D03*
X607776Y1095767D03*
X615256D03*
X618996Y1103247D03*
X611516D03*
X618996Y1099507D03*
X611516D03*
X615256Y1110728D03*
Y1114468D03*
X611516D03*
X607776D03*
X615256Y1118208D03*
Y1121948D03*
X611516D03*
X607776D03*
X618996Y1114468D03*
Y1118208D03*
Y1121948D03*
X611516Y1118208D03*
X607776D03*
X611516Y1110728D03*
X618996D03*
X607776D03*
X615256Y1125688D03*
Y1129429D03*
X611516D03*
X607776D03*
Y1136909D03*
X615256Y1140649D03*
X611516D03*
X607776D03*
X618996D03*
Y1125688D03*
Y1129429D03*
Y1133169D03*
X611516Y1125688D03*
X607776D03*
Y1133169D03*
X618996Y1144389D03*
Y1148129D03*
Y1151870D03*
Y1155610D03*
X607776Y1144389D03*
X615256Y1151869D03*
X611516D03*
X607776Y1148129D03*
Y1151870D03*
X615256Y1155610D03*
X611516D03*
X607776D03*
Y1159350D03*
X615256Y1166830D03*
X611516D03*
X607775D03*
X611516Y1170570D03*
X607775D03*
X618996Y1159350D03*
X613386Y1187401D03*
X609646D03*
X620866D03*
X618996Y1174310D03*
Y1178051D03*
X607775Y1174310D03*
Y1178051D03*
X611516Y1174310D03*
X615256D03*
X613386Y1183661D03*
X617126Y1187401D03*
Y1183661D03*
X613386Y1179921D03*
X620866Y1183661D03*
X609646D03*
X605905D03*
Y1187401D03*
X613386D03*
X609646D03*
X620866D03*
X615256Y1178051D03*
X611516D03*
X620866Y1194881D03*
Y1202362D03*
X609646Y1194881D03*
X613386D03*
X609646Y1202362D03*
X613386D03*
Y1198621D03*
X609646Y1191141D03*
X613386D03*
X617126Y1202362D03*
Y1194881D03*
Y1198621D03*
X620866D03*
X617126Y1191141D03*
X620866D03*
X605905Y1202362D03*
Y1194881D03*
X609646Y1198621D03*
X605905Y1191141D03*
X613386Y1194881D03*
X605905Y1198621D03*
X609646Y1194881D03*
Y1202362D03*
X613386D03*
X620866D03*
Y1194881D03*
Y1217322D03*
Y1209842D03*
X613386D03*
X609646D03*
Y1217322D03*
X613386D03*
Y1221062D03*
X609646D03*
Y1213582D03*
X613386D03*
X620866Y1206102D03*
X617126D03*
Y1213582D03*
Y1209842D03*
X620866Y1213582D03*
Y1221062D03*
X617126D03*
Y1217322D03*
X613386Y1206102D03*
X605905Y1217322D03*
Y1209842D03*
X609646Y1206102D03*
X613386Y1217322D03*
X605905Y1221062D03*
X609646Y1217322D03*
Y1209842D03*
X605905Y1206102D03*
Y1213582D03*
X620866Y1209842D03*
X613386D03*
X620866Y1217322D03*
Y1224803D03*
Y1228543D03*
X613386Y1224803D03*
Y1228543D03*
X609646Y1232283D03*
Y1236023D03*
X617126D03*
Y1232283D03*
X605905Y1224803D03*
Y1232283D03*
Y1236023D03*
X620866D03*
Y1232283D03*
X617126Y1228543D03*
Y1224803D03*
X609646D03*
Y1228543D03*
X613386Y1232283D03*
Y1236023D03*
X605905Y1228543D03*
X620866D03*
Y1224803D03*
X609646Y1232283D03*
X617126Y1236023D03*
X613386Y1228543D03*
X617126Y1232283D03*
X609646Y1236023D03*
X613386Y1224803D03*
X620866Y1243503D03*
Y1247243D03*
X617126Y1250984D03*
Y1254724D03*
X609646D03*
Y1250984D03*
X613386Y1247243D03*
Y1243503D03*
X617126D03*
Y1239763D03*
X620866D03*
X613386D03*
X609646Y1243503D03*
Y1239763D03*
X620866Y1254724D03*
Y1250984D03*
X617126Y1247243D03*
X609646D03*
X613386Y1254724D03*
Y1250984D03*
X605905Y1243503D03*
Y1254724D03*
Y1250984D03*
Y1247243D03*
X617126Y1250984D03*
X620866Y1243503D03*
Y1247243D03*
X609646Y1254724D03*
X613386Y1247243D03*
X617126Y1254724D03*
X613386Y1243503D03*
X609646Y1250984D03*
X605905Y1239763D03*
X617126Y1258465D03*
X609646D03*
X639567Y1075196D03*
X632086D03*
X626476Y1073326D03*
X635827Y1075196D03*
X628346D03*
X632085Y1071455D03*
X632086Y1075196D03*
X622736Y1073326D03*
X632086Y1078936D03*
X635827Y1086417D03*
Y1082677D03*
X639567Y1078936D03*
Y1093897D03*
X632086D03*
X626476Y1077066D03*
Y1088287D03*
Y1092027D03*
X622736Y1080807D03*
Y1084547D03*
Y1088287D03*
X635827Y1090157D03*
X628346Y1078936D03*
Y1090157D03*
X635827Y1078936D03*
X632086Y1090157D03*
Y1082677D03*
Y1086417D03*
Y1078936D03*
X635827Y1086417D03*
Y1082677D03*
X622736Y1077066D03*
X626476Y1084547D03*
X622736Y1092027D03*
X626476Y1080807D03*
X639567Y1097637D03*
X635827Y1105117D03*
Y1101376D03*
X632086Y1097637D03*
D03*
X630216Y1099507D03*
X622736D03*
Y1103247D03*
X626476Y1106988D03*
X622736D03*
X626476Y1095767D03*
Y1099507D03*
X630216Y1103247D03*
X635827Y1093897D03*
X632086Y1101377D03*
Y1105117D03*
X628346Y1097637D03*
Y1093897D03*
X635827Y1097637D03*
Y1105117D03*
X632086Y1093897D03*
X635827Y1101376D03*
X622736Y1095767D03*
X626476Y1103247D03*
X633957Y1110728D03*
X630216D03*
X626476D03*
X622736Y1114468D03*
X630216Y1118208D03*
X626476D03*
Y1121948D03*
X633957Y1114468D03*
Y1118208D03*
Y1121948D03*
X635827Y1108858D03*
X632086D03*
X622736Y1118208D03*
X626476Y1114468D03*
X622736Y1110728D03*
X630216Y1114468D03*
X633957Y1140649D03*
Y1125688D03*
Y1129429D03*
Y1133169D03*
Y1136909D03*
X630216Y1140649D03*
X626476D03*
X622736D03*
X630216Y1129428D03*
X626476D03*
X622736Y1129429D03*
X630216Y1136909D03*
X626476D03*
X630216Y1144389D03*
X626476D03*
X630216Y1148129D03*
Y1155610D03*
Y1151870D03*
X633957D03*
Y1148129D03*
Y1144389D03*
X626476Y1148129D03*
X622736Y1144389D03*
Y1148129D03*
X626476Y1151870D03*
X622736Y1155610D03*
Y1166830D03*
Y1170570D03*
X630216Y1159350D03*
Y1166830D03*
Y1170570D03*
X633957D03*
Y1166830D03*
Y1159350D03*
X626476D03*
X624606Y1187401D03*
X632086Y1191141D03*
X628346D03*
X622736Y1174310D03*
X633957Y1185531D03*
X628346Y1183661D03*
X630216Y1174310D03*
Y1178051D03*
Y1181791D03*
X622736Y1178050D03*
X632086Y1187401D03*
X628346D03*
X624606Y1183661D03*
X635827Y1187401D03*
X624606D03*
X633957Y1174310D03*
Y1178051D03*
Y1181791D03*
X624606Y1194881D03*
Y1202362D03*
X628346Y1198621D03*
X632086D03*
X628346Y1206102D03*
X632086D03*
X624606Y1191141D03*
X632086Y1202362D03*
X628346D03*
X624606Y1198621D03*
X632086Y1194881D03*
X628346D03*
X635827Y1191141D03*
Y1194881D03*
Y1198621D03*
Y1202362D03*
X628346Y1191141D03*
X624606Y1194881D03*
X632086Y1191141D03*
X628346Y1198621D03*
X624606Y1202362D03*
X632086Y1198621D03*
X624606Y1217322D03*
Y1209842D03*
X628346Y1213582D03*
X632086D03*
X624606Y1206102D03*
Y1213582D03*
X632086Y1209842D03*
X628346D03*
Y1217322D03*
Y1221062D03*
X624606D03*
X632086D03*
Y1217322D03*
X635827Y1221062D03*
Y1206102D03*
Y1209842D03*
Y1213582D03*
Y1217322D03*
X628346Y1206102D03*
X632086D03*
X624606Y1217322D03*
X628346Y1213582D03*
X632086D03*
X624606Y1209842D03*
X635827Y1224803D03*
Y1228543D03*
X639567Y1232283D03*
Y1236023D03*
X624606Y1232283D03*
Y1236023D03*
X628346Y1224803D03*
Y1228543D03*
X632086Y1232283D03*
Y1236023D03*
Y1228543D03*
Y1224803D03*
X624606D03*
Y1228543D03*
X628346Y1236023D03*
Y1232283D03*
X635827Y1236023D03*
Y1232283D03*
X628346Y1224803D03*
Y1228543D03*
X635827D03*
X632086Y1232283D03*
Y1236023D03*
X624606Y1232283D03*
Y1236023D03*
X635827Y1224803D03*
Y1243503D03*
Y1247243D03*
X632086Y1250984D03*
Y1254724D03*
X624606D03*
Y1250984D03*
X628346Y1247243D03*
Y1243503D03*
X639567Y1250984D03*
Y1254724D03*
X632086Y1247243D03*
Y1243503D03*
X635827Y1239763D03*
X632086D03*
X628346D03*
Y1250984D03*
X624606Y1243503D03*
Y1239763D03*
X635827Y1254724D03*
Y1250984D03*
X628346Y1254724D03*
X624606Y1247243D03*
Y1254724D03*
Y1250984D03*
X632086Y1254724D03*
X635827Y1243503D03*
X632086Y1250984D03*
X635827Y1247243D03*
X628346Y1243503D03*
Y1247243D03*
X632087Y1258465D03*
X624606D03*
X636288Y1372385D03*
Y1384297D03*
X631928Y1396583D03*
X636288D03*
X624048D03*
X631928Y1408495D03*
X636288D03*
X624048D03*
X654527Y1075196D03*
X647047D03*
X643307D03*
X650787D03*
X647046Y1071455D03*
X639566D03*
X639567Y1075196D03*
X647047D03*
X650787Y1086417D03*
X643307D03*
Y1082677D03*
X647047Y1078936D03*
X650787Y1082677D03*
X654527Y1078936D03*
Y1093897D03*
X647047D03*
X650787Y1078936D03*
X643307Y1090157D03*
X639567D03*
X647047Y1082677D03*
Y1086417D03*
X643307Y1078936D03*
X650787Y1090157D03*
X647047D03*
X639567Y1086417D03*
Y1082677D03*
X643307Y1086417D03*
Y1082677D03*
X647047Y1078936D03*
X639567D03*
X650787Y1082677D03*
Y1086417D03*
X654527Y1097637D03*
X650787Y1105117D03*
X643307D03*
Y1101376D03*
X647047Y1097637D03*
X650787Y1101376D03*
Y1105117D03*
X639567Y1101377D03*
Y1105117D03*
X647047D03*
Y1101377D03*
X650787Y1097637D03*
X643307D03*
Y1093897D03*
X650787D03*
X647047D03*
X639567Y1097637D03*
X643307Y1105117D03*
X647047Y1097637D03*
X639567Y1093897D03*
X643307Y1101376D03*
X650787D03*
X637697Y1114468D03*
X648917Y1118208D03*
X645177D03*
X641437D03*
X637697D03*
X648917Y1121948D03*
X645177D03*
X641437D03*
X637697D03*
Y1110728D03*
X652657Y1118208D03*
Y1121948D03*
X650787Y1108858D03*
X647047D03*
X643307D03*
X639567D03*
X645177Y1114468D03*
X641437D03*
X648917D03*
X652657D03*
X641437Y1133169D03*
X637697D03*
X645177Y1136909D03*
X637697D03*
X645177Y1140649D03*
X641437D03*
X652657Y1133169D03*
Y1129429D03*
Y1125688D03*
Y1136909D03*
X637697Y1140649D03*
X648917Y1125688D03*
X645177D03*
X641437D03*
X637697D03*
X645177Y1129429D03*
X641437D03*
X637697D03*
X645177Y1133169D03*
X648917Y1140649D03*
Y1136909D03*
X652657Y1140649D03*
X641437Y1136909D03*
X648917Y1129429D03*
Y1133169D03*
X637697Y1155610D03*
Y1151870D03*
X645177Y1144389D03*
X637697D03*
Y1148129D03*
X645177Y1151870D03*
X648917Y1155610D03*
Y1148129D03*
X652657Y1151869D03*
Y1144389D03*
Y1148129D03*
Y1155610D03*
X648917Y1144389D03*
Y1151869D03*
X641437Y1144389D03*
Y1151870D03*
X645177Y1155610D03*
Y1148129D03*
Y1170570D03*
X637697Y1166830D03*
X645177Y1159350D03*
X637697D03*
Y1170570D03*
X648917Y1166830D03*
X652657Y1159350D03*
Y1170570D03*
X648917Y1159350D03*
Y1170570D03*
X652657Y1166830D03*
X641437Y1170570D03*
X645177Y1166830D03*
X641437Y1159350D03*
X637697Y1189271D03*
X645177Y1185531D03*
X637697D03*
Y1178051D03*
Y1174310D03*
X645177Y1178051D03*
X637697Y1181791D03*
X652657Y1189271D03*
X648917Y1181791D03*
Y1174310D03*
X652657Y1185531D03*
Y1178051D03*
X648917Y1185531D03*
Y1178051D03*
X652657Y1181791D03*
Y1174310D03*
X641437Y1185531D03*
Y1178051D03*
X645177Y1181791D03*
Y1174310D03*
X652657Y1193011D03*
Y1204232D03*
X637697Y1193011D03*
X645177D03*
Y1196751D03*
Y1200491D03*
X641437D03*
Y1204232D03*
X645177D03*
X648917D03*
Y1196751D03*
Y1200491D03*
X641437Y1193011D03*
Y1196751D03*
X652657Y1200491D03*
Y1196751D03*
X648917Y1193011D03*
X652657Y1211712D03*
X648917Y1219192D03*
X641437D03*
Y1211712D03*
X645177D03*
X648917D03*
Y1207972D03*
X645177D03*
X641437D03*
X652657D03*
X639567Y1221062D03*
X647047D03*
X643307D03*
X650787D03*
X652657Y1215452D03*
Y1219192D03*
X641437Y1215452D03*
X648917D03*
X645177D03*
X654527Y1232283D03*
Y1236023D03*
X643307Y1224803D03*
Y1228543D03*
X647047Y1236023D03*
Y1232283D03*
X650787Y1228543D03*
Y1224803D03*
X639567D03*
Y1228543D03*
X643307Y1236023D03*
Y1232283D03*
X650787Y1236023D03*
X647047Y1228543D03*
Y1224803D03*
X650787Y1232283D03*
X639567Y1236023D03*
X647047D03*
X639567Y1232283D03*
X643307Y1224803D03*
X647047Y1232283D03*
X643307Y1228543D03*
X650787D03*
Y1224803D03*
X643307Y1243503D03*
Y1247243D03*
X647047Y1254724D03*
Y1250984D03*
X650787Y1247243D03*
Y1243503D03*
X654527Y1250984D03*
Y1254724D03*
X639567Y1243503D03*
Y1239763D03*
Y1247243D03*
X647047Y1243503D03*
X650787Y1239763D03*
X647047D03*
X643307D03*
X650787Y1254724D03*
Y1250984D03*
X647047Y1247243D03*
X643307Y1254724D03*
Y1250984D03*
X639567D03*
Y1254724D03*
X650787Y1247243D03*
Y1243503D03*
X647047Y1254724D03*
Y1250984D03*
X643307Y1247243D03*
Y1243503D03*
X647047Y1258465D03*
X639567D03*
X648528Y1348187D03*
Y1360099D03*
X644168Y1384297D03*
Y1372385D03*
X648528D03*
Y1384297D03*
X644168Y1396583D03*
X648528D03*
X644168Y1408495D03*
X648528D03*
X669488Y1075196D03*
X662008D03*
X658268D03*
X665748D03*
X669487Y1071455D03*
X662007D03*
X654526D03*
X662008Y1075196D03*
X654527D03*
X669488D03*
X665748Y1086417D03*
Y1082677D03*
X669488Y1078936D03*
X658268Y1086417D03*
Y1082677D03*
X662008Y1078936D03*
X669488Y1093897D03*
X662008D03*
X669488Y1090157D03*
Y1086417D03*
X665748Y1078936D03*
X669488Y1082677D03*
X665748Y1090157D03*
X654527Y1082677D03*
Y1086417D03*
Y1090157D03*
X658268D03*
X662008Y1082677D03*
Y1086417D03*
Y1090157D03*
X658268Y1078936D03*
X662008D03*
X665748Y1082677D03*
X658268D03*
X654527Y1078936D03*
X665748Y1086417D03*
X658268D03*
X669488Y1078936D03*
Y1097637D03*
X665748Y1105117D03*
X658268D03*
X662008Y1097637D03*
X658268Y1101376D03*
X665748D03*
X662008Y1097637D03*
X654527Y1093897D03*
X669488D03*
X662008Y1101377D03*
X665748Y1093897D03*
X658268D03*
X654527Y1105117D03*
Y1101377D03*
X662008Y1105117D03*
X658268Y1097637D03*
X669488Y1101377D03*
Y1105117D03*
X665748Y1097637D03*
Y1105117D03*
X654527Y1097637D03*
X662008Y1093897D03*
X669488Y1097637D03*
X665748Y1101376D03*
X658268Y1105117D03*
Y1101376D03*
X656398Y1118208D03*
Y1121948D03*
X663878Y1118208D03*
X660138D03*
Y1121948D03*
X663878D03*
X667618Y1118208D03*
Y1121948D03*
X669488Y1108858D03*
X665748D03*
X662008D03*
X658268D03*
X654527D03*
X660138Y1114468D03*
X656398D03*
X663878D03*
X667618D03*
X656398Y1140649D03*
X660138D03*
X663878D03*
X656398Y1125688D03*
X660138D03*
X663878D03*
Y1133169D03*
X660138D03*
X656398D03*
X667618D03*
Y1140649D03*
Y1125688D03*
Y1129429D03*
X660138D03*
X656398D03*
X663878D03*
Y1136909D03*
X660138D03*
X656398D03*
X667618D03*
Y1148129D03*
X660138D03*
X656398D03*
X663878D03*
X656398Y1155610D03*
X663878D03*
X660138D03*
X667618D03*
Y1144389D03*
X663878D03*
X660138D03*
X656398D03*
X667618Y1151870D03*
X663878D03*
X660138D03*
X656398D03*
X663878Y1166830D03*
X660138Y1159350D03*
X656398Y1166830D03*
X660138Y1170570D03*
X667618Y1159350D03*
Y1170570D03*
X663878D03*
X660138Y1166830D03*
X656398Y1170570D03*
X663878Y1159350D03*
X656398D03*
X667618Y1166830D03*
X663878Y1181791D03*
X660138D03*
X656398D03*
X663878Y1189271D03*
X660138D03*
X656398D03*
X667618Y1181791D03*
Y1189271D03*
X656398Y1174310D03*
X663878D03*
X667618D03*
X660138D03*
X667618Y1185531D03*
X660138D03*
X656398D03*
X663878D03*
X667618Y1178051D03*
X663878D03*
X660138D03*
X656398D03*
X663878Y1196751D03*
X660138D03*
X656398D03*
Y1204232D03*
X660138D03*
X663878D03*
X667618Y1196751D03*
Y1204232D03*
Y1200491D03*
X656398D03*
X663878D03*
X660138D03*
X663878Y1193011D03*
X660138D03*
X656398D03*
X667618D03*
X663878Y1207972D03*
X660138D03*
X656398D03*
X667618D03*
Y1211712D03*
X654527Y1221062D03*
X658268D03*
X662008D03*
X665748D03*
X669488D03*
X663878Y1211712D03*
X656398D03*
X660138Y1215452D03*
X656398D03*
X663878D03*
X667618D03*
X660138Y1211712D03*
X669488Y1232283D03*
Y1236023D03*
X658268Y1224803D03*
Y1228543D03*
X662008Y1236023D03*
Y1232283D03*
X665748Y1228543D03*
Y1224803D03*
X654527D03*
Y1228543D03*
X658268Y1236023D03*
Y1232283D03*
X662008Y1228543D03*
Y1224803D03*
X665748Y1236023D03*
Y1232283D03*
X669488Y1228543D03*
Y1224803D03*
Y1232283D03*
X654527Y1236023D03*
X662008Y1232283D03*
X665748Y1224803D03*
X662008Y1236023D03*
X658268Y1224803D03*
X665748Y1228543D03*
X658268D03*
X669488Y1236023D03*
X654527Y1232283D03*
X658268Y1243503D03*
Y1247243D03*
X662008Y1254724D03*
Y1250984D03*
X665748Y1247243D03*
Y1243503D03*
X669488Y1250984D03*
Y1254724D03*
X654527Y1239763D03*
Y1243503D03*
Y1247243D03*
X662008Y1239763D03*
X658268D03*
X669488D03*
X665748D03*
Y1250984D03*
Y1254724D03*
X669488Y1247243D03*
Y1243503D03*
X662008D03*
Y1247243D03*
X658268Y1254724D03*
Y1250984D03*
X662008Y1254724D03*
X665748Y1247243D03*
X669488Y1250984D03*
X658268Y1247243D03*
X662008Y1250984D03*
X665748Y1243503D03*
X669488Y1254724D03*
X658268Y1243503D03*
X654527Y1254724D03*
Y1250984D03*
X662008Y1258465D03*
X669488D03*
X654528D03*
X660768Y1348187D03*
X668648D03*
X656408D03*
X660768Y1360099D03*
X668648D03*
X656408D03*
Y1384297D03*
Y1372385D03*
X668648D03*
X660768D03*
X668648Y1384297D03*
X660768D03*
X668648Y1396583D03*
X656408D03*
X660768D03*
X668648Y1408495D03*
X656408D03*
X660768D03*
X684449Y1075196D03*
X676968D03*
X680709D03*
X673228D03*
X684448Y1071455D03*
X676967D03*
X676968Y1075196D03*
X684449D03*
X673228Y1086417D03*
Y1082677D03*
X676968Y1078936D03*
X680709Y1082677D03*
Y1086417D03*
X684449Y1078936D03*
X688189Y1082677D03*
Y1086417D03*
X684449Y1093897D03*
X676968D03*
X680709Y1090157D03*
X676968D03*
X684449D03*
Y1082677D03*
Y1086417D03*
X673228Y1090157D03*
Y1078936D03*
X680709D03*
X676968Y1082677D03*
Y1086417D03*
Y1078936D03*
X680709Y1086417D03*
X684449Y1078936D03*
X673228Y1086417D03*
Y1082677D03*
X680709D03*
X688189Y1101376D03*
Y1105117D03*
X684449Y1097637D03*
X673228Y1101376D03*
Y1105117D03*
X680708Y1101376D03*
Y1105117D03*
X676968Y1097637D03*
X673228Y1105117D03*
X684449Y1093897D03*
X676968D03*
Y1105117D03*
X684449Y1101377D03*
Y1105117D03*
X680709Y1093897D03*
X676968Y1101377D03*
X680709Y1097637D03*
X673228D03*
Y1093897D03*
X684449Y1097637D03*
X676968D03*
X680708Y1105117D03*
X673228Y1101376D03*
X680708D03*
X682579Y1118208D03*
Y1121948D03*
X671358Y1114468D03*
Y1118208D03*
X675098D03*
X678838D03*
X675098Y1121948D03*
X678838D03*
X671358D03*
X684449Y1108858D03*
X680709D03*
X676968D03*
X673228D03*
X682579Y1114468D03*
X678839D03*
X675098D03*
X682579Y1133169D03*
Y1140649D03*
Y1125688D03*
X671358Y1140649D03*
X675098D03*
X678838D03*
X675098Y1125688D03*
X671358D03*
X678838D03*
Y1133169D03*
X675098D03*
X671358D03*
X675098Y1129429D03*
X671358D03*
X678838D03*
X682579D03*
Y1136909D03*
X678838D03*
X675098D03*
X671358D03*
X682579Y1148129D03*
X678838D03*
X675098D03*
X671358D03*
Y1155610D03*
X678838D03*
X682579D03*
X675098D03*
X678839Y1151870D03*
X675098D03*
X671358D03*
X682579D03*
Y1144389D03*
X671358D03*
X678838D03*
X675098D03*
X682579Y1170570D03*
Y1159350D03*
X675098Y1170570D03*
X678839Y1166830D03*
X671358D03*
X675098Y1159350D03*
X682579Y1166830D03*
X678838Y1170570D03*
X671358D03*
X675098Y1166830D03*
X671358Y1159350D03*
X678838D03*
X675098Y1181791D03*
X671358D03*
X678838Y1189271D03*
X675098D03*
X671358D03*
X682579Y1181791D03*
Y1189271D03*
X678838Y1181791D03*
X671358Y1174310D03*
X678838D03*
X682579D03*
X675098D03*
X682579Y1185531D03*
X675098D03*
X671358D03*
X678838D03*
X682579Y1178051D03*
X678838D03*
X675098D03*
X671358D03*
X682579Y1196751D03*
Y1204232D03*
X678838D03*
Y1196751D03*
X675098D03*
X671358D03*
Y1204232D03*
X675098D03*
Y1200491D03*
X671358D03*
X678838D03*
X682579D03*
Y1193011D03*
X678838D03*
X675098D03*
X671358D03*
X682579Y1207972D03*
X675098Y1211712D03*
X678838Y1219192D03*
Y1207972D03*
X675098D03*
X671358D03*
X673228Y1221062D03*
X676968D03*
X680709D03*
X684449D03*
X682579Y1211712D03*
X678839D03*
Y1215452D03*
X671358Y1211712D03*
Y1215452D03*
X675098D03*
X684449Y1236023D03*
Y1232283D03*
X688189Y1224803D03*
Y1228543D03*
X673228Y1224803D03*
Y1228543D03*
X676968Y1236023D03*
Y1232283D03*
X680709Y1228543D03*
Y1224803D03*
X673228Y1236023D03*
Y1232283D03*
X676968Y1224803D03*
Y1228543D03*
X680709Y1236023D03*
Y1232283D03*
X684449Y1224803D03*
Y1228543D03*
X676968Y1236023D03*
X684449Y1232283D03*
X673228Y1228543D03*
X680709Y1224803D03*
X684449Y1236023D03*
X676968Y1232283D03*
X673228Y1224803D03*
X680709Y1228543D03*
X673228Y1243503D03*
Y1247243D03*
X676968Y1254724D03*
Y1250984D03*
X680709Y1247243D03*
Y1243503D03*
X684449Y1250984D03*
Y1254724D03*
X688189Y1243503D03*
Y1247243D03*
X673228Y1239763D03*
X676968D03*
X680709D03*
Y1254724D03*
Y1250984D03*
X676968Y1243503D03*
Y1247243D03*
X673228Y1254724D03*
Y1250984D03*
X684449Y1247243D03*
Y1243503D03*
Y1239763D03*
X673228Y1243503D03*
X680709Y1247243D03*
X673228D03*
X684449Y1254724D03*
Y1250984D03*
X676968Y1254724D03*
Y1250984D03*
X680709Y1243503D03*
X684450Y1258465D03*
X676969D03*
X680888Y1348187D03*
X673008D03*
X685248D03*
X680888Y1360099D03*
X673008D03*
X685248D03*
Y1372385D03*
Y1384297D03*
X673008Y1372385D03*
Y1384297D03*
X680888Y1372385D03*
Y1384297D03*
Y1396583D03*
X685248D03*
X673008D03*
X680888Y1408495D03*
X685248D03*
X673008D03*
X699408Y1075196D03*
X691928Y1075195D03*
X688189Y1075196D03*
X695669D03*
X699408Y1071455D03*
X691928Y1071454D03*
X699408Y1075196D03*
X691928Y1075195D03*
X699408Y1078936D03*
X695668Y1082676D03*
Y1086416D03*
X691928Y1078935D03*
X703148Y1082677D03*
Y1086417D03*
X691928Y1093897D03*
X699408D03*
X688189Y1078936D03*
Y1090157D03*
X691929Y1082677D03*
Y1086417D03*
X695669Y1090157D03*
X699409D03*
Y1086417D03*
X691929Y1090157D03*
X695669Y1078936D03*
X699409Y1082677D03*
X688189Y1086417D03*
Y1082677D03*
X691928Y1078935D03*
X699408Y1078936D03*
X695668Y1086416D03*
Y1082676D03*
X703149Y1101376D03*
Y1105117D03*
X695669D03*
Y1101376D03*
X691928Y1097637D03*
X699408D03*
X688189Y1105117D03*
Y1097637D03*
X695669Y1093897D03*
X688189D03*
X699409Y1105117D03*
X691929Y1101377D03*
X699409D03*
X695669Y1097637D03*
X691929Y1105117D03*
X695669Y1101376D03*
X699408Y1097637D03*
X695669Y1105117D03*
X691928Y1093897D03*
Y1097637D03*
X699408Y1093897D03*
X688189Y1101376D03*
X693799Y1121948D03*
X697539D03*
X701279D03*
X686319D03*
Y1118208D03*
Y1114468D03*
X699409Y1108858D03*
X695669D03*
X691929D03*
X688189D03*
X693799Y1114468D03*
Y1118208D03*
X701279Y1114468D03*
X697539Y1118208D03*
Y1114468D03*
X701279Y1118208D03*
X693799Y1133464D03*
X697539Y1133169D03*
X686417Y1132677D03*
X693799Y1140649D03*
X697539D03*
X693799Y1125688D03*
X697539D03*
X701279D03*
Y1140649D03*
Y1133169D03*
X686319Y1140649D03*
Y1125688D03*
X701279Y1129429D03*
X697539D03*
X693799D03*
X686319D03*
X697539Y1136909D03*
X693799D03*
X701279D03*
X686319D03*
X697539Y1148129D03*
X701279D03*
X693799D03*
X697539Y1155610D03*
X686319Y1148129D03*
Y1155610D03*
X701279D03*
X693799D03*
X701279Y1151869D03*
X697539D03*
X693799D03*
X701279Y1144389D03*
X697539D03*
X693799D03*
X686319D03*
Y1151870D03*
X697539Y1166830D03*
X693799Y1170570D03*
Y1159350D03*
X701279D03*
Y1170570D03*
X686319Y1166830D03*
X693799D03*
X697539Y1170570D03*
Y1159350D03*
X701279Y1166830D03*
X686319Y1170570D03*
Y1159350D03*
X693799Y1181791D03*
Y1189271D03*
X697539D03*
X701279D03*
Y1181791D03*
X697539D03*
Y1174310D03*
X686319Y1181791D03*
Y1189271D03*
Y1174310D03*
X701279D03*
X693799D03*
X701279Y1185531D03*
X697539D03*
X693799D03*
X701279Y1178051D03*
X697539D03*
X693799D03*
X686319Y1185531D03*
Y1178051D03*
X697539Y1204232D03*
X693799D03*
Y1196751D03*
X697539D03*
X701279D03*
Y1204232D03*
X686319Y1196751D03*
Y1204232D03*
X701279Y1200491D03*
X697539D03*
X693799D03*
X686319D03*
X701279Y1193011D03*
X697539D03*
X693799D03*
X686319D03*
X693799Y1207972D03*
X697539D03*
Y1211712D03*
X701279Y1207972D03*
Y1211712D03*
X686319Y1207972D03*
X695669Y1221062D03*
X699409D03*
X691929D03*
X688189D03*
X686319Y1211712D03*
Y1215452D03*
X699409Y1217322D03*
X697539Y1215452D03*
X693799D03*
Y1211712D03*
X701279Y1215452D03*
X695669Y1217322D03*
X703149Y1224803D03*
Y1228543D03*
X691929Y1236023D03*
Y1232283D03*
X695669Y1224803D03*
X699409Y1232283D03*
Y1236023D03*
X695669Y1228543D03*
X688189D03*
X691929Y1236023D03*
X699409Y1232283D03*
X688189Y1236023D03*
Y1232283D03*
X691929Y1224803D03*
Y1228543D03*
X699409Y1224803D03*
Y1228543D03*
X695669Y1236023D03*
Y1232283D03*
X688189Y1224803D03*
X699409Y1236023D03*
X691929Y1232283D03*
X695669Y1228543D03*
Y1224803D03*
X691929Y1254724D03*
Y1250984D03*
X695669Y1247243D03*
Y1243503D03*
X699409Y1250984D03*
Y1254724D03*
X703149Y1247243D03*
Y1243503D03*
X688189Y1254724D03*
Y1250984D03*
Y1239763D03*
X699409Y1247243D03*
Y1243503D03*
Y1239763D03*
X695669D03*
X691929D03*
Y1243503D03*
Y1247243D03*
X695669Y1250984D03*
Y1254724D03*
X699409D03*
X691929Y1250984D03*
X688189Y1247243D03*
Y1243503D03*
X691929Y1254724D03*
X695669Y1247243D03*
X699409Y1250984D03*
X695669Y1243503D03*
X699409Y1258465D03*
X691929D03*
X693128Y1348187D03*
X697488D03*
X693128Y1360099D03*
X697488D03*
Y1384297D03*
Y1372385D03*
X693128D03*
Y1384297D03*
Y1396583D03*
X697488D03*
X693128Y1408495D03*
X697488D03*
X706889Y1075196D03*
X714369D03*
X703149D03*
X718110D03*
X710630D03*
X714369Y1071455D03*
X706889D03*
Y1075196D03*
X714369D03*
X718109Y1086417D03*
Y1082677D03*
X714369Y1078936D03*
X710629Y1082676D03*
Y1086416D03*
X706889Y1078936D03*
Y1093897D03*
X714369D03*
X710630Y1078936D03*
X706890Y1082677D03*
Y1086417D03*
Y1090157D03*
X718110Y1078936D03*
X714370Y1082677D03*
Y1086417D03*
Y1090157D03*
X710630D03*
X718110D03*
X703149Y1078936D03*
Y1090157D03*
X706889Y1078936D03*
X718109Y1086417D03*
X714369Y1078936D03*
X703148Y1082677D03*
X710629Y1086416D03*
X703148Y1086417D03*
X718109Y1082677D03*
X710629Y1082676D03*
X718110Y1105117D03*
Y1101376D03*
X710630D03*
Y1105117D03*
X706889Y1097637D03*
X714369D03*
X706890Y1101377D03*
Y1105117D03*
X714370D03*
Y1101377D03*
X710630Y1097637D03*
Y1093897D03*
X718110Y1097637D03*
Y1093897D03*
X703149D03*
Y1097637D03*
X714369D03*
X706889Y1093897D03*
X703149Y1105117D03*
X718110D03*
Y1101376D03*
X710630Y1105117D03*
X714369Y1093897D03*
X706889Y1097637D03*
X703149Y1101376D03*
X710630D03*
X716240Y1121948D03*
X705020D03*
X708760D03*
X712500D03*
X718110Y1108858D03*
X714370D03*
X710630D03*
X706890D03*
X703149D03*
X708760Y1114468D03*
X716240Y1118208D03*
X705020Y1114468D03*
X712500D03*
X716240D03*
X705020Y1118208D03*
X712500D03*
X708760D03*
X716240Y1140649D03*
Y1125688D03*
Y1133169D03*
X712500Y1125688D03*
X708760D03*
X705020D03*
X712500Y1140649D03*
X708760D03*
X705020D03*
X712500Y1133169D03*
X708760D03*
X705020D03*
Y1129429D03*
X708760D03*
X712500D03*
X716240D03*
Y1136909D03*
X705020D03*
X708760D03*
X712500D03*
X716240Y1148129D03*
X712500D03*
X708760D03*
X705020D03*
X712500Y1155610D03*
X705020D03*
X708760D03*
X716240D03*
Y1151869D03*
X708760D03*
X712500D03*
X705020D03*
X712500Y1144389D03*
X705020D03*
X708760D03*
X716240D03*
Y1170570D03*
Y1159350D03*
X708760D03*
X705020Y1166830D03*
X712500D03*
X708760Y1170570D03*
X716240Y1166830D03*
X705020Y1159350D03*
X712500D03*
X705020Y1170570D03*
X712500D03*
X708760Y1166830D03*
X716240Y1189271D03*
Y1181791D03*
X712500Y1189271D03*
X708760D03*
X705020D03*
X712500Y1181791D03*
X708760D03*
X705020D03*
Y1174310D03*
X712500D03*
X716240D03*
X708760D03*
X716240Y1185531D03*
X708760D03*
X712500D03*
X705020D03*
X716240Y1178051D03*
X712500D03*
X705020D03*
X708760D03*
X716240Y1196751D03*
Y1204232D03*
X712500Y1196751D03*
X708760D03*
X705020D03*
X708760Y1204232D03*
X712500D03*
X705020D03*
X712500Y1200491D03*
X705020D03*
X708760D03*
X716240D03*
X708760Y1193011D03*
X712500D03*
X705020D03*
X716240D03*
Y1211712D03*
Y1207972D03*
X712500D03*
Y1211712D03*
X708760Y1207972D03*
X705020D03*
X703149Y1221062D03*
X706890D03*
X710630D03*
X714370D03*
X718110D03*
X716240Y1215452D03*
X708760D03*
X712500D03*
X705019Y1215451D03*
Y1211711D03*
X708760D03*
X718110Y1224803D03*
Y1228543D03*
X706890Y1236023D03*
Y1232283D03*
X710630Y1228543D03*
Y1224803D03*
X714370Y1232283D03*
Y1236023D03*
X706890D03*
X718110Y1228543D03*
X714370Y1236023D03*
X710630Y1228543D03*
X703149D03*
Y1236023D03*
Y1232283D03*
X710630Y1236023D03*
X718110D03*
Y1232283D03*
X710630D03*
X714370Y1224803D03*
Y1228543D03*
X706890Y1224803D03*
Y1228543D03*
X714370Y1232283D03*
X703149Y1224803D03*
X718110D03*
X710630D03*
X706890Y1232283D03*
Y1254724D03*
Y1250984D03*
X710630Y1243503D03*
Y1247243D03*
X714370Y1250984D03*
Y1254724D03*
X718110Y1247243D03*
Y1243503D03*
X703149Y1254724D03*
Y1250984D03*
Y1239763D03*
X714370D03*
X718110Y1250984D03*
Y1239763D03*
X714370Y1243503D03*
Y1247243D03*
X710630Y1254724D03*
Y1250984D03*
Y1239763D03*
X706890Y1247243D03*
Y1243503D03*
Y1239763D03*
X718110Y1254724D03*
Y1243503D03*
Y1247243D03*
X706890Y1250984D03*
X703149Y1243503D03*
X714370Y1254724D03*
Y1250984D03*
X710630Y1247243D03*
X706890Y1254724D03*
X710630Y1243503D03*
X703149Y1247243D03*
X714370Y1258465D03*
X706890D03*
X705368Y1348187D03*
X717608D03*
X709728D03*
X705368Y1360099D03*
X717608D03*
X709728D03*
Y1384297D03*
Y1372385D03*
X705368D03*
Y1384297D03*
X717608Y1372385D03*
Y1384297D03*
Y1396583D03*
X705368D03*
X709728D03*
X717608Y1408495D03*
X705368D03*
X709728D03*
X736810Y1075196D03*
X721849D03*
X729330D03*
X725590D03*
X733071D03*
X729330Y1071455D03*
X721849D03*
Y1075196D03*
X729330D03*
X733069Y1082677D03*
Y1086417D03*
X729330Y1078936D03*
X725589Y1082676D03*
Y1086416D03*
X721849Y1078936D03*
X736810D03*
Y1093897D03*
X729330D03*
X721849D03*
X721850Y1082677D03*
X729331Y1086417D03*
Y1082677D03*
X733071Y1090157D03*
Y1078936D03*
X729331Y1090157D03*
X725590D03*
X721850D03*
X725590Y1078936D03*
X721850Y1086417D03*
X725589Y1086416D03*
X733069Y1086417D03*
X721849Y1078936D03*
X729330D03*
X733069Y1082677D03*
X725589Y1082676D03*
X733071Y1105117D03*
Y1101376D03*
X736810Y1097637D03*
X721849D03*
X725590Y1101376D03*
Y1105117D03*
X729330Y1097637D03*
X729331Y1101377D03*
X725590Y1097637D03*
X721850Y1101377D03*
Y1105117D03*
X725590Y1093897D03*
X729331Y1105117D03*
X733071Y1093897D03*
Y1097637D03*
X725590Y1101376D03*
X733071Y1105117D03*
X725590D03*
X721849Y1097637D03*
Y1093897D03*
X729330Y1097637D03*
X733071Y1101376D03*
X729330Y1093897D03*
X734941Y1121948D03*
Y1118208D03*
X727460Y1121948D03*
X719980D03*
X723720D03*
X727460Y1118208D03*
X731201Y1121948D03*
Y1118208D03*
X733071Y1108858D03*
X729331D03*
X725590D03*
X721850D03*
X731201Y1114468D03*
X734941D03*
X727460D03*
X719980Y1118208D03*
Y1114468D03*
X734941Y1129429D03*
Y1125688D03*
Y1140649D03*
Y1133169D03*
Y1136909D03*
X727460Y1140649D03*
X723720Y1125688D03*
X719980D03*
X727460Y1129429D03*
Y1125688D03*
X723720Y1140649D03*
X719980D03*
X727460Y1133169D03*
X723720D03*
X719980D03*
X727460Y1136909D03*
X731201Y1125688D03*
X719980Y1129429D03*
X723720D03*
X731201D03*
X719980Y1136909D03*
X723720D03*
X731201D03*
Y1140649D03*
X727460Y1151869D03*
Y1148129D03*
Y1144389D03*
X723720Y1148129D03*
X719980D03*
X731201D03*
Y1151869D03*
Y1155610D03*
X734941Y1151870D03*
Y1148129D03*
Y1144389D03*
X719980Y1155610D03*
X727460D03*
X723720D03*
X719980Y1151869D03*
X723720D03*
Y1144389D03*
X719980D03*
X734941Y1155610D03*
X731201Y1144389D03*
Y1170570D03*
X719980Y1166830D03*
X731201Y1159350D03*
Y1166830D03*
X719980Y1159350D03*
X727460D03*
X723720D03*
Y1166830D03*
X727460D03*
X719980Y1170570D03*
X727460D03*
X723720D03*
X734941Y1159350D03*
Y1166830D03*
Y1170570D03*
X727460Y1185531D03*
X734941Y1181791D03*
Y1185531D03*
Y1189271D03*
Y1178051D03*
X727460Y1189271D03*
X723720Y1181791D03*
X719980D03*
Y1174310D03*
X727460Y1178051D03*
X723720Y1189271D03*
X719980D03*
X731201Y1174310D03*
Y1181791D03*
X727460Y1174310D03*
X723720D03*
X727460Y1181791D03*
X719980Y1185531D03*
Y1178051D03*
X723720D03*
Y1185531D03*
X734941Y1174310D03*
X731201Y1189271D03*
Y1185531D03*
Y1178051D03*
X719980Y1204232D03*
X727460D03*
X727480Y1196732D03*
X731201Y1196751D03*
Y1204232D03*
X734941Y1193011D03*
X727460D03*
X723720Y1196751D03*
X719980D03*
X727460Y1200491D03*
X723720Y1204232D03*
X719980Y1200491D03*
X723720D03*
X731201D03*
X719980Y1193011D03*
X723720D03*
X731201D03*
X734941Y1196751D03*
Y1204232D03*
Y1200491D03*
Y1211712D03*
X727460Y1207972D03*
X723720Y1211712D03*
Y1207972D03*
X719980Y1211712D03*
Y1207972D03*
X727460Y1211712D03*
X731201Y1207972D03*
X733071Y1221062D03*
X721850D03*
X725590D03*
X729331D03*
X731201Y1215452D03*
X734941D03*
X723720D03*
X719980D03*
X731201Y1211712D03*
X734941Y1207972D03*
X727461Y1215452D03*
X736811Y1236023D03*
Y1232283D03*
X733071Y1228543D03*
Y1224803D03*
X721850Y1236023D03*
Y1232283D03*
X725590Y1224803D03*
Y1228543D03*
X729331Y1236023D03*
Y1232283D03*
X725590Y1228543D03*
X733071D03*
X729331Y1224803D03*
Y1228543D03*
X733071Y1236023D03*
Y1232283D03*
X725590Y1236023D03*
Y1232283D03*
X721850Y1224803D03*
Y1228543D03*
Y1236023D03*
X733071Y1224803D03*
X721850Y1232283D03*
X725590Y1224803D03*
X729331Y1236023D03*
Y1232283D03*
X721850Y1254724D03*
Y1250984D03*
X725590Y1243503D03*
Y1247243D03*
X729331Y1250984D03*
Y1254724D03*
X733071Y1247243D03*
Y1243503D03*
X736811Y1254724D03*
Y1250984D03*
X733071Y1239763D03*
X729331Y1243503D03*
X721850D03*
X725590Y1239763D03*
X729331D03*
X721850D03*
X729331Y1247243D03*
X733071Y1250984D03*
Y1254724D03*
X725590D03*
Y1250984D03*
X721850Y1247243D03*
X729331Y1250984D03*
X733071Y1247243D03*
X721850Y1250984D03*
Y1254724D03*
X725590Y1243503D03*
X729331Y1254724D03*
X733071Y1243503D03*
X725590Y1247243D03*
X729331Y1258465D03*
X721850D03*
X734208Y1348187D03*
X729848D03*
X721968D03*
X734208Y1360099D03*
X729848D03*
X721968D03*
X729848Y1372385D03*
Y1384297D03*
X721968D03*
Y1372385D03*
X734208D03*
Y1384297D03*
X729848Y1396489D03*
X721968D03*
X734208D03*
X729848Y1408401D03*
X721968D03*
X734208D03*
X751771Y1075196D03*
X744290D03*
X740551D03*
X748031D03*
X744290Y1071455D03*
X736810D03*
Y1075196D03*
X744290D03*
Y1078936D03*
X748030Y1082677D03*
X740550Y1082676D03*
Y1086416D03*
X748030Y1086417D03*
X751771Y1078936D03*
Y1093897D03*
X744290D03*
X748030Y1090157D03*
X744291Y1082677D03*
X748031Y1078936D03*
X744291Y1090157D03*
Y1086417D03*
X740551Y1078936D03*
Y1090157D03*
X736811Y1086417D03*
Y1090157D03*
Y1082677D03*
X744290Y1078936D03*
X748030Y1086417D03*
X740550Y1086416D03*
Y1082676D03*
X736810Y1078936D03*
X748030Y1082677D03*
X751771Y1097637D03*
X740551Y1105117D03*
X748031Y1101376D03*
X740551D03*
X748031Y1105117D03*
X744290Y1097637D03*
X744291Y1101377D03*
X740551Y1097637D03*
X748031Y1093897D03*
Y1097637D03*
X740551Y1093897D03*
X744291Y1105117D03*
X736811D03*
Y1101377D03*
X736810Y1097637D03*
X748031Y1105117D03*
X744290Y1093897D03*
X740551Y1105117D03*
X744290Y1097637D03*
X736810Y1093897D03*
X740551Y1101376D03*
X748031D03*
X751771Y1123818D03*
Y1116338D03*
X748031Y1123818D03*
Y1120078D03*
Y1116338D03*
Y1112598D03*
Y1108858D03*
X744291D03*
X740551D03*
X736811D03*
X738681Y1118208D03*
X742421D03*
X738681Y1114468D03*
X742421D03*
X751771Y1131299D03*
X738681Y1136909D03*
Y1140649D03*
X748031Y1138779D03*
Y1135039D03*
Y1131299D03*
Y1127558D03*
X742421Y1140649D03*
Y1136909D03*
X746161Y1140649D03*
X749902D03*
X738681Y1155610D03*
Y1148129D03*
X749901Y1144389D03*
Y1151869D03*
X746161Y1144389D03*
Y1155610D03*
Y1151869D03*
X742421D03*
X738681D03*
X742421Y1155610D03*
X746161Y1148129D03*
X738681Y1144389D03*
X742421Y1148129D03*
Y1144389D03*
X749902Y1155610D03*
Y1148129D03*
X738681Y1166830D03*
X746161Y1170570D03*
Y1166830D03*
X738681Y1159350D03*
X749901Y1166830D03*
Y1159350D03*
X738681Y1170570D03*
X746161Y1159350D03*
X742421D03*
Y1166830D03*
Y1170570D03*
X749902D03*
X749901Y1181791D03*
Y1174310D03*
X738681D03*
Y1178051D03*
X742421Y1181791D03*
X738681Y1185531D03*
Y1189271D03*
X746161Y1185531D03*
Y1178051D03*
Y1174310D03*
X742421Y1185531D03*
Y1189271D03*
X746161D03*
X742421Y1174310D03*
X738681Y1181791D03*
X746161D03*
X742421Y1178051D03*
X751772Y1198621D03*
Y1206102D03*
X748031Y1191141D03*
X738681Y1204232D03*
X748031Y1194881D03*
X738681Y1193011D03*
Y1196751D03*
X742421Y1193011D03*
X748031Y1202362D03*
Y1198621D03*
X742421Y1196751D03*
X738681Y1200491D03*
X742421Y1204232D03*
Y1200491D03*
X751772Y1213582D03*
X736811Y1221062D03*
X740551D03*
X748031D03*
X744291D03*
X748031Y1217322D03*
Y1213582D03*
Y1209842D03*
Y1206102D03*
X742421Y1211712D03*
Y1215452D03*
Y1207972D03*
X738681Y1215452D03*
Y1207972D03*
Y1211712D03*
X751772Y1232283D03*
Y1236023D03*
X740551Y1224803D03*
Y1228543D03*
X744291Y1232283D03*
Y1236023D03*
X748031Y1228543D03*
Y1224803D03*
X744291Y1236023D03*
X736811Y1232283D03*
Y1224803D03*
Y1228543D03*
X748031Y1236023D03*
Y1232283D03*
X740551Y1236023D03*
X744291Y1228543D03*
X740551Y1232283D03*
X744291Y1224803D03*
Y1232283D03*
X736811Y1236023D03*
X740551Y1224803D03*
Y1228543D03*
X748031Y1224803D03*
Y1228543D03*
X740551Y1247243D03*
X748031Y1243503D03*
Y1247243D03*
X744291Y1254724D03*
Y1250984D03*
X740551Y1243503D03*
X751772Y1254724D03*
Y1250984D03*
X736811Y1243503D03*
Y1239763D03*
Y1247243D03*
X748031Y1239763D03*
X744291Y1243503D03*
Y1239763D03*
X740551D03*
X748031Y1254724D03*
Y1250984D03*
X744291Y1247243D03*
X740551Y1254724D03*
Y1250984D03*
X744291Y1254724D03*
X740551Y1243503D03*
Y1247243D03*
X744291Y1250984D03*
X736811Y1254724D03*
Y1250984D03*
X748031Y1247243D03*
Y1243503D03*
X744291Y1258465D03*
X736811D03*
X746448Y1348187D03*
X742088D03*
X746448Y1360099D03*
X742088D03*
Y1384297D03*
Y1372385D03*
X746448D03*
Y1384297D03*
X742088Y1396489D03*
Y1408401D03*
X766731Y1075196D03*
X759251D03*
X755512D03*
X762993D03*
X766732Y1071455D03*
X759252D03*
X751771D03*
Y1075196D03*
X766731D03*
X759251D03*
X762991Y1086417D03*
X766731Y1078936D03*
X759251D03*
X762991Y1082677D03*
X755511Y1086416D03*
Y1082676D03*
X766731Y1093897D03*
X759251D03*
Y1082677D03*
X766731Y1090157D03*
X751772Y1086417D03*
X751771Y1090157D03*
Y1082677D03*
X759251Y1090157D03*
X762991D03*
X759252Y1086417D03*
X755511Y1090157D03*
X766732Y1086417D03*
X762993Y1078936D03*
X766731Y1082677D03*
X755513Y1078936D03*
X762991Y1086417D03*
X766731Y1078936D03*
X755511Y1086416D03*
X759251Y1078936D03*
X755511Y1082676D03*
X762991Y1082677D03*
X751771Y1078936D03*
X766731Y1097637D03*
X762992Y1101376D03*
X759251Y1097637D03*
X755512Y1105117D03*
Y1101376D03*
X762992Y1105117D03*
X751771Y1101377D03*
X751772Y1105117D03*
X762992Y1097637D03*
Y1093897D03*
X759252Y1105117D03*
X766732D03*
X755512Y1097637D03*
X759252Y1101377D03*
X766732D03*
X755512Y1093897D03*
X751771Y1097637D03*
X762992Y1101376D03*
Y1105117D03*
X755512D03*
X759251Y1097637D03*
Y1093897D03*
X766731Y1097637D03*
X755512Y1101376D03*
X766731Y1093897D03*
X751771D03*
X755512Y1123818D03*
Y1116338D03*
X759252Y1120078D03*
Y1112598D03*
X762992D03*
Y1120078D03*
Y1116338D03*
X766732Y1120078D03*
X762991Y1108857D03*
X766731Y1108858D03*
X766732Y1116338D03*
Y1123818D03*
X762992D03*
X766732Y1112598D03*
X755512Y1108858D03*
X759252D03*
X751772D03*
X759252Y1116338D03*
X755512Y1120078D03*
X759252Y1123818D03*
X751771Y1112598D03*
Y1120078D03*
X755512Y1123818D03*
X759252Y1112598D03*
X751771Y1123818D03*
X762992Y1112598D03*
X755512Y1116338D03*
X751771D03*
X759252Y1120078D03*
X762992D03*
X755512Y1131299D03*
X759252Y1135039D03*
Y1127559D03*
X762992D03*
Y1135039D03*
X757382Y1140649D03*
X761122D03*
X764862D03*
X762992Y1131299D03*
X766732D03*
Y1135039D03*
Y1127558D03*
X755512D03*
X759252Y1131299D03*
X755512Y1135039D03*
X751772Y1127558D03*
Y1135039D03*
X751771Y1131299D03*
X762992Y1135039D03*
X755512Y1131299D03*
X762992Y1127559D03*
X759252Y1135039D03*
Y1127559D03*
X764862Y1155610D03*
Y1148129D03*
X753642Y1144389D03*
X757382D03*
Y1148129D03*
Y1151869D03*
Y1155610D03*
X761122Y1148129D03*
Y1155610D03*
X753642Y1151869D03*
X761122Y1144389D03*
Y1151869D03*
X753642Y1155610D03*
X764862Y1151869D03*
Y1144389D03*
Y1159350D03*
Y1170570D03*
X757382Y1166830D03*
Y1170570D03*
X761122D03*
X753642Y1166830D03*
X757382Y1159350D03*
X753642D03*
X764862Y1166830D03*
X761122D03*
Y1159350D03*
X753642Y1170570D03*
Y1181791D03*
Y1174310D03*
X757382D03*
Y1178051D03*
Y1181791D03*
Y1185531D03*
X764862D03*
Y1178051D03*
X755512Y1187401D03*
X761122Y1178051D03*
Y1185531D03*
X753642Y1189271D03*
X764862D03*
Y1174310D03*
X761122Y1181791D03*
X764862D03*
X761122Y1174310D03*
X755512Y1198621D03*
X759252Y1202362D03*
X762992D03*
X755512Y1206102D03*
X766732Y1194881D03*
X759252Y1191141D03*
X762992D03*
X755512Y1194881D03*
X751772D03*
X755512Y1202362D03*
X766732D03*
Y1198621D03*
X762992D03*
X759252D03*
X751772Y1202362D03*
X762992D03*
X755512Y1198621D03*
X759252Y1202362D03*
X751772Y1198621D03*
X762992Y1209842D03*
X759252D03*
X755512Y1213582D03*
X759252Y1217322D03*
X762992D03*
X766732Y1221062D03*
Y1217322D03*
X762992Y1221062D03*
X759252D03*
X755512D03*
Y1217322D03*
X759252Y1213582D03*
X762992D03*
X766732D03*
Y1209842D03*
X755512D03*
X766732Y1206102D03*
X762992D03*
X759252D03*
X751772Y1221062D03*
Y1217322D03*
Y1209842D03*
X762992Y1217322D03*
X751772Y1213582D03*
X762992Y1209842D03*
X755512Y1213582D03*
X751772Y1206102D03*
X759252Y1217322D03*
Y1209842D03*
X755512Y1206102D03*
X766732Y1232283D03*
Y1236023D03*
X759252D03*
Y1232283D03*
X762992Y1228543D03*
Y1224803D03*
X755512Y1228543D03*
Y1224803D03*
X759252D03*
Y1228543D03*
X755512Y1232283D03*
Y1236023D03*
X766732Y1224803D03*
Y1228543D03*
X762992Y1232283D03*
Y1236023D03*
X751772Y1224803D03*
Y1228543D03*
X755512D03*
X751772Y1236023D03*
X762992Y1228543D03*
X751772Y1232283D03*
X766732D03*
Y1236023D03*
X759252Y1232283D03*
X762992Y1224803D03*
X759252Y1236023D03*
X755512Y1224803D03*
Y1243503D03*
Y1247243D03*
X759252Y1250984D03*
Y1254724D03*
X766732D03*
Y1250984D03*
X762992Y1247243D03*
Y1243503D03*
X755512Y1250984D03*
Y1254724D03*
X759252Y1247243D03*
Y1243503D03*
X762992Y1250984D03*
Y1254724D03*
X766732Y1247243D03*
Y1243503D03*
X755512Y1239763D03*
X759252D03*
X762992D03*
X766732D03*
X751772Y1247243D03*
Y1243503D03*
Y1239763D03*
X766732Y1250984D03*
X755512Y1243503D03*
X762992D03*
Y1247243D03*
X751772Y1250984D03*
Y1254724D03*
X759252D03*
X766732D03*
X759252Y1250984D03*
X755512Y1247243D03*
X766732Y1258465D03*
X759252D03*
X751772D03*
X766568Y1348187D03*
X758688D03*
X754328D03*
X766568Y1360099D03*
X758688D03*
X754328D03*
Y1372385D03*
Y1384297D03*
X758688Y1372385D03*
X766568D03*
X758688Y1384297D03*
X766568D03*
X774211Y1075196D03*
X777953D03*
X770473D03*
X774212Y1071455D03*
X774211Y1075196D03*
X777953Y1090157D03*
X781693D03*
Y1082676D03*
X777953D03*
X770471Y1082677D03*
Y1086417D03*
X774211Y1078936D03*
X774212Y1093897D03*
Y1090157D03*
X777953Y1078936D03*
X781693D03*
X770473D03*
X774213Y1086417D03*
X774212Y1082677D03*
X770471Y1090157D03*
X781693Y1086417D03*
X777953D03*
X781693Y1090157D03*
X777953D03*
X781693Y1082676D03*
X774211Y1078936D03*
X770471Y1086417D03*
Y1082677D03*
X777953Y1082676D03*
X781693Y1101377D03*
X774212Y1097637D03*
X770472Y1105117D03*
Y1101377D03*
X777953D03*
X781693Y1108858D03*
X777953D03*
X770472Y1097637D03*
X777953Y1093897D03*
X774212Y1101377D03*
X777953Y1105117D03*
X774213D03*
X770472Y1093897D03*
X781693D03*
Y1097637D03*
X777953D03*
X781693Y1105117D03*
X770472Y1101377D03*
X781693D03*
X777953D03*
X774212Y1097637D03*
X770472Y1105117D03*
X774212Y1093897D03*
X770472Y1112598D03*
X774212D03*
X781693Y1116338D03*
X777953D03*
X770472Y1120078D03*
X774212D03*
X781693Y1123818D03*
X777953D03*
X781693Y1112598D03*
X770472Y1123818D03*
X777953Y1120078D03*
X781693D03*
X774212Y1123818D03*
X770472Y1108858D03*
X774212D03*
X770472Y1116338D03*
X774212D03*
X777953Y1112598D03*
X774212D03*
X770472D03*
X781693Y1123818D03*
X777953D03*
X781693Y1116338D03*
X777953Y1108858D03*
X770472Y1120078D03*
X781693Y1108858D03*
X777953Y1116338D03*
X774212Y1120078D03*
X781693Y1131299D03*
X770472Y1127558D03*
X774212D03*
X777953Y1131299D03*
X774212Y1135039D03*
X770472D03*
X783563Y1140649D03*
X776083D03*
X779823D03*
X781693Y1127558D03*
X777953D03*
X774212Y1131299D03*
X770471D03*
X777953Y1135039D03*
X781693D03*
X770472Y1138779D03*
Y1127558D03*
Y1135039D03*
X781693Y1131299D03*
X774212Y1127558D03*
Y1135039D03*
X777953Y1131299D03*
X768602Y1140649D03*
X772342D03*
X783563Y1155610D03*
Y1148129D03*
X776083D03*
Y1151869D03*
X772342D03*
X776083Y1155610D03*
X772342Y1144389D03*
X768602Y1151869D03*
Y1144389D03*
X776083D03*
X779823Y1155610D03*
Y1148129D03*
X772342D03*
Y1155610D03*
X783563Y1151870D03*
X779823D03*
Y1144389D03*
X783563D03*
X768602Y1155610D03*
Y1148129D03*
X783563Y1170570D03*
Y1166830D03*
X776083D03*
Y1170570D03*
X772342Y1166830D03*
X768602Y1159350D03*
X776083D03*
X772342D03*
X768602Y1166830D03*
X779823D03*
Y1170570D03*
Y1159350D03*
X772342Y1170570D03*
X768602D03*
X783563Y1159350D03*
X776083Y1174310D03*
X772342D03*
X776083Y1178051D03*
Y1181791D03*
Y1185531D03*
X772342Y1181791D03*
X779823Y1185531D03*
Y1178051D03*
X783563Y1185531D03*
Y1178051D03*
X768602Y1181791D03*
Y1174310D03*
X772342Y1189271D03*
X783563D03*
X768602Y1185531D03*
X772342Y1178051D03*
X779823Y1189271D03*
X772342Y1185531D03*
X783563Y1174310D03*
X779823D03*
X783563Y1181791D03*
X768602Y1178051D03*
X779823Y1181791D03*
X781693Y1198621D03*
X770472Y1202362D03*
X774212D03*
X777953Y1198621D03*
X781693Y1206102D03*
X777953D03*
X783503Y1193011D03*
X776083Y1196751D03*
X772342D03*
X776083Y1193011D03*
X779823D03*
X781693Y1202362D03*
X777953D03*
X774212Y1198621D03*
X770472D03*
X781693D03*
X774212Y1202362D03*
X770472D03*
X777953Y1198621D03*
X768602Y1193011D03*
X772342D03*
X774212Y1209842D03*
X770472D03*
Y1217322D03*
X774212D03*
X777953Y1221062D03*
X781693D03*
X777953Y1213582D03*
X781693D03*
Y1217322D03*
X777953D03*
X774212Y1221062D03*
X770472D03*
X781693Y1209842D03*
X777953D03*
X774212Y1213582D03*
X770472D03*
X774212Y1206102D03*
X770472D03*
X777953D03*
X770472Y1209842D03*
X781693Y1213582D03*
X774212Y1209842D03*
X777953Y1221062D03*
X781693D03*
Y1206102D03*
X770472Y1217322D03*
X774212D03*
X777953Y1213582D03*
X781693Y1228543D03*
X774212Y1236023D03*
Y1232283D03*
X777953Y1228543D03*
X770472D03*
Y1224803D03*
X781693Y1239763D03*
X777953D03*
X781693Y1224803D03*
X777953D03*
X774212D03*
Y1228543D03*
X770472Y1236023D03*
Y1232283D03*
X781693D03*
X777953D03*
Y1236023D03*
X781693D03*
X770472Y1228543D03*
X781693D03*
X770472Y1224803D03*
X777953Y1228543D03*
X774212Y1232283D03*
Y1236023D03*
X781693Y1247243D03*
X777953D03*
X774212Y1250984D03*
Y1254724D03*
X770472Y1247243D03*
Y1243503D03*
Y1250984D03*
Y1254724D03*
X781693Y1250984D03*
X777953D03*
X774212Y1247243D03*
Y1243503D03*
X777953D03*
X781693D03*
X770472Y1239763D03*
X774212D03*
X777953Y1254724D03*
Y1239763D03*
X781693D03*
X777953Y1247243D03*
X770472Y1243503D03*
X781693Y1247243D03*
X770472D03*
X774212Y1250984D03*
Y1254724D03*
Y1258465D03*
X778808Y1348187D03*
X770928D03*
X778808Y1360099D03*
X770928D03*
X785434Y1090158D03*
Y1082677D03*
Y1101378D03*
Y1123819D03*
Y1116339D03*
Y1108859D03*
Y1131300D03*
Y1198621D03*
Y1221062D03*
Y1213582D03*
Y1206102D03*
Y1228543D03*
Y1247243D03*
Y1239762D03*
X920349Y450340D03*
X917549D03*
X920349Y453884D03*
Y457427D03*
X917549Y453884D03*
Y457427D03*
X920349Y460970D03*
X917549D03*
X962380Y617861D03*
X958837D03*
X962380Y620661D03*
X958837D03*
X969467D03*
X965923Y617861D03*
Y620661D03*
X969467Y617861D03*
X1057381Y1092027D03*
Y1084547D03*
Y1088287D03*
Y1095767D03*
Y1103247D03*
Y1106988D03*
Y1099507D03*
Y1118208D03*
Y1110728D03*
Y1114468D03*
Y1121948D03*
Y1140649D03*
Y1133169D03*
Y1125688D03*
Y1129429D03*
Y1136909D03*
Y1151870D03*
Y1144389D03*
Y1148129D03*
X1054881Y1170570D03*
X1057381Y1159350D03*
X1057380Y1170570D03*
X1059251Y1191141D03*
X1054881Y1178050D03*
X1059251Y1187401D03*
Y1183661D03*
X1057380Y1178051D03*
X1059251Y1198621D03*
Y1206102D03*
Y1194881D03*
Y1202362D03*
X1055510Y1198622D03*
Y1191142D03*
X1059251Y1198621D03*
Y1191141D03*
Y1221062D03*
Y1213582D03*
Y1209842D03*
Y1217322D03*
X1055510Y1221063D03*
Y1213583D03*
Y1206103D03*
X1059251Y1221062D03*
Y1206102D03*
Y1213582D03*
Y1228543D03*
Y1239763D03*
Y1232283D03*
Y1236023D03*
Y1224803D03*
X1055510Y1228542D03*
X1059251Y1228543D03*
Y1247243D03*
Y1243503D03*
Y1250984D03*
X1055509Y1239762D03*
Y1247242D03*
X1059251Y1247243D03*
Y1239763D03*
X1052473Y1348187D03*
Y1360099D03*
Y1384297D03*
Y1372385D03*
X1068602Y1073326D03*
X1072342D03*
X1064862D03*
X1072342Y1088287D03*
Y1084547D03*
Y1080807D03*
X1064861Y1077066D03*
X1061121Y1092027D03*
X1068602D03*
X1064862Y1088287D03*
X1068602D03*
X1061121Y1084547D03*
X1064862D03*
Y1080807D03*
X1061121Y1080806D03*
Y1077066D03*
X1068602D03*
X1064862Y1092027D03*
X1072342Y1077066D03*
X1068602Y1084547D03*
Y1080807D03*
X1061121Y1088287D03*
X1072342Y1092027D03*
Y1099507D03*
Y1106988D03*
Y1103247D03*
X1061121Y1095767D03*
X1068602D03*
X1064862Y1106988D03*
X1068602D03*
X1061121Y1103247D03*
X1064862D03*
Y1099507D03*
X1068602D03*
X1072342Y1095767D03*
X1061121Y1106988D03*
X1068602Y1103247D03*
X1064862Y1095767D03*
X1061121Y1099507D03*
X1072342Y1121948D03*
Y1118208D03*
Y1114468D03*
Y1110728D03*
X1064862Y1121948D03*
X1068602D03*
X1061121Y1118208D03*
X1064862Y1114468D03*
X1068602D03*
X1061121Y1110728D03*
Y1114468D03*
X1068602Y1110728D03*
Y1118208D03*
X1064862Y1110728D03*
Y1118208D03*
X1061121Y1121948D03*
X1072342Y1140649D03*
Y1129429D03*
Y1125688D03*
X1061121D03*
Y1140649D03*
X1064862D03*
X1068602D03*
X1064862Y1136909D03*
X1061121Y1133169D03*
X1064862Y1129429D03*
X1068602D03*
X1064862Y1125688D03*
X1068602D03*
X1061121Y1129429D03*
X1064862Y1133169D03*
X1061121Y1136909D03*
X1072342Y1155610D03*
Y1151869D03*
X1064862Y1155610D03*
X1068602D03*
X1061121Y1151870D03*
X1064862D03*
Y1148129D03*
X1068602Y1151869D03*
X1061121Y1144389D03*
X1064862D03*
X1061121Y1148129D03*
X1072342Y1166830D03*
X1064861Y1170570D03*
X1068602D03*
X1064861Y1166830D03*
X1068602D03*
X1061121Y1159350D03*
X1064862D03*
X1061122Y1166830D03*
X1061120Y1170570D03*
X1066732Y1187401D03*
X1070472D03*
X1077952D03*
X1062991Y1191141D03*
X1072342Y1181791D03*
Y1174310D03*
X1061120Y1181791D03*
X1064861D03*
X1068602D03*
Y1174310D03*
X1064861Y1178051D03*
X1061120Y1174310D03*
X1064861D03*
X1074212Y1187401D03*
X1062991D03*
Y1183661D03*
X1066732D03*
X1070472D03*
X1074212D03*
X1070472Y1187401D03*
X1066732D03*
X1072342Y1178051D03*
X1068602D03*
X1061120D03*
X1077952Y1202362D03*
Y1194881D03*
X1062991Y1198621D03*
X1070472Y1202362D03*
X1066732D03*
X1070472Y1194881D03*
X1066732D03*
X1062991Y1206102D03*
X1074212Y1191141D03*
Y1198621D03*
Y1194881D03*
Y1202362D03*
X1070472Y1191141D03*
X1066732D03*
X1070472Y1198621D03*
X1066732D03*
X1062991Y1194881D03*
Y1202362D03*
Y1198621D03*
X1066732Y1194881D03*
X1062991Y1191141D03*
X1070472Y1194881D03*
Y1202362D03*
X1066732D03*
X1062991Y1221062D03*
Y1213582D03*
X1070472Y1217322D03*
X1066732D03*
Y1209842D03*
X1070472D03*
X1077952D03*
Y1217322D03*
X1074212Y1206102D03*
X1066732D03*
X1070472D03*
X1074212Y1217322D03*
Y1209842D03*
Y1213582D03*
X1070472D03*
X1066732D03*
X1062991Y1209842D03*
Y1217322D03*
X1074212Y1221062D03*
X1066732D03*
X1070472D03*
Y1217322D03*
X1066732D03*
X1062991Y1221062D03*
Y1206102D03*
X1070472Y1209842D03*
X1062991Y1213582D03*
X1066732Y1209842D03*
X1074212Y1232283D03*
Y1236023D03*
X1077952Y1228543D03*
Y1224803D03*
X1062991Y1228543D03*
X1066732Y1236023D03*
Y1232283D03*
X1070472Y1228543D03*
Y1224803D03*
X1062991Y1239763D03*
X1070472Y1236023D03*
Y1232283D03*
X1066732Y1228543D03*
Y1224803D03*
X1074212D03*
Y1228543D03*
X1062991Y1236023D03*
Y1232283D03*
Y1224803D03*
X1070472Y1228543D03*
X1066732Y1236023D03*
Y1232283D03*
X1074212Y1236023D03*
Y1232283D03*
X1070472Y1224803D03*
X1062991Y1228543D03*
Y1247243D03*
X1070472Y1243503D03*
Y1247243D03*
X1066732Y1250984D03*
Y1254724D03*
X1074212D03*
Y1250984D03*
X1077952Y1247243D03*
Y1243503D03*
X1070472Y1250984D03*
Y1254724D03*
X1066732Y1247243D03*
X1074212D03*
X1066732Y1239763D03*
Y1243503D03*
X1070472Y1239763D03*
X1074212D03*
Y1243503D03*
X1062991Y1250984D03*
Y1254724D03*
Y1243503D03*
X1074212Y1250984D03*
X1066732Y1254724D03*
X1070472Y1247243D03*
X1074212Y1254724D03*
X1062991Y1247243D03*
X1070472Y1243503D03*
X1062991Y1239763D03*
X1066732Y1250984D03*
X1074212Y1258465D03*
X1066732D03*
X1072593Y1348187D03*
X1064713D03*
X1060353D03*
X1072593Y1360099D03*
X1064713D03*
X1060353D03*
X1072593Y1384297D03*
Y1372385D03*
X1064713D03*
Y1384297D03*
X1060353D03*
Y1372385D03*
X1072593Y1396583D03*
X1064713D03*
X1072593Y1408495D03*
X1064713D03*
X1089172Y1075196D03*
X1083562Y1073326D03*
X1076082D03*
X1089171Y1071455D03*
X1089172Y1075196D03*
X1079822Y1073326D03*
X1089172Y1078936D03*
X1092913Y1082677D03*
Y1086417D03*
X1089172Y1093897D03*
X1083562Y1092027D03*
Y1088287D03*
Y1077066D03*
X1079822Y1088287D03*
Y1084547D03*
Y1080807D03*
X1076082Y1092027D03*
Y1088287D03*
Y1077066D03*
X1089172Y1082677D03*
Y1086417D03*
Y1090157D03*
Y1078936D03*
X1079822Y1092027D03*
X1083562Y1084547D03*
X1079822Y1077066D03*
X1076082Y1084547D03*
Y1080807D03*
X1083562D03*
X1092913Y1105117D03*
Y1101376D03*
X1089172Y1097637D03*
D03*
Y1093897D03*
X1083562Y1099507D03*
Y1095767D03*
X1087302Y1106988D03*
X1079822D03*
X1083562D03*
X1079822Y1103247D03*
Y1099507D03*
X1076082Y1106988D03*
Y1095767D03*
X1089172Y1101377D03*
Y1105117D03*
X1076082Y1103247D03*
X1079822Y1095767D03*
X1076082Y1099507D03*
X1083562Y1103247D03*
Y1121948D03*
Y1118208D03*
X1087302D03*
X1079822Y1114468D03*
X1083562Y1110728D03*
X1087302D03*
X1091043D03*
Y1121948D03*
Y1118208D03*
Y1114468D03*
X1076082D03*
X1089172Y1108858D03*
X1079822Y1118208D03*
X1076082Y1121948D03*
Y1118208D03*
X1079822Y1110728D03*
X1083562Y1114468D03*
X1087302D03*
X1076082Y1110728D03*
X1091043Y1125688D03*
Y1140649D03*
X1083562Y1136909D03*
X1087302D03*
X1079822Y1129429D03*
X1083562Y1129428D03*
X1087302D03*
X1079822Y1140649D03*
X1083562D03*
X1087302D03*
X1091043Y1136909D03*
Y1133169D03*
Y1129429D03*
X1076082Y1133169D03*
Y1129429D03*
Y1125688D03*
Y1140649D03*
X1087302Y1151870D03*
Y1155610D03*
Y1148129D03*
X1083562Y1144389D03*
X1087302D03*
X1076082Y1155610D03*
Y1151870D03*
Y1148129D03*
Y1144389D03*
X1091043Y1151870D03*
Y1148129D03*
Y1144389D03*
X1083562Y1148129D03*
X1079822Y1144389D03*
Y1148129D03*
X1083562Y1151870D03*
X1079822Y1155610D03*
X1087302Y1170570D03*
Y1166830D03*
Y1159350D03*
X1079822Y1170570D03*
Y1166830D03*
X1091043Y1170570D03*
X1076082Y1159350D03*
X1091043Y1166830D03*
Y1159350D03*
X1083562D03*
X1081692Y1187401D03*
X1085432Y1191141D03*
X1089172D03*
X1079822Y1174310D03*
Y1178050D03*
X1081692Y1179921D03*
X1083562Y1181791D03*
X1087302D03*
Y1178051D03*
Y1174310D03*
X1076082Y1181791D03*
Y1178051D03*
Y1174310D03*
X1077952Y1183661D03*
X1081692D03*
X1085432D03*
X1089172Y1187401D03*
X1085432D03*
X1091043Y1185531D03*
X1077952Y1187401D03*
X1081692D03*
X1091043Y1181791D03*
Y1178051D03*
Y1174310D03*
X1089172Y1198621D03*
X1085432D03*
X1081692Y1202362D03*
Y1194881D03*
X1089172Y1206102D03*
X1085432D03*
X1077952Y1191141D03*
Y1198621D03*
X1081692D03*
Y1191141D03*
X1085432Y1194881D03*
X1089172D03*
X1085432Y1202362D03*
X1089172D03*
X1077952Y1194881D03*
Y1202362D03*
X1089172Y1191141D03*
Y1198621D03*
X1081692Y1202362D03*
X1085432Y1198621D03*
X1081692Y1194881D03*
X1085432Y1191141D03*
X1089172Y1213582D03*
X1085432D03*
X1081692Y1209842D03*
Y1217322D03*
X1077952Y1206102D03*
Y1213582D03*
X1081692Y1206102D03*
Y1213582D03*
X1085432Y1209842D03*
X1089172D03*
X1077952Y1221062D03*
X1089172Y1217322D03*
Y1221062D03*
X1081692D03*
X1085432D03*
Y1217322D03*
X1089172Y1206102D03*
X1077952Y1209842D03*
X1081692D03*
Y1217322D03*
X1089172Y1213582D03*
X1077952Y1217322D03*
X1085432Y1206102D03*
Y1213582D03*
X1092913Y1228543D03*
Y1224803D03*
X1089172Y1236023D03*
Y1232283D03*
X1085432Y1228543D03*
Y1224803D03*
X1081692Y1236023D03*
Y1232283D03*
X1077952D03*
Y1236023D03*
X1085432Y1232283D03*
Y1236023D03*
X1081692Y1228543D03*
Y1224803D03*
X1089172D03*
Y1228543D03*
Y1232283D03*
X1081692D03*
Y1236023D03*
X1089172D03*
X1077952Y1224803D03*
Y1228543D03*
X1085432Y1224803D03*
Y1228543D03*
Y1243503D03*
Y1247243D03*
X1081692Y1250984D03*
Y1254724D03*
X1089172D03*
Y1250984D03*
X1092913Y1247243D03*
Y1243503D03*
X1077952Y1250984D03*
Y1254724D03*
Y1239763D03*
X1081692Y1247243D03*
X1085432Y1254724D03*
X1081692Y1239763D03*
Y1243503D03*
X1085432Y1250984D03*
Y1239763D03*
X1089172D03*
Y1243503D03*
Y1247243D03*
X1077952Y1243503D03*
X1081692Y1250984D03*
X1077952Y1247243D03*
X1081692Y1254724D03*
X1085432Y1243503D03*
X1089172Y1254724D03*
Y1250984D03*
X1085432Y1247243D03*
X1089173Y1258465D03*
X1081692D03*
X1089193Y1348187D03*
X1084833D03*
X1076953D03*
X1089193Y1360099D03*
X1084833D03*
X1076953D03*
X1089193Y1384297D03*
Y1372385D03*
X1084833Y1384297D03*
Y1372385D03*
X1076953Y1384297D03*
Y1372385D03*
X1089193Y1396583D03*
X1084833D03*
X1076953D03*
X1089193Y1408495D03*
X1084833D03*
X1076953D03*
X1096653Y1075196D03*
X1104133D03*
X1092913D03*
X1107873D03*
X1100393D03*
X1104132Y1071455D03*
X1096652D03*
X1096653Y1075196D03*
X1104133D03*
X1096653Y1078936D03*
X1100393Y1082677D03*
Y1086417D03*
X1107873D03*
Y1082677D03*
X1104133Y1078936D03*
X1096653Y1093897D03*
X1104133D03*
X1092913Y1078936D03*
Y1090157D03*
X1104133Y1086417D03*
Y1090157D03*
Y1082677D03*
X1107873Y1090157D03*
Y1078936D03*
X1100393D03*
Y1090157D03*
X1096653Y1082677D03*
Y1086417D03*
Y1090157D03*
X1100393Y1082677D03*
X1104133Y1078936D03*
X1107873Y1082677D03*
Y1086417D03*
X1092913Y1082677D03*
X1100393Y1086417D03*
X1092913D03*
X1096653Y1078936D03*
X1107873Y1105117D03*
Y1101376D03*
X1100393Y1105117D03*
X1096653Y1097637D03*
X1100393Y1101376D03*
X1104133Y1097637D03*
X1092913Y1105117D03*
X1104133Y1097637D03*
X1096653D03*
X1100393Y1105117D03*
X1104133Y1093897D03*
X1100393Y1101376D03*
X1096653Y1093897D03*
X1092913Y1101376D03*
X1107873Y1105117D03*
X1092913Y1093897D03*
Y1097637D03*
X1107873Y1093897D03*
Y1097637D03*
X1104133Y1101377D03*
X1100393Y1097637D03*
Y1093897D03*
X1096653Y1101377D03*
X1104133Y1105117D03*
X1096653D03*
X1107873Y1101376D03*
X1094783Y1110728D03*
Y1121948D03*
X1098523D03*
X1102263D03*
X1106003D03*
X1094783Y1118208D03*
X1098523D03*
X1102263D03*
X1106003D03*
X1094783Y1114468D03*
X1107873Y1108858D03*
X1104133D03*
X1100393D03*
X1096653D03*
X1092913D03*
X1102263Y1114468D03*
X1098523D03*
X1106003D03*
X1098523Y1140649D03*
X1102263D03*
X1094783Y1136909D03*
X1102263D03*
X1094783Y1133169D03*
X1098523D03*
X1102263D03*
X1094783Y1129429D03*
X1098523D03*
X1102263D03*
X1094783Y1125688D03*
X1098523D03*
X1102263D03*
X1106003D03*
X1094783Y1140649D03*
X1106003D03*
Y1136909D03*
X1098523D03*
X1106003Y1129429D03*
Y1133169D03*
X1094783Y1151870D03*
Y1155610D03*
X1102263Y1151870D03*
X1094783Y1148129D03*
Y1144389D03*
X1102263D03*
X1106003Y1148129D03*
Y1155610D03*
Y1151869D03*
Y1144389D03*
X1098523D03*
Y1151870D03*
X1102263Y1148129D03*
Y1155610D03*
Y1170570D03*
X1094783D03*
Y1159350D03*
X1102263D03*
X1094783Y1166830D03*
X1106003D03*
Y1170570D03*
Y1159350D03*
X1102263Y1166830D03*
X1098523Y1159350D03*
Y1170570D03*
X1102263Y1178051D03*
X1094783Y1181791D03*
X1102263Y1185531D03*
X1094783Y1174310D03*
Y1178051D03*
X1106003Y1181791D03*
Y1174310D03*
X1092913Y1187401D03*
X1106003Y1178051D03*
Y1185531D03*
X1098523D03*
X1102263Y1174310D03*
X1098523Y1178051D03*
X1102263Y1181791D03*
X1098523Y1196751D03*
Y1193011D03*
X1106003Y1200491D03*
Y1196751D03*
Y1204232D03*
X1102263D03*
X1098523D03*
Y1200491D03*
X1102263D03*
Y1196751D03*
Y1193011D03*
X1092913Y1191141D03*
Y1194881D03*
Y1198621D03*
Y1202362D03*
X1106003Y1193011D03*
X1098523Y1207972D03*
X1102263D03*
X1106003D03*
Y1211712D03*
X1102263D03*
X1098523D03*
Y1219192D03*
X1106003D03*
X1092913Y1206102D03*
Y1209842D03*
Y1213582D03*
Y1217322D03*
X1107873Y1221062D03*
X1104133D03*
X1100393D03*
X1096653D03*
X1092913D03*
X1106003Y1215452D03*
X1098523D03*
X1102263D03*
X1107873Y1224803D03*
Y1228543D03*
X1096653Y1236023D03*
Y1232283D03*
X1104133D03*
Y1236023D03*
X1100393Y1228543D03*
Y1224803D03*
X1092913Y1232283D03*
Y1236023D03*
X1107873Y1232283D03*
X1104133Y1224803D03*
Y1228543D03*
X1107873Y1236023D03*
X1100393Y1232283D03*
Y1236023D03*
X1096653Y1228543D03*
Y1224803D03*
X1100393Y1228543D03*
X1104133Y1236023D03*
X1092913Y1224803D03*
X1104133Y1232283D03*
X1107873Y1224803D03*
X1096653Y1236023D03*
X1100393Y1224803D03*
X1107873Y1228543D03*
X1096653Y1232283D03*
X1092913Y1228543D03*
X1096653Y1254724D03*
Y1250984D03*
X1107873Y1243503D03*
Y1247243D03*
X1104133Y1250984D03*
Y1254724D03*
X1100393Y1247243D03*
Y1243503D03*
X1092913Y1250984D03*
Y1254724D03*
Y1239763D03*
X1100393Y1250984D03*
Y1254724D03*
X1104133Y1247243D03*
X1107873Y1250984D03*
Y1254724D03*
X1100393Y1239763D03*
X1104133D03*
X1107873D03*
X1104133Y1243503D03*
X1096653Y1247243D03*
Y1239763D03*
Y1243503D03*
Y1254724D03*
X1104133D03*
X1092913Y1247243D03*
X1096653Y1250984D03*
X1092913Y1243503D03*
X1107873D03*
X1100393D03*
X1107873Y1247243D03*
X1100393D03*
X1104133Y1250984D03*
Y1258465D03*
X1096653D03*
X1101433Y1348187D03*
X1097073D03*
X1101433Y1360099D03*
X1097073D03*
X1101433Y1384297D03*
Y1372385D03*
X1097073D03*
Y1384297D03*
X1101433Y1396583D03*
X1097073D03*
X1101433Y1408495D03*
X1097073D03*
X1126574Y1075196D03*
X1111613D03*
X1119094D03*
X1115354D03*
X1122834D03*
X1119093Y1071455D03*
X1111612D03*
X1111613Y1075196D03*
X1119094D03*
X1111613Y1078936D03*
X1115354Y1082677D03*
Y1086417D03*
X1119094Y1078936D03*
X1122834Y1082677D03*
Y1086417D03*
X1126574Y1078936D03*
Y1093897D03*
X1111613D03*
X1119094D03*
X1115354Y1090157D03*
Y1078936D03*
X1119094Y1082677D03*
Y1086417D03*
Y1090157D03*
X1122834D03*
Y1078936D03*
X1111613Y1082677D03*
Y1086417D03*
Y1090157D03*
X1122834Y1086417D03*
X1119094Y1078936D03*
X1115354Y1082677D03*
X1111613Y1078936D03*
X1115354Y1086417D03*
X1122834Y1082677D03*
Y1105117D03*
Y1101376D03*
X1126574Y1097637D03*
X1115354Y1105117D03*
X1111613Y1097637D03*
X1115354Y1101376D03*
X1119094Y1097637D03*
D03*
X1115354Y1101376D03*
X1111613Y1093897D03*
Y1097637D03*
X1122834Y1105117D03*
X1119094Y1093897D03*
X1122834D03*
X1115354D03*
X1122834Y1097637D03*
X1115354D03*
X1119094Y1101377D03*
X1111613D03*
X1119094Y1105117D03*
X1111613D03*
X1122834Y1101376D03*
X1115354Y1105117D03*
X1117224Y1121948D03*
Y1118208D03*
X1120964D03*
X1109743Y1121948D03*
X1113484D03*
X1109743Y1118208D03*
X1113484D03*
X1124704Y1121948D03*
Y1118208D03*
X1120964Y1121948D03*
X1122834Y1108858D03*
X1119094D03*
X1115354D03*
X1111613D03*
X1117224Y1114468D03*
X1113484D03*
X1120964D03*
X1124704D03*
X1109743D03*
Y1136909D03*
X1124704Y1125688D03*
Y1140649D03*
Y1133169D03*
X1113484D03*
X1117224D03*
X1120964D03*
X1109743Y1125688D03*
X1120964D03*
X1117224D03*
X1113484D03*
X1120964Y1140649D03*
X1117224D03*
X1113484D03*
X1109743Y1129429D03*
Y1133169D03*
X1120964Y1129429D03*
X1113484D03*
X1117224D03*
X1124704D03*
Y1136909D03*
X1113484D03*
X1117224D03*
X1120964D03*
X1109743Y1140649D03*
X1113484Y1155610D03*
X1109743Y1144389D03*
X1120964Y1155610D03*
X1109743Y1151869D03*
X1120964Y1148129D03*
X1113484D03*
X1117224D03*
X1124704D03*
Y1144389D03*
X1113484D03*
X1117224D03*
X1120964D03*
X1113484Y1151870D03*
X1117224D03*
X1120964D03*
X1124704D03*
Y1155610D03*
X1109743D03*
Y1148129D03*
X1117224Y1155610D03*
Y1170570D03*
X1109743D03*
X1113484Y1166830D03*
X1117224Y1159350D03*
X1120964Y1166830D03*
X1109743Y1159350D03*
X1124704Y1170570D03*
Y1159350D03*
X1113484D03*
X1120964D03*
X1109743Y1166830D03*
X1113484Y1170570D03*
X1117224Y1166830D03*
X1120964Y1170570D03*
X1124704Y1166830D03*
X1109743Y1189271D03*
X1113484D03*
X1117224D03*
X1120964D03*
X1113484Y1181791D03*
X1117224D03*
X1120964D03*
X1124704Y1189271D03*
Y1181791D03*
X1109743Y1178051D03*
X1120964Y1174310D03*
X1109743Y1185531D03*
X1113484Y1174310D03*
Y1178051D03*
X1117224D03*
X1120964D03*
X1124704D03*
X1120964Y1185531D03*
X1113484D03*
X1117224D03*
X1124704D03*
X1109743Y1174310D03*
Y1181791D03*
X1117224Y1174310D03*
X1124704D03*
Y1204232D03*
Y1196751D03*
X1120964Y1204232D03*
X1117224D03*
X1113484D03*
X1109743D03*
Y1193011D03*
Y1196751D03*
Y1200491D03*
X1113484Y1196751D03*
X1117224D03*
X1120964D03*
X1117224Y1200491D03*
X1120964D03*
X1113484D03*
X1124704D03*
X1120964Y1193011D03*
X1117224D03*
X1113484D03*
X1124704D03*
X1113484Y1207972D03*
X1117224D03*
X1120964D03*
X1109743Y1211712D03*
Y1207972D03*
X1124704Y1211712D03*
Y1207972D03*
X1122834Y1221062D03*
X1119094D03*
X1115354D03*
X1111613D03*
X1124704Y1215452D03*
X1120964D03*
Y1211712D03*
X1117224Y1215452D03*
X1109743D03*
X1113484Y1211712D03*
X1111613Y1217322D03*
X1115354D03*
X1117224Y1211712D03*
X1126574Y1236023D03*
Y1232283D03*
X1122834Y1224803D03*
Y1228543D03*
X1111613Y1236023D03*
Y1232283D03*
X1119094D03*
Y1236023D03*
X1115354Y1228543D03*
Y1224803D03*
X1122834D03*
Y1232283D03*
Y1236023D03*
X1119094Y1224803D03*
Y1228543D03*
X1115354Y1232283D03*
Y1236023D03*
X1111613Y1228543D03*
Y1224803D03*
X1119094Y1232283D03*
X1115354Y1228543D03*
X1111613Y1232283D03*
X1119094Y1236023D03*
X1115354Y1224803D03*
X1111613Y1236023D03*
X1122834Y1228543D03*
X1111613Y1254724D03*
Y1250984D03*
X1122834Y1243503D03*
Y1247243D03*
X1119094Y1250984D03*
Y1254724D03*
X1115354Y1247243D03*
Y1243503D03*
X1126574Y1254724D03*
Y1250984D03*
X1115354D03*
Y1254724D03*
X1119094Y1247243D03*
Y1243503D03*
X1122834Y1254724D03*
Y1250984D03*
Y1239763D03*
X1115354D03*
X1119094D03*
X1111613Y1247243D03*
Y1243503D03*
Y1239763D03*
X1122834Y1243503D03*
X1119094Y1250984D03*
X1111613Y1254724D03*
X1119094D03*
X1122834Y1247243D03*
X1115354Y1243503D03*
Y1247243D03*
X1111613Y1250984D03*
X1119094Y1258465D03*
X1111614D03*
X1113673Y1348187D03*
X1121553D03*
X1109313D03*
X1113673Y1360099D03*
X1121553D03*
X1109313D03*
X1113673Y1372385D03*
Y1384297D03*
X1121553Y1372385D03*
Y1384297D03*
X1109313D03*
Y1372385D03*
X1113673Y1396583D03*
X1121553D03*
X1109313D03*
X1113673Y1408495D03*
X1121553D03*
X1109313D03*
X1141535Y1075196D03*
X1134054D03*
X1130314D03*
X1137795D03*
X1134053Y1071455D03*
X1126573D03*
X1126574Y1075196D03*
X1134054D03*
X1130314Y1086417D03*
Y1082677D03*
X1134054Y1078936D03*
X1137795Y1082677D03*
Y1086417D03*
X1141535Y1078936D03*
Y1093897D03*
X1134054D03*
X1126574Y1090157D03*
Y1086417D03*
Y1082677D03*
X1130314Y1090157D03*
Y1078936D03*
X1134054Y1082677D03*
Y1086417D03*
Y1090157D03*
X1137795D03*
Y1078936D03*
X1134054D03*
X1126574D03*
X1130314Y1086417D03*
Y1082677D03*
X1137795Y1086417D03*
Y1082677D03*
X1141535Y1097637D03*
X1130314Y1105117D03*
X1137794D03*
X1130314Y1101376D03*
X1137794D03*
X1134054Y1097637D03*
X1126574Y1093897D03*
X1130314Y1105117D03*
X1134054Y1093897D03*
X1130314Y1101376D03*
X1134054Y1097637D03*
X1137794Y1105117D03*
X1126574Y1097637D03*
X1137794Y1101376D03*
X1126574Y1101377D03*
X1130314Y1097637D03*
Y1093897D03*
X1137795D03*
Y1097637D03*
X1134054Y1101377D03*
X1126574Y1105117D03*
X1134054D03*
X1139665Y1121948D03*
X1128444Y1114468D03*
X1130314Y1112598D03*
X1128444Y1118208D03*
X1132184D03*
X1135924D03*
X1132184Y1121948D03*
X1135924D03*
X1128444D03*
X1139665Y1118208D03*
X1137795Y1108858D03*
X1134054D03*
X1130314D03*
X1126574D03*
X1139665Y1114468D03*
X1135925D03*
X1132184D03*
X1139665Y1125688D03*
X1128444Y1140649D03*
X1132184D03*
X1135924D03*
X1132184Y1125688D03*
X1128444D03*
X1135924D03*
Y1133169D03*
X1132184D03*
X1128444D03*
X1139665D03*
Y1140649D03*
X1132184Y1129429D03*
X1128444D03*
X1135924D03*
X1139665D03*
Y1136909D03*
X1135924D03*
X1132184D03*
X1128444D03*
X1135924Y1148129D03*
X1132184D03*
X1128444D03*
X1139665D03*
X1128444Y1155610D03*
X1135924D03*
X1128444Y1144389D03*
X1135924D03*
X1132184D03*
X1139665D03*
X1135925Y1151870D03*
X1132184D03*
X1128444D03*
X1139665D03*
Y1155610D03*
X1132184D03*
X1139665Y1170570D03*
Y1159350D03*
X1132184Y1170570D03*
X1135925Y1166830D03*
X1128444D03*
X1132184Y1159350D03*
X1139665Y1166830D03*
X1135924Y1170570D03*
X1128444D03*
X1132184Y1166830D03*
X1128444Y1159350D03*
X1135924D03*
Y1181791D03*
X1132184D03*
X1128444D03*
X1135924Y1189271D03*
X1132184D03*
X1128444D03*
Y1174310D03*
X1135924D03*
X1139665Y1181791D03*
Y1189271D03*
Y1178051D03*
X1135924D03*
X1132184D03*
X1128444D03*
X1139665Y1185531D03*
X1132184D03*
X1128444D03*
X1135924D03*
X1139665Y1174310D03*
X1132184D03*
X1139665Y1196751D03*
Y1204232D03*
X1135924D03*
Y1196751D03*
X1132184D03*
X1128444D03*
Y1204232D03*
X1132184D03*
Y1200491D03*
X1128444D03*
X1135924D03*
X1139665D03*
X1128444Y1193011D03*
X1132184D03*
X1135924D03*
X1139665D03*
Y1207972D03*
X1132184Y1211712D03*
X1134054Y1217322D03*
X1135924Y1207972D03*
X1132184D03*
X1128444D03*
X1137795Y1221062D03*
X1134054D03*
X1130314D03*
X1126574D03*
X1139665Y1211712D03*
X1135925D03*
Y1215452D03*
X1128444D03*
X1132184D03*
X1128444Y1211712D03*
X1141535Y1232283D03*
Y1236023D03*
X1137795Y1224803D03*
Y1228543D03*
X1134054Y1232283D03*
Y1236023D03*
X1130314Y1228543D03*
Y1224803D03*
X1126574D03*
Y1228543D03*
X1137795Y1232283D03*
Y1236023D03*
X1134054Y1228543D03*
Y1224803D03*
X1130314Y1232283D03*
Y1236023D03*
X1134054D03*
X1137795Y1228543D03*
X1134054Y1232283D03*
X1126574D03*
Y1236023D03*
X1137795Y1224803D03*
X1130314Y1228543D03*
Y1224803D03*
X1137795Y1243503D03*
Y1247243D03*
X1134054Y1250984D03*
Y1254724D03*
X1130314Y1247243D03*
Y1243503D03*
X1141535Y1254724D03*
Y1250984D03*
X1126574Y1243503D03*
Y1247243D03*
Y1239763D03*
X1130314Y1250984D03*
Y1254724D03*
X1134054Y1247243D03*
Y1243503D03*
X1137795Y1250984D03*
Y1254724D03*
Y1239763D03*
X1134054D03*
X1130314D03*
X1126574Y1254724D03*
X1137795Y1243503D03*
X1130314Y1247243D03*
X1126574Y1250984D03*
X1137795Y1247243D03*
X1130314Y1243503D03*
X1134054Y1250984D03*
Y1254724D03*
X1134055Y1258465D03*
X1126574D03*
X1138153Y1348187D03*
X1133793D03*
X1125913D03*
X1138153Y1360099D03*
X1133793D03*
X1125913D03*
X1138153Y1384297D03*
Y1372385D03*
X1133793Y1384297D03*
Y1372385D03*
X1125913Y1384297D03*
Y1372385D03*
X1138153Y1396583D03*
X1133793D03*
X1125913D03*
X1138153Y1408495D03*
X1133793D03*
X1125913D03*
X1156494Y1075196D03*
X1149014Y1075195D03*
X1152755Y1075196D03*
X1145275D03*
X1156494Y1071455D03*
X1149014Y1071454D03*
X1141534Y1071455D03*
X1141535Y1075196D03*
X1156494D03*
X1149014Y1075195D03*
X1145275Y1082677D03*
Y1086417D03*
X1156494Y1078936D03*
X1152754Y1082676D03*
Y1086416D03*
X1149014Y1078935D03*
X1156494Y1093897D03*
X1149014D03*
X1141535Y1082677D03*
Y1086417D03*
Y1090157D03*
X1149015Y1082677D03*
Y1086417D03*
X1152755Y1090157D03*
X1156495D03*
Y1086417D03*
X1149015Y1090157D03*
X1152755Y1078936D03*
X1156495Y1082677D03*
X1145275Y1090157D03*
Y1078936D03*
Y1086417D03*
Y1082677D03*
X1141535Y1078936D03*
X1149014Y1078935D03*
X1156494Y1078936D03*
X1152754Y1086416D03*
Y1082676D03*
X1156494Y1097637D03*
X1145275Y1105117D03*
X1152755D03*
X1145275Y1101376D03*
X1149014Y1097637D03*
X1152755Y1101376D03*
X1145275Y1105117D03*
X1141535Y1093897D03*
X1145275Y1101376D03*
X1141535Y1097637D03*
Y1101377D03*
X1149015D03*
X1152755Y1093897D03*
Y1097637D03*
X1156495Y1101377D03*
X1145275Y1093897D03*
Y1097637D03*
X1141535Y1105117D03*
X1149015D03*
X1156495D03*
X1149014Y1097637D03*
X1156494Y1093897D03*
X1152755Y1101376D03*
X1156494Y1097637D03*
X1149014Y1093897D03*
X1152755Y1105117D03*
X1150885Y1121948D03*
X1143405D03*
Y1118208D03*
Y1114468D03*
X1154625Y1121948D03*
X1156495Y1108858D03*
X1152755D03*
X1149015D03*
X1145275D03*
X1141535D03*
X1154625Y1118208D03*
X1150885D03*
X1154625Y1114468D03*
X1150885D03*
X1154625Y1125688D03*
X1150885Y1133464D03*
X1154625Y1133169D03*
X1143503Y1132677D03*
X1143405Y1140649D03*
Y1125688D03*
X1150885Y1140649D03*
X1154625D03*
X1150885Y1125688D03*
X1154625Y1129429D03*
X1150885D03*
X1143405D03*
Y1136909D03*
X1154625D03*
X1150885D03*
X1143405Y1148129D03*
X1150885D03*
X1154625D03*
X1143405Y1155610D03*
X1154625D03*
X1143405Y1144389D03*
X1150885Y1151869D03*
X1154625D03*
Y1144389D03*
X1150885D03*
X1143405Y1151870D03*
X1150885Y1155610D03*
X1154625Y1166830D03*
X1150885Y1170570D03*
X1143405Y1166830D03*
X1150885Y1159350D03*
X1143405Y1170570D03*
X1154625Y1159350D03*
X1143405D03*
X1150885Y1166830D03*
X1154625Y1170570D03*
X1143405Y1181791D03*
X1154625D03*
X1150885D03*
Y1189271D03*
X1154625D03*
X1143405D03*
Y1174310D03*
X1154625D03*
X1143405Y1178051D03*
Y1185531D03*
X1154625D03*
X1150885D03*
X1154625Y1178051D03*
X1150885D03*
Y1174310D03*
Y1196751D03*
X1154625Y1204232D03*
X1150885D03*
X1154625Y1196751D03*
X1143405D03*
Y1204232D03*
Y1200491D03*
X1154625D03*
X1150885D03*
Y1193011D03*
X1154625D03*
X1143405D03*
X1150885Y1207972D03*
X1154625D03*
Y1211712D03*
X1143405Y1207972D03*
X1149015Y1221062D03*
X1156495D03*
X1152755D03*
X1145275D03*
X1141535D03*
X1143405Y1211712D03*
Y1215452D03*
X1150885Y1211712D03*
Y1215452D03*
X1154625D03*
X1156495Y1217322D03*
X1152755D03*
X1156495Y1236023D03*
Y1232283D03*
X1145275Y1228543D03*
Y1224803D03*
X1152755Y1228543D03*
Y1224803D03*
X1149015Y1232283D03*
Y1236023D03*
D03*
Y1232283D03*
X1152755Y1228543D03*
X1145275Y1224803D03*
X1156495Y1232283D03*
Y1236023D03*
X1141535Y1228543D03*
Y1224803D03*
X1152755Y1232283D03*
Y1236023D03*
X1156495Y1228543D03*
Y1224803D03*
X1149015Y1228543D03*
Y1224803D03*
X1145275Y1232283D03*
Y1236023D03*
X1141535D03*
X1145275Y1228543D03*
X1152755Y1224803D03*
X1141535Y1232283D03*
X1145275Y1247243D03*
Y1243503D03*
X1156495Y1254724D03*
Y1250984D03*
X1152755Y1243503D03*
Y1247243D03*
X1149015Y1250984D03*
Y1254724D03*
X1141535Y1239763D03*
Y1243503D03*
Y1247243D03*
X1152755Y1254724D03*
Y1250984D03*
X1149015Y1247243D03*
Y1243503D03*
Y1239763D03*
X1152755D03*
X1156495D03*
Y1243503D03*
Y1247243D03*
X1145275Y1239763D03*
Y1250984D03*
Y1254724D03*
X1141535D03*
Y1250984D03*
X1149015Y1254724D03*
X1145275Y1247243D03*
X1152755Y1243503D03*
X1156495Y1254724D03*
X1145275Y1243503D03*
X1152755Y1247243D03*
X1149015Y1250984D03*
X1156495D03*
Y1258465D03*
X1149015D03*
X1141536D03*
X1150393Y1348187D03*
X1146033D03*
X1150393Y1360099D03*
X1146033D03*
X1150393Y1384297D03*
Y1372385D03*
X1146033D03*
Y1384297D03*
X1150393Y1396583D03*
X1146033D03*
X1150393Y1408495D03*
X1146033D03*
X1171455Y1075196D03*
X1163975D03*
X1167716D03*
X1160235D03*
X1171455Y1071455D03*
X1163975D03*
Y1075196D03*
X1171455D03*
X1160234Y1082677D03*
Y1086417D03*
X1171455Y1078936D03*
X1167715Y1082676D03*
Y1086416D03*
X1163975Y1078936D03*
X1175195Y1086417D03*
Y1082677D03*
X1171455Y1093897D03*
X1163975D03*
X1167716Y1078936D03*
X1163976Y1082677D03*
Y1086417D03*
Y1090157D03*
X1171456Y1082677D03*
Y1086417D03*
Y1090157D03*
X1167716D03*
X1160235Y1078936D03*
Y1090157D03*
X1160234Y1086417D03*
X1167715Y1086416D03*
X1163975Y1078936D03*
X1160234Y1082677D03*
X1171455Y1078936D03*
X1167715Y1082676D03*
X1175196Y1105117D03*
X1171455Y1097637D03*
X1175196Y1101376D03*
X1160235Y1105117D03*
X1167716D03*
X1160235Y1101376D03*
X1163975Y1097637D03*
X1167716Y1101376D03*
X1163976Y1101377D03*
X1171456D03*
X1167716Y1097637D03*
Y1093897D03*
X1160235D03*
Y1097637D03*
X1163976Y1105117D03*
X1171456D03*
X1160235D03*
Y1101376D03*
X1171455Y1093897D03*
X1167716Y1105117D03*
X1171455Y1097637D03*
X1163975Y1093897D03*
Y1097637D03*
X1167716Y1101376D03*
X1169586Y1121948D03*
X1165846D03*
X1162106D03*
X1158365D03*
X1173326D03*
X1171456Y1108858D03*
X1167716D03*
X1163976D03*
X1160235D03*
X1162106Y1114468D03*
X1169586D03*
X1162106Y1118208D03*
X1173326Y1114468D03*
X1158365Y1118208D03*
X1173326D03*
X1165846Y1114468D03*
X1158365D03*
X1169586Y1118208D03*
X1165846D03*
X1162106Y1133169D03*
X1165846D03*
X1169586D03*
X1158365Y1140649D03*
X1162106D03*
X1165846D03*
X1169586D03*
X1158365Y1125688D03*
X1162106D03*
X1165846D03*
X1169586D03*
X1173326Y1133169D03*
Y1125688D03*
Y1140649D03*
X1158365Y1133169D03*
X1169586Y1129429D03*
X1165846D03*
X1162106D03*
X1158365D03*
X1173326D03*
Y1136909D03*
X1169586D03*
X1165846D03*
X1158365D03*
X1162106D03*
X1173326Y1148129D03*
X1158365D03*
X1162106D03*
X1165846D03*
X1169586D03*
X1162106Y1155610D03*
X1169586D03*
X1173326Y1151869D03*
X1158365D03*
X1162106D03*
X1169586D03*
X1165846D03*
X1173326Y1144389D03*
X1165846D03*
X1158365D03*
X1162106D03*
X1169586D03*
X1173326Y1155610D03*
X1165846D03*
X1158365D03*
Y1170570D03*
X1165846D03*
X1169586Y1166830D03*
X1158365Y1159350D03*
X1162106Y1166830D03*
X1165846Y1159350D03*
X1173326D03*
Y1170570D03*
Y1166830D03*
X1165846D03*
X1169586Y1170570D03*
X1158365Y1166830D03*
X1162106Y1170570D03*
X1169586Y1159350D03*
X1162106D03*
X1173326Y1189271D03*
X1158365Y1181791D03*
X1162106D03*
X1165846D03*
X1169586D03*
X1158365Y1189271D03*
X1162106D03*
X1165846D03*
X1169586D03*
X1173326Y1181791D03*
X1169586Y1174310D03*
X1162106D03*
X1158365Y1185531D03*
X1162106D03*
X1169586D03*
X1165846D03*
X1173326D03*
X1165846Y1178051D03*
X1158365D03*
X1162106D03*
X1169586D03*
X1173326D03*
X1165846Y1174310D03*
X1158365D03*
X1173326D03*
X1162106Y1204232D03*
X1158365D03*
X1169586D03*
X1165846D03*
X1158365Y1196751D03*
X1162106D03*
X1165846D03*
X1169586D03*
X1173326Y1204232D03*
Y1196751D03*
Y1200491D03*
X1165846D03*
X1162106D03*
X1158365D03*
X1169586D03*
X1165846Y1193011D03*
X1169586D03*
X1158365D03*
X1162106D03*
X1173326D03*
X1158365Y1211712D03*
Y1207972D03*
X1173326D03*
Y1211712D03*
X1162106Y1207972D03*
X1165846D03*
X1169586Y1211712D03*
Y1207972D03*
X1171456Y1221062D03*
X1167716D03*
X1163976D03*
X1160235D03*
X1173326Y1215452D03*
X1165846D03*
X1169586D03*
X1162105Y1215451D03*
X1158365Y1215452D03*
X1162105Y1211711D03*
X1165846D03*
X1171456Y1236023D03*
Y1232283D03*
X1175196Y1228543D03*
Y1224803D03*
X1160235Y1228543D03*
Y1224803D03*
X1167716D03*
Y1228543D03*
X1163976Y1232283D03*
Y1236023D03*
X1160235Y1224803D03*
X1163976Y1232283D03*
X1167716Y1224803D03*
X1160235Y1228543D03*
X1171456Y1232283D03*
X1163976Y1236023D03*
Y1228543D03*
Y1224803D03*
X1171456Y1228543D03*
Y1224803D03*
X1167716Y1232283D03*
Y1236023D03*
X1160235Y1232283D03*
Y1236023D03*
X1171456D03*
X1167716Y1228543D03*
X1160235Y1243503D03*
Y1247243D03*
X1171456Y1254724D03*
Y1250984D03*
X1167716Y1247243D03*
Y1243503D03*
X1163976Y1250984D03*
Y1254724D03*
X1175196Y1243503D03*
Y1247243D03*
X1163976Y1239763D03*
Y1243503D03*
Y1247243D03*
X1167716Y1239763D03*
Y1250984D03*
Y1254724D03*
X1171456Y1247243D03*
Y1243503D03*
Y1239763D03*
X1160235D03*
Y1250984D03*
Y1254724D03*
X1171456Y1250984D03*
X1167716Y1247243D03*
X1163976Y1250984D03*
X1160235Y1247243D03*
Y1243503D03*
X1167716D03*
X1171456Y1254724D03*
X1163976D03*
X1171456Y1258465D03*
X1163976D03*
X1162633Y1348187D03*
X1170513D03*
X1158273D03*
X1162633Y1360099D03*
X1170513D03*
X1158273D03*
X1162633Y1372385D03*
Y1384297D03*
X1170513Y1372385D03*
Y1384297D03*
X1158273D03*
Y1372385D03*
X1162633Y1396583D03*
X1170513D03*
X1158273D03*
X1162633Y1408495D03*
X1170513D03*
X1158273D03*
X1186416Y1075196D03*
X1178935D03*
X1175196D03*
X1182676D03*
X1186416Y1071455D03*
X1178935D03*
Y1075196D03*
X1186416D03*
Y1078936D03*
X1182675Y1082676D03*
Y1086416D03*
X1178935Y1078936D03*
X1190155Y1082677D03*
Y1086417D03*
X1178935Y1093897D03*
X1186416D03*
X1175196Y1078936D03*
Y1090157D03*
X1178936D03*
X1182676Y1078936D03*
X1178936Y1082677D03*
Y1086417D03*
X1182676Y1090157D03*
X1186417D03*
Y1086417D03*
Y1082677D03*
X1175195Y1086417D03*
X1182675Y1086416D03*
X1175195Y1082677D03*
X1178935Y1078936D03*
X1182675Y1082676D03*
X1186416Y1078936D03*
X1190157Y1105117D03*
Y1101376D03*
X1182676Y1105117D03*
X1178935Y1097637D03*
X1186416D03*
X1182676Y1101376D03*
X1175196Y1097637D03*
Y1093897D03*
X1178936Y1101377D03*
X1186417D03*
X1182676Y1097637D03*
Y1093897D03*
X1178936Y1105117D03*
X1186417D03*
X1178935Y1097637D03*
X1186416Y1093897D03*
X1182676Y1105117D03*
X1175196D03*
X1178935Y1093897D03*
X1182676Y1101376D03*
X1175196D03*
X1186416Y1097637D03*
X1188287Y1118208D03*
Y1121948D03*
X1184546Y1118208D03*
X1180806Y1121948D03*
X1177066D03*
X1184546D03*
X1186417Y1108858D03*
X1182676D03*
X1178936D03*
X1175196D03*
X1188287Y1114468D03*
X1177066D03*
Y1118208D03*
X1184546Y1114468D03*
X1188287Y1125688D03*
X1184546Y1136909D03*
X1177066Y1133169D03*
X1180806D03*
X1184546D03*
X1177066Y1140649D03*
X1180806D03*
X1184546Y1125688D03*
Y1129429D03*
X1177066Y1125688D03*
X1180806D03*
X1184546Y1140649D03*
X1180806Y1129429D03*
X1177066D03*
X1188287D03*
X1180806Y1136909D03*
X1177066D03*
X1188287D03*
Y1140649D03*
Y1155610D03*
Y1151869D03*
Y1148129D03*
X1177066D03*
X1180806D03*
X1184546Y1144389D03*
Y1148129D03*
Y1151869D03*
X1177066Y1155610D03*
X1184546D03*
X1180806Y1151869D03*
X1177066D03*
Y1144389D03*
X1180806D03*
Y1155610D03*
X1188287Y1144389D03*
X1177066Y1166830D03*
X1188287D03*
Y1159350D03*
Y1170570D03*
X1180806D03*
X1184546D03*
X1177066D03*
X1184546Y1166830D03*
X1180806D03*
X1177066Y1159350D03*
X1180806D03*
X1184546D03*
X1188287Y1181791D03*
Y1174310D03*
X1177066Y1189271D03*
X1180806D03*
X1184546Y1178051D03*
X1177066Y1174310D03*
X1184546Y1185531D03*
X1177066Y1181791D03*
X1180806D03*
X1184546Y1189271D03*
Y1174310D03*
X1177066Y1185531D03*
Y1178051D03*
X1180806Y1185531D03*
Y1178051D03*
Y1174310D03*
X1184546Y1181791D03*
X1188287Y1185531D03*
Y1189271D03*
Y1178051D03*
X1184546Y1204232D03*
X1177066D03*
X1180806D03*
X1184546Y1200491D03*
X1177066Y1196751D03*
X1180806D03*
X1184546Y1193011D03*
X1188287Y1204232D03*
Y1196751D03*
X1184566Y1196732D03*
X1180806Y1200491D03*
X1177066D03*
X1188287D03*
X1177066Y1193011D03*
X1180806D03*
X1188287D03*
Y1207972D03*
X1184546Y1211712D03*
X1177066Y1207972D03*
Y1211712D03*
X1180806Y1207972D03*
Y1211712D03*
X1184546Y1207972D03*
X1186417Y1221062D03*
X1182676D03*
X1178936D03*
X1175196D03*
X1188287Y1215452D03*
X1180806D03*
X1177066D03*
X1188287Y1211712D03*
X1190157Y1224803D03*
Y1228543D03*
X1186417Y1232283D03*
Y1236023D03*
X1182676Y1228543D03*
Y1224803D03*
X1178936Y1232283D03*
Y1236023D03*
X1182676Y1228543D03*
X1186417Y1236023D03*
X1178936D03*
X1186417Y1232283D03*
X1175196Y1228543D03*
X1178936Y1232283D03*
X1182676Y1224803D03*
X1175196D03*
Y1232283D03*
Y1236023D03*
X1178936Y1228543D03*
Y1224803D03*
X1182676Y1232283D03*
Y1236023D03*
X1186417Y1228543D03*
Y1224803D03*
Y1254724D03*
Y1250984D03*
X1182676Y1247243D03*
Y1243503D03*
X1178936Y1250984D03*
Y1254724D03*
X1190157Y1243503D03*
Y1247243D03*
X1175196Y1254724D03*
Y1239763D03*
Y1250984D03*
X1178936Y1247243D03*
X1182676Y1250984D03*
Y1254724D03*
X1186417Y1247243D03*
X1178936Y1239763D03*
X1186417D03*
X1182676D03*
X1178936Y1243503D03*
X1186417D03*
X1178936Y1254724D03*
X1175196Y1243503D03*
X1182676Y1247243D03*
X1178936Y1250984D03*
X1186417D03*
X1182676Y1243503D03*
X1186417Y1254724D03*
X1175196Y1247243D03*
X1186417Y1258465D03*
X1178936D03*
X1182753Y1348187D03*
X1174873D03*
X1182753Y1360099D03*
X1174873D03*
X1182753Y1384297D03*
Y1372385D03*
X1174873Y1384297D03*
Y1372385D03*
X1182753Y1396583D03*
X1174873D03*
X1182753Y1408495D03*
X1174873D03*
X1193896Y1075196D03*
X1201376D03*
X1190157D03*
X1197637D03*
X1205117D03*
X1201376Y1071455D03*
X1193896D03*
Y1075196D03*
X1201376D03*
X1193896Y1078936D03*
X1205116Y1086417D03*
Y1082677D03*
X1197636Y1082676D03*
Y1086416D03*
X1201376Y1078936D03*
X1193896Y1093897D03*
X1201376D03*
X1190157Y1078936D03*
Y1090157D03*
X1197637Y1078936D03*
Y1090157D03*
X1201377D03*
Y1086417D03*
Y1082677D03*
X1205117Y1078936D03*
X1205116Y1090157D03*
X1193897Y1082677D03*
Y1086417D03*
Y1090157D03*
X1190155Y1086417D03*
X1205116Y1082677D03*
X1190155D03*
X1197636Y1082676D03*
X1193896Y1078936D03*
X1205116Y1086417D03*
X1201376Y1078936D03*
X1197636Y1086416D03*
X1205117Y1105117D03*
Y1101376D03*
X1197637Y1105117D03*
X1193896Y1097637D03*
X1201376D03*
X1197637Y1101376D03*
X1190157Y1093897D03*
Y1097637D03*
X1197637D03*
X1201377Y1101377D03*
X1197637Y1093897D03*
X1205117D03*
Y1097637D03*
X1193897Y1101377D03*
X1201377Y1105117D03*
X1193897D03*
X1201376Y1093897D03*
X1193896Y1097637D03*
X1197637Y1105117D03*
X1205117D03*
X1197637Y1101376D03*
X1205117D03*
X1190157D03*
X1193896Y1093897D03*
X1201376Y1097637D03*
X1190157Y1105117D03*
X1192027Y1118208D03*
Y1121948D03*
X1205117Y1123818D03*
Y1120078D03*
Y1116338D03*
Y1108858D03*
X1201377D03*
X1197637D03*
X1193897D03*
X1190157D03*
X1199507Y1118208D03*
X1195767D03*
Y1114468D03*
X1192027D03*
X1199507D03*
X1192027Y1136909D03*
X1195767Y1140649D03*
X1192027Y1133169D03*
Y1140649D03*
X1195767Y1136909D03*
X1192027Y1125688D03*
Y1129429D03*
X1205117Y1135039D03*
Y1131299D03*
Y1127558D03*
X1199507Y1140649D03*
Y1136909D03*
X1203247Y1140649D03*
X1195767Y1148129D03*
X1192027Y1144389D03*
X1195767Y1155610D03*
X1192027Y1148129D03*
X1195767Y1151869D03*
X1199507D03*
X1203247D03*
Y1155610D03*
Y1144389D03*
X1192027Y1151870D03*
X1199507Y1155610D03*
X1192027D03*
X1203247Y1148129D03*
X1195767Y1144389D03*
X1199507Y1148129D03*
Y1144389D03*
X1195767Y1170570D03*
Y1159350D03*
X1203247Y1166830D03*
Y1170570D03*
Y1159350D03*
X1195767Y1166830D03*
X1199507Y1170570D03*
Y1166830D03*
Y1159350D03*
X1192027Y1166830D03*
Y1170570D03*
Y1159350D03*
Y1181791D03*
X1199507Y1185531D03*
X1203247Y1174310D03*
Y1178051D03*
Y1185531D03*
X1192027Y1178051D03*
Y1189271D03*
X1195767D03*
X1192027Y1185531D03*
X1195767D03*
X1199507Y1181791D03*
X1195767Y1178051D03*
Y1174310D03*
X1203247Y1189271D03*
X1199507D03*
Y1174310D03*
X1195767Y1181791D03*
X1192027Y1174310D03*
X1199507Y1178051D03*
X1203247Y1181791D03*
X1195767Y1204232D03*
X1199507Y1193011D03*
X1203247D03*
X1195767Y1196751D03*
Y1193011D03*
X1192027D03*
X1205117Y1198621D03*
Y1202362D03*
X1199507Y1196751D03*
Y1204232D03*
X1195767Y1200491D03*
X1192027Y1196751D03*
Y1200491D03*
Y1204232D03*
X1199507Y1200491D03*
X1192027Y1211712D03*
X1205117Y1206102D03*
Y1209842D03*
Y1213582D03*
Y1217322D03*
Y1221062D03*
X1201377D03*
X1197637D03*
X1193897D03*
X1190157D03*
X1192027Y1215452D03*
X1199507Y1211712D03*
Y1215452D03*
Y1207972D03*
X1195767Y1215452D03*
X1192027Y1207972D03*
X1195767D03*
Y1211712D03*
X1205117Y1224803D03*
Y1228543D03*
X1193897Y1232283D03*
Y1236023D03*
X1201377D03*
Y1232283D03*
X1197637Y1228543D03*
Y1224803D03*
D03*
X1193897Y1236023D03*
X1190157Y1228543D03*
X1201377Y1236023D03*
X1190157Y1224803D03*
X1193897Y1232283D03*
X1197637Y1228543D03*
X1190157Y1232283D03*
Y1236023D03*
X1197637Y1232283D03*
X1201377Y1228543D03*
X1197637Y1236023D03*
X1201377Y1224803D03*
X1205117Y1232283D03*
Y1236023D03*
X1193897Y1228543D03*
Y1224803D03*
X1201377Y1232283D03*
X1205117Y1228543D03*
Y1224803D03*
X1193897Y1250984D03*
Y1254724D03*
X1197637Y1243503D03*
X1201377Y1250984D03*
Y1254724D03*
X1205117Y1247243D03*
Y1243503D03*
X1197637Y1247243D03*
X1190157Y1254724D03*
Y1250984D03*
Y1239763D03*
X1197637Y1250984D03*
Y1254724D03*
X1201377Y1247243D03*
X1205117Y1250984D03*
Y1254724D03*
X1197637Y1239763D03*
X1201377D03*
Y1243503D03*
X1205117Y1239763D03*
X1193897Y1247243D03*
Y1239763D03*
Y1243503D03*
X1190157D03*
X1201377Y1250984D03*
X1197637Y1247243D03*
X1193897Y1250984D03*
X1201377Y1254724D03*
X1197637Y1243503D03*
X1193897Y1254724D03*
X1190157Y1247243D03*
X1205117Y1243503D03*
Y1247243D03*
X1201377Y1258465D03*
X1193897D03*
X1223817Y1075196D03*
X1208857D03*
X1216337D03*
X1212598D03*
X1220079D03*
X1216338Y1071455D03*
X1208857D03*
X1216337Y1075196D03*
X1208857D03*
Y1078936D03*
X1220077Y1082677D03*
Y1086417D03*
X1216337Y1078936D03*
X1212597Y1086416D03*
Y1082676D03*
X1223817Y1078936D03*
Y1093897D03*
X1208857D03*
X1216337D03*
X1220079Y1078936D03*
X1212599D03*
X1216337Y1082677D03*
X1216338Y1086417D03*
X1212597Y1090157D03*
X1216337D03*
X1220077D03*
X1208857Y1082677D03*
X1208858Y1086417D03*
X1208857Y1090157D03*
X1212597Y1082676D03*
Y1086416D03*
X1220077Y1086417D03*
X1208857Y1078936D03*
X1216337D03*
X1220077Y1082677D03*
X1220078Y1105117D03*
X1223817Y1097637D03*
X1220078Y1101376D03*
X1212598Y1105117D03*
X1208857Y1097637D03*
X1216337D03*
X1212598Y1101376D03*
Y1093897D03*
X1220078D03*
X1212598Y1097637D03*
X1220078D03*
X1216338Y1101377D03*
X1208857D03*
X1216338Y1105117D03*
X1208858D03*
X1220078D03*
X1216337Y1093897D03*
X1212598Y1101376D03*
Y1105117D03*
X1208857Y1093897D03*
X1216337Y1097637D03*
X1220078Y1101376D03*
X1208857Y1097637D03*
X1220078Y1120078D03*
Y1112598D03*
X1208857Y1123818D03*
Y1116338D03*
X1212598Y1123818D03*
Y1116338D03*
X1216338Y1120078D03*
Y1112598D03*
X1212598Y1108858D03*
X1216338D03*
Y1116338D03*
X1212598Y1120078D03*
X1216338Y1123818D03*
X1208857Y1112598D03*
Y1120078D03*
X1220077Y1108857D03*
X1220078Y1116338D03*
Y1123818D03*
X1208858Y1108858D03*
X1212598Y1123818D03*
X1208857Y1116338D03*
X1212598D03*
X1216338Y1120078D03*
Y1112598D03*
X1208857Y1123818D03*
X1220078Y1112598D03*
Y1120078D03*
Y1135039D03*
Y1127559D03*
X1216338Y1135039D03*
X1208857Y1131299D03*
X1212598D03*
X1216338Y1127559D03*
X1221948Y1140649D03*
X1218208D03*
X1214468D03*
X1206987Y1136909D03*
X1212598Y1127558D03*
X1216338Y1131299D03*
X1208858Y1127558D03*
X1220078Y1131299D03*
X1212598Y1135039D03*
X1208858D03*
X1216338Y1127559D03*
Y1135039D03*
X1212598Y1131299D03*
X1208857D03*
X1220078Y1135039D03*
Y1127559D03*
X1206988Y1140649D03*
X1221948Y1155610D03*
X1210728Y1151869D03*
X1206987D03*
X1218208Y1155610D03*
Y1148129D03*
X1214468Y1155610D03*
Y1151869D03*
Y1148129D03*
Y1144389D03*
X1206987D03*
X1210728D03*
X1221948Y1148129D03*
X1218208Y1144389D03*
Y1151869D03*
X1206988Y1155610D03*
Y1148129D03*
X1210728Y1155610D03*
X1221948Y1151869D03*
Y1144389D03*
X1206987Y1159350D03*
X1210728D03*
X1214468D03*
X1210728Y1166830D03*
X1206987D03*
X1218208Y1170570D03*
X1214468D03*
Y1166830D03*
X1221948Y1170570D03*
Y1159350D03*
X1218208Y1166830D03*
Y1159350D03*
X1221948Y1166830D03*
X1210728Y1170570D03*
X1206988D03*
X1210728Y1181791D03*
X1206987D03*
X1210728Y1189271D03*
X1218208Y1185531D03*
Y1178051D03*
X1214468Y1189271D03*
X1221948Y1178051D03*
Y1185531D03*
X1206987Y1174310D03*
Y1189271D03*
X1214468Y1185531D03*
Y1181791D03*
Y1178051D03*
Y1174310D03*
X1210728D03*
X1218208Y1189271D03*
Y1174310D03*
X1221948Y1181791D03*
Y1174310D03*
X1218208Y1181791D03*
X1221948Y1189271D03*
X1220078Y1202362D03*
X1208858Y1198621D03*
X1212598D03*
X1216338Y1202362D03*
X1208858Y1206102D03*
X1212598D03*
X1208858Y1194881D03*
X1212598D03*
X1218208Y1193011D03*
X1214468D03*
X1221948D03*
X1212598Y1202362D03*
X1220078Y1198621D03*
X1216338D03*
X1208858Y1202362D03*
X1212598Y1198621D03*
X1208858D03*
X1216338Y1202362D03*
X1220078D03*
X1208858Y1213582D03*
X1220078Y1209842D03*
X1216338D03*
X1212598Y1213582D03*
X1216338Y1217322D03*
X1220078D03*
Y1206102D03*
X1216338D03*
X1220078Y1221062D03*
X1216338D03*
X1212598D03*
Y1217322D03*
X1216338Y1213582D03*
X1220078D03*
X1212598Y1209842D03*
X1208858Y1221062D03*
Y1217322D03*
Y1209842D03*
X1220078Y1217322D03*
Y1209842D03*
X1212598Y1206102D03*
X1216338Y1217322D03*
X1212598Y1213582D03*
X1208858Y1206102D03*
Y1213582D03*
X1216338Y1209842D03*
X1223818Y1232283D03*
Y1236023D03*
X1220078Y1228543D03*
Y1224803D03*
X1208858Y1232283D03*
Y1236023D03*
X1216338D03*
Y1232283D03*
X1212598Y1228543D03*
Y1224803D03*
X1216338D03*
Y1228543D03*
X1212598Y1232283D03*
Y1236023D03*
X1220078Y1232283D03*
Y1236023D03*
X1208858Y1224803D03*
Y1228543D03*
X1220078Y1224803D03*
X1212598Y1228543D03*
X1208858Y1232283D03*
X1216338Y1236023D03*
Y1232283D03*
X1212598Y1224803D03*
X1220078Y1228543D03*
X1208858Y1236023D03*
Y1254724D03*
Y1250984D03*
X1212598Y1243503D03*
Y1247243D03*
X1216338Y1250984D03*
Y1254724D03*
X1220078Y1247243D03*
Y1243503D03*
X1223818Y1254724D03*
Y1250984D03*
X1212598D03*
Y1254724D03*
X1216338Y1247243D03*
Y1243503D03*
X1220078Y1250984D03*
Y1254724D03*
X1212598Y1239763D03*
X1216338D03*
X1220078D03*
X1208858Y1247243D03*
Y1243503D03*
Y1239763D03*
X1212598Y1243503D03*
X1220078Y1247243D03*
Y1243503D03*
X1212598Y1247243D03*
X1208858Y1254724D03*
Y1250984D03*
X1216338Y1254724D03*
Y1250984D03*
Y1258465D03*
X1208858D03*
X1231297Y1075196D03*
X1227559D03*
X1235039D03*
X1231298Y1071455D03*
X1223818D03*
X1231297Y1075196D03*
X1223817D03*
X1235039Y1090157D03*
Y1082676D03*
X1227557Y1082677D03*
Y1086417D03*
X1231297Y1078936D03*
X1238779Y1090157D03*
Y1082676D03*
X1231298Y1093897D03*
X1223817Y1082677D03*
X1223818Y1086417D03*
X1223817Y1090157D03*
X1235039Y1078936D03*
X1227559D03*
X1231298Y1082677D03*
X1235039Y1086417D03*
X1231299D03*
X1227557Y1090157D03*
X1231298D03*
X1235039D03*
X1231297Y1078936D03*
X1235039Y1082676D03*
X1227557Y1086417D03*
X1223817Y1078936D03*
X1227557Y1082677D03*
X1238779Y1101377D03*
X1227558Y1105117D03*
X1235039Y1101377D03*
X1227558D03*
X1231298Y1097637D03*
X1235039Y1108858D03*
X1238779D03*
X1223818Y1101377D03*
X1227558Y1093897D03*
Y1097637D03*
X1231298Y1101377D03*
X1235039Y1093897D03*
Y1097637D03*
X1223818Y1105117D03*
X1231299D03*
X1235039D03*
X1227558Y1101377D03*
X1231298Y1093897D03*
X1235039Y1101377D03*
X1227558Y1105117D03*
X1223817Y1093897D03*
Y1097637D03*
X1231298D03*
Y1112598D03*
X1227558D03*
X1235039Y1116338D03*
X1227558Y1120078D03*
X1231298D03*
X1235039Y1123818D03*
X1238779Y1116338D03*
Y1123818D03*
X1223817Y1108858D03*
X1223818Y1116338D03*
Y1112598D03*
Y1123818D03*
Y1120078D03*
X1227558Y1108858D03*
X1231298D03*
X1227558Y1116338D03*
X1231298D03*
X1235039Y1112598D03*
X1227558Y1123818D03*
X1231298D03*
X1235039Y1120078D03*
X1227558Y1112598D03*
X1235039Y1123818D03*
X1231298Y1120078D03*
Y1112598D03*
X1235039Y1108858D03*
Y1116338D03*
X1227558Y1120078D03*
X1238779Y1131299D03*
X1231298Y1135039D03*
X1227558D03*
Y1127558D03*
X1231298D03*
X1235039Y1131299D03*
X1236909Y1140649D03*
X1233169D03*
X1229428Y1136909D03*
X1233169D03*
X1223818Y1127558D03*
Y1131299D03*
X1235039Y1127558D03*
X1231298Y1131299D03*
X1227557D03*
X1223818Y1135039D03*
X1235039D03*
X1231298D03*
X1227558Y1127558D03*
X1235039Y1131299D03*
X1231298Y1127558D03*
X1227558Y1135039D03*
X1236909Y1136909D03*
X1225688Y1140649D03*
X1229428D03*
X1236909Y1148129D03*
Y1155610D03*
X1233169Y1144389D03*
X1225688D03*
Y1151869D03*
X1229428Y1144389D03*
X1233169Y1155610D03*
X1229428Y1151869D03*
X1233169D03*
Y1148129D03*
X1236909Y1151870D03*
X1225688Y1148129D03*
X1229428D03*
X1225688Y1155610D03*
X1236909Y1144389D03*
X1229428Y1155610D03*
X1236909Y1170570D03*
Y1166830D03*
X1225688D03*
X1229428Y1159350D03*
X1233169D03*
X1225688D03*
X1229428Y1166830D03*
X1233169Y1170570D03*
Y1166830D03*
X1229428Y1170570D03*
X1225688D03*
X1236909Y1159350D03*
Y1178051D03*
Y1185531D03*
X1229428Y1181791D03*
Y1189271D03*
X1233169D03*
Y1185531D03*
Y1181791D03*
Y1178051D03*
X1229428Y1174310D03*
X1233169D03*
X1225688D03*
Y1181791D03*
Y1189271D03*
X1236909Y1181791D03*
X1225688Y1185531D03*
X1236909Y1189271D03*
X1229428Y1178051D03*
Y1185531D03*
X1236909Y1174310D03*
X1225688Y1178051D03*
X1238779Y1198621D03*
X1227558Y1202362D03*
X1231298D03*
X1235039Y1198621D03*
Y1206102D03*
X1238779D03*
X1233169Y1193011D03*
X1223818Y1194881D03*
X1229428Y1196751D03*
X1233169D03*
X1236909Y1193011D03*
X1223818Y1202362D03*
Y1198621D03*
X1235039Y1202362D03*
X1231298Y1198621D03*
X1227558D03*
X1231298Y1202362D03*
X1235039Y1198621D03*
X1227558Y1202362D03*
X1225688Y1193011D03*
X1229428D03*
X1231298Y1209842D03*
X1227558D03*
Y1217322D03*
X1231298D03*
X1235039Y1221062D03*
Y1213582D03*
X1238779Y1221062D03*
Y1213582D03*
X1223818Y1206102D03*
Y1221062D03*
Y1217322D03*
Y1213582D03*
Y1209842D03*
X1231298Y1206102D03*
X1227558D03*
X1235039Y1217322D03*
X1231298Y1221062D03*
X1227558D03*
X1235039Y1209842D03*
X1231298Y1213582D03*
X1227558D03*
X1235039D03*
X1231298Y1209842D03*
X1227558D03*
X1235039Y1221062D03*
X1231298Y1217322D03*
X1235039Y1206102D03*
X1227558Y1217322D03*
X1238779Y1228543D03*
X1231298Y1236023D03*
Y1232283D03*
X1235039Y1228543D03*
X1227558D03*
Y1224803D03*
X1235039Y1239763D03*
X1238779D03*
X1223818Y1224803D03*
Y1228543D03*
X1235039Y1224803D03*
X1231298D03*
Y1228543D03*
X1227558Y1236023D03*
Y1232283D03*
X1235039D03*
Y1236023D03*
X1225688Y1222932D03*
X1231298Y1232283D03*
X1227558Y1228543D03*
Y1224803D03*
X1223818Y1236023D03*
X1231298D03*
X1235039Y1228543D03*
X1223818Y1232283D03*
X1227558Y1243503D03*
Y1247243D03*
X1231298Y1254724D03*
Y1250984D03*
X1235039Y1247243D03*
X1238779D03*
X1223818D03*
Y1243503D03*
Y1239763D03*
X1227558Y1250984D03*
Y1254724D03*
X1235039Y1250984D03*
X1231298Y1247243D03*
Y1243503D03*
X1235039D03*
X1227558Y1239763D03*
X1231298D03*
X1235039Y1254724D03*
X1227558Y1247243D03*
X1231298Y1254724D03*
X1223818D03*
Y1250984D03*
X1235039Y1239763D03*
X1227558Y1243503D03*
X1231298Y1250984D03*
X1235039Y1247243D03*
X1231298Y1258465D03*
X1223818D03*
X1235966Y1348187D03*
X1228086D03*
X1235966Y1360099D03*
X1228086D03*
X1235966Y1372385D03*
Y1384297D03*
X1228086Y1372385D03*
Y1384297D03*
X1238779Y1086417D03*
Y1078936D03*
X1242520Y1090158D03*
Y1082677D03*
X1238779Y1090157D03*
Y1082676D03*
Y1093897D03*
Y1097637D03*
Y1105117D03*
X1242520Y1101378D03*
X1238779Y1101377D03*
Y1112598D03*
Y1120078D03*
X1242520Y1123819D03*
Y1116339D03*
Y1108859D03*
X1238779Y1108858D03*
Y1116338D03*
Y1123818D03*
X1243149Y1136909D03*
X1240649Y1140649D03*
X1238779Y1127558D03*
Y1135039D03*
X1242520Y1131300D03*
X1238779Y1131299D03*
X1240649Y1136909D03*
Y1148129D03*
Y1155610D03*
Y1151870D03*
Y1144389D03*
Y1166830D03*
Y1170570D03*
Y1159350D03*
Y1178051D03*
Y1185531D03*
Y1174310D03*
Y1181791D03*
Y1189271D03*
X1240589Y1193011D03*
X1238779Y1202362D03*
X1242520Y1198621D03*
X1238779D03*
Y1217322D03*
Y1209842D03*
X1242520Y1221062D03*
Y1213582D03*
Y1206102D03*
X1238779Y1221062D03*
Y1206102D03*
Y1213582D03*
Y1224803D03*
Y1232283D03*
Y1236023D03*
X1242520Y1228543D03*
X1238779D03*
Y1250984D03*
Y1243503D03*
X1242520Y1247243D03*
Y1239762D03*
X1238779Y1247243D03*
Y1239763D03*
X1252566Y1348187D03*
X1240326D03*
X1248206D03*
X1252566Y1360099D03*
X1240326D03*
X1248206D03*
X1252566Y1372385D03*
Y1384297D03*
X1240326D03*
Y1372385D03*
X1248206D03*
Y1384297D03*
X1252566Y1396583D03*
X1240326D03*
X1248206D03*
X1252566Y1408495D03*
X1240326D03*
X1248206D03*
X1264806Y1348187D03*
X1260446D03*
X1264806Y1360099D03*
X1260446D03*
X1264806Y1372385D03*
Y1384297D03*
X1260446Y1372385D03*
Y1384297D03*
X1264806Y1396583D03*
X1260446D03*
X1264806Y1408495D03*
X1260446D03*
X1284926Y1348187D03*
X1277046D03*
X1272686D03*
X1284926Y1360099D03*
X1277046D03*
X1272686D03*
X1284926Y1372385D03*
Y1384297D03*
X1277046Y1372385D03*
Y1384297D03*
X1272686D03*
Y1372385D03*
X1284926Y1396583D03*
X1277046D03*
X1272686D03*
X1284926Y1408495D03*
X1277046D03*
X1272686D03*
X1301526Y1348187D03*
X1289286D03*
X1297166D03*
X1301526Y1360099D03*
X1289286D03*
X1297166D03*
X1301526Y1372385D03*
Y1384297D03*
X1289286D03*
Y1372385D03*
X1297166Y1384297D03*
Y1372385D03*
X1301526Y1396583D03*
X1289286D03*
X1297166D03*
X1301526Y1408495D03*
X1289286D03*
X1297166D03*
X1313766Y1348187D03*
X1309406D03*
X1313766Y1360099D03*
X1309406D03*
X1313766Y1372385D03*
Y1384297D03*
X1309406Y1372385D03*
Y1384297D03*
X1313766Y1396583D03*
X1309406D03*
X1313766Y1408495D03*
X1309406D03*
X1333886Y1348187D03*
X1326006D03*
X1321646D03*
X1333886Y1360099D03*
X1326006D03*
X1321646D03*
X1333886Y1372385D03*
Y1384297D03*
X1326006Y1372385D03*
Y1384297D03*
X1321646D03*
Y1372385D03*
X1333886Y1396583D03*
X1326006D03*
X1321646D03*
X1333886Y1408495D03*
X1326006D03*
X1321646D03*
X1339196Y441086D03*
Y433999D03*
Y437543D03*
X1336396Y441086D03*
Y433999D03*
Y437543D03*
X1339196Y444629D03*
X1336396D03*
X1350486Y1348187D03*
X1338246D03*
X1346126D03*
X1350486Y1360099D03*
X1338246D03*
X1346126D03*
X1350486Y1372385D03*
Y1384297D03*
X1338246D03*
Y1372385D03*
X1346126Y1384297D03*
Y1372385D03*
X1350486Y1396583D03*
X1338246D03*
X1346126D03*
X1350486Y1408495D03*
X1338246D03*
X1346126D03*
X1358366Y1348187D03*
Y1360099D03*
Y1372385D03*
Y1384297D03*
Y1396583D03*
Y1408495D03*
X1415924Y620661D03*
Y617861D03*
X1423010Y620661D03*
X1419467Y617861D03*
X1423010D03*
X1426554Y620661D03*
Y617861D03*
X1419467Y620661D03*
X1459130Y1348187D03*
Y1360099D03*
Y1384297D03*
Y1372385D03*
X1479250Y1348187D03*
X1471370D03*
X1467010D03*
X1479250Y1360099D03*
X1471370D03*
X1467010D03*
X1479250Y1384297D03*
Y1372385D03*
X1471370D03*
Y1384297D03*
X1467010D03*
Y1372385D03*
X1479250Y1396583D03*
X1471370D03*
X1479250Y1408495D03*
X1471370D03*
X1495850Y1348187D03*
X1483610D03*
X1491490D03*
X1495850Y1360099D03*
X1483610D03*
X1491490D03*
X1483610Y1384297D03*
Y1372385D03*
X1491490Y1384297D03*
Y1372385D03*
X1495850Y1384297D03*
Y1372385D03*
Y1396583D03*
X1483610D03*
X1491490D03*
X1495850Y1408495D03*
X1483610D03*
X1491490D03*
X1514468Y1084547D03*
Y1092027D03*
Y1088287D03*
Y1095767D03*
Y1103247D03*
Y1099507D03*
Y1106988D03*
Y1110728D03*
Y1118208D03*
Y1121948D03*
Y1114468D03*
Y1125688D03*
Y1133169D03*
Y1140649D03*
Y1129429D03*
Y1136909D03*
Y1144389D03*
Y1151870D03*
Y1148129D03*
Y1155610D03*
X1511968Y1170570D03*
X1514468Y1159350D03*
Y1166829D03*
X1514467Y1170570D03*
X1516338Y1191141D03*
X1511968Y1178050D03*
X1514468Y1174309D03*
Y1181790D03*
X1514467Y1178051D03*
X1516338Y1198621D03*
Y1206102D03*
X1512597Y1198622D03*
Y1191142D03*
X1516338Y1221062D03*
Y1213582D03*
X1512597Y1221063D03*
Y1213583D03*
Y1206103D03*
X1516338Y1228543D03*
Y1239763D03*
X1512597Y1228542D03*
X1516338Y1247243D03*
X1512596Y1239762D03*
Y1247242D03*
X1508090Y1348187D03*
X1503730D03*
X1508090Y1360099D03*
X1503730D03*
X1508090Y1384297D03*
Y1372385D03*
X1503730D03*
Y1384297D03*
X1508090Y1396583D03*
X1503730D03*
X1508090Y1408495D03*
X1503730D03*
X1525689Y1073326D03*
X1521949D03*
X1529429D03*
X1521948Y1077066D03*
X1525689D03*
X1518208D03*
Y1080806D03*
X1529429Y1080807D03*
X1521949D03*
X1529429Y1084547D03*
X1521949D03*
X1518208D03*
X1529429Y1088287D03*
X1525689D03*
X1521949D03*
X1525689Y1092027D03*
X1518208D03*
X1529429Y1077066D03*
X1525689Y1084547D03*
X1529429Y1092027D03*
X1521949D03*
X1518208Y1088287D03*
X1525689Y1080807D03*
X1521949Y1103247D03*
X1518208D03*
X1529429Y1106988D03*
X1525689D03*
X1521949D03*
X1525689Y1095767D03*
X1518208D03*
X1529429Y1099507D03*
X1521949D03*
X1529429Y1103247D03*
X1518208Y1099507D03*
X1525689D03*
X1529429Y1095767D03*
X1525689Y1103247D03*
X1518208Y1106988D03*
X1521949Y1095767D03*
X1529429Y1110728D03*
X1518208D03*
X1529429Y1114468D03*
X1525689D03*
X1521949D03*
X1529429Y1118208D03*
X1518208D03*
X1529429Y1121948D03*
X1525689D03*
X1521949D03*
Y1110728D03*
X1518208Y1114468D03*
X1525689Y1110728D03*
X1518208Y1121948D03*
X1521949Y1118208D03*
X1525689D03*
X1529429Y1125688D03*
X1518208D03*
X1529429Y1129429D03*
X1525689D03*
X1521949D03*
X1518208Y1133169D03*
X1521949Y1136909D03*
X1529429Y1140649D03*
X1525689D03*
X1521949D03*
X1518208D03*
X1525689Y1125688D03*
X1518208Y1129429D03*
X1521949Y1125688D03*
X1518208Y1136909D03*
X1521949Y1133169D03*
Y1144389D03*
X1518208D03*
X1529429Y1151869D03*
X1525689D03*
X1521949Y1148129D03*
Y1151870D03*
X1518208D03*
X1529429Y1155610D03*
X1525689D03*
X1521949D03*
X1518208Y1148129D03*
Y1155610D03*
X1521949Y1159350D03*
X1518208D03*
X1529429Y1166830D03*
X1525689D03*
X1521948D03*
X1525689Y1170570D03*
X1521948D03*
X1518209Y1166830D03*
X1518207Y1170570D03*
X1523819Y1187401D03*
X1527559D03*
X1520078Y1191141D03*
X1521948Y1174310D03*
X1518207D03*
X1521948Y1178051D03*
X1525689Y1174310D03*
X1529429D03*
X1527559Y1179921D03*
X1523819D03*
X1518207Y1181791D03*
X1516338Y1187401D03*
X1520078D03*
X1527559Y1183661D03*
X1523819D03*
X1520078D03*
X1516338D03*
X1523819Y1187401D03*
X1527559D03*
Y1176180D03*
X1518207Y1178051D03*
X1520078Y1198621D03*
X1527559Y1202362D03*
X1523819D03*
X1527559Y1194881D03*
X1523819D03*
X1520078Y1206102D03*
X1516338Y1194881D03*
Y1202362D03*
X1527559Y1191141D03*
X1523819D03*
X1527559Y1198621D03*
X1523819D03*
X1520078Y1194881D03*
Y1202362D03*
X1516338Y1198621D03*
X1523819Y1194881D03*
X1520078Y1198621D03*
X1523819Y1202362D03*
X1516338Y1191141D03*
X1527559Y1202362D03*
Y1194881D03*
X1520078Y1191141D03*
Y1221062D03*
Y1213582D03*
X1527559Y1217322D03*
X1523819D03*
Y1209842D03*
X1527559D03*
X1516338D03*
Y1217322D03*
X1523819Y1206102D03*
X1527559D03*
Y1213582D03*
X1523819D03*
X1520078Y1209842D03*
Y1217322D03*
X1523819Y1221062D03*
X1527559D03*
X1520078D03*
X1516338Y1213582D03*
Y1206102D03*
X1520078D03*
X1527559Y1217322D03*
X1523819Y1209842D03*
X1516338Y1221062D03*
X1527559Y1209842D03*
X1523819Y1217322D03*
X1520078Y1213582D03*
X1531299Y1232283D03*
Y1236023D03*
X1520078Y1228543D03*
X1523819Y1236023D03*
Y1232283D03*
X1527559Y1228543D03*
Y1224803D03*
X1520078Y1239763D03*
X1527559Y1228543D03*
X1516338D03*
Y1232283D03*
Y1236023D03*
Y1224803D03*
X1527559Y1236023D03*
Y1232283D03*
X1523819Y1228543D03*
Y1224803D03*
X1520078Y1236023D03*
Y1232283D03*
Y1224803D03*
X1523819Y1232283D03*
X1520078Y1228543D03*
X1523819Y1236023D03*
X1527559Y1224803D03*
X1520078Y1247243D03*
X1527559Y1243503D03*
Y1247243D03*
X1523819Y1250984D03*
Y1254724D03*
X1531299D03*
Y1250984D03*
X1516338Y1239763D03*
Y1243503D03*
Y1250984D03*
X1527559D03*
Y1254724D03*
X1523819Y1247243D03*
Y1239763D03*
Y1243503D03*
X1527559Y1239763D03*
X1520078Y1250984D03*
Y1254724D03*
Y1243503D03*
Y1239763D03*
Y1247243D03*
X1516338D03*
X1527559Y1243503D03*
Y1247243D03*
X1523819Y1250984D03*
Y1254724D03*
Y1258465D03*
X1528210Y1348187D03*
X1520330D03*
X1515970D03*
X1528210Y1360099D03*
X1520330D03*
X1515970D03*
X1528210Y1372385D03*
Y1384297D03*
X1520330Y1372385D03*
Y1384297D03*
X1515970D03*
Y1372385D03*
X1528210Y1396583D03*
X1520330D03*
X1515970D03*
X1528210Y1408495D03*
X1520330D03*
X1515970D03*
X1546259Y1075196D03*
X1533169Y1073326D03*
X1540649D03*
X1546258Y1071455D03*
X1546259Y1075196D03*
X1536909Y1073326D03*
X1546259Y1078936D03*
Y1093897D03*
X1540649Y1088287D03*
X1533169Y1077066D03*
X1536909Y1080807D03*
Y1084547D03*
Y1088287D03*
X1533169D03*
Y1092027D03*
X1540649Y1077066D03*
Y1092027D03*
X1546259Y1082677D03*
Y1086417D03*
Y1090157D03*
Y1078936D03*
X1533169Y1080807D03*
Y1084547D03*
X1540649Y1080807D03*
X1536909Y1077066D03*
X1540649Y1084547D03*
X1536909Y1092027D03*
X1546259Y1097637D03*
X1544389Y1099507D03*
X1533169Y1095767D03*
X1536909Y1099507D03*
Y1103247D03*
X1540649Y1106988D03*
X1536909D03*
X1533169D03*
X1544389D03*
X1540649Y1095767D03*
Y1099507D03*
X1546259Y1101377D03*
Y1105117D03*
Y1097637D03*
Y1093897D03*
X1536909Y1095767D03*
X1533169Y1099507D03*
X1540649Y1103247D03*
X1533169D03*
X1544389Y1118208D03*
X1540649D03*
Y1121948D03*
X1544389Y1110728D03*
X1540649D03*
X1536909Y1114468D03*
X1533169D03*
X1536909Y1118208D03*
X1533169D03*
Y1121948D03*
X1544389Y1114468D03*
X1536909Y1110728D03*
X1533169D03*
X1540649Y1114468D03*
X1544389Y1140649D03*
X1540649D03*
X1536909D03*
X1533169D03*
Y1125688D03*
X1544389Y1129428D03*
X1540649D03*
X1536909Y1129429D03*
X1533169D03*
X1544389Y1136909D03*
X1533169Y1133169D03*
X1540649Y1136909D03*
X1544389Y1144389D03*
X1540649D03*
X1533169D03*
Y1148129D03*
Y1151870D03*
Y1155610D03*
X1544389Y1148129D03*
Y1155610D03*
Y1151870D03*
X1536909Y1148129D03*
X1540649Y1151870D03*
Y1148129D03*
X1536909Y1144389D03*
Y1155610D03*
X1533169Y1159350D03*
X1536909Y1166830D03*
Y1170570D03*
X1544389Y1159350D03*
Y1166830D03*
Y1170570D03*
X1540649Y1159350D03*
Y1170570D03*
X1538779Y1187401D03*
X1535039D03*
X1546259Y1191141D03*
X1542519D03*
X1535039Y1187401D03*
X1536909Y1174310D03*
X1533169D03*
Y1178051D03*
X1544389Y1174310D03*
Y1178051D03*
Y1181791D03*
X1540649D03*
X1538779Y1179921D03*
X1535039Y1176180D03*
X1531299Y1179921D03*
Y1187401D03*
X1546259D03*
X1542519D03*
Y1183661D03*
X1538779D03*
X1535039D03*
X1531299D03*
X1538779Y1187401D03*
X1540649Y1174310D03*
Y1178050D03*
X1531299Y1176180D03*
X1546259Y1198621D03*
X1542519D03*
X1538779Y1202362D03*
Y1194881D03*
X1535039Y1202362D03*
Y1194881D03*
X1546259Y1206102D03*
X1542519D03*
Y1191141D03*
X1538779Y1202362D03*
X1535039Y1194881D03*
X1542519Y1198621D03*
X1535039Y1191141D03*
X1531299D03*
X1535039Y1198621D03*
X1531299D03*
Y1194881D03*
Y1202362D03*
X1538779Y1198621D03*
Y1191141D03*
X1542519Y1194881D03*
X1546259D03*
X1542519Y1202362D03*
X1546259D03*
Y1198621D03*
Y1191141D03*
X1535039Y1202362D03*
X1538779Y1194881D03*
X1546259Y1213582D03*
X1542519D03*
X1538779Y1209842D03*
Y1217322D03*
X1535039Y1209842D03*
Y1217322D03*
X1542519Y1213582D03*
Y1206102D03*
X1546259Y1213582D03*
X1535039Y1209842D03*
X1531299Y1206102D03*
X1535039D03*
X1531299Y1217322D03*
X1535039Y1213582D03*
X1531299Y1209842D03*
Y1213582D03*
X1538779Y1206102D03*
Y1213582D03*
X1542519Y1209842D03*
X1546259D03*
X1531299Y1221062D03*
X1535039D03*
X1546259Y1217322D03*
Y1221062D03*
X1538779D03*
X1542519D03*
Y1217322D03*
X1535039D03*
X1546259Y1206102D03*
X1538779Y1209842D03*
Y1217322D03*
X1546259Y1236023D03*
Y1232283D03*
X1542519Y1228543D03*
Y1224803D03*
X1538779Y1236023D03*
Y1232283D03*
X1535039Y1228543D03*
Y1224803D03*
X1546259Y1232283D03*
X1535039Y1224803D03*
X1538779Y1236023D03*
X1531299Y1232283D03*
X1542519Y1228543D03*
X1535039D03*
X1546259Y1236023D03*
X1531299Y1224803D03*
Y1228543D03*
X1535039Y1232283D03*
Y1236023D03*
X1542519Y1232283D03*
Y1236023D03*
X1538779Y1228543D03*
Y1224803D03*
X1546259D03*
Y1228543D03*
X1542519Y1224803D03*
X1531299Y1236023D03*
X1538779Y1232283D03*
X1542519Y1243503D03*
Y1247243D03*
X1538779Y1250984D03*
Y1254724D03*
X1546259D03*
Y1250984D03*
X1535039Y1247243D03*
Y1243503D03*
X1531299Y1247243D03*
X1535039Y1250984D03*
Y1254724D03*
Y1239763D03*
X1531299D03*
Y1243503D03*
X1538779Y1247243D03*
X1542519Y1254724D03*
X1538779Y1239763D03*
Y1243503D03*
X1542519Y1250984D03*
Y1239763D03*
X1546259D03*
Y1243503D03*
Y1247243D03*
Y1250984D03*
X1542519Y1243503D03*
X1546259Y1254724D03*
X1542519Y1247243D03*
X1538779Y1250984D03*
Y1254724D03*
X1535039Y1243503D03*
X1531299Y1250984D03*
X1535039Y1247243D03*
X1531299Y1254724D03*
X1546260Y1258465D03*
X1538779D03*
X1531299D03*
X1544810Y1348187D03*
X1532570D03*
X1540450D03*
X1544810Y1360099D03*
X1532570D03*
X1540450D03*
X1544810Y1384297D03*
Y1372385D03*
X1532570Y1384297D03*
Y1372385D03*
X1540450Y1384297D03*
Y1372385D03*
X1544810Y1396583D03*
X1532570D03*
X1540450D03*
X1544810Y1408495D03*
X1532570D03*
X1540450D03*
X1561220Y1075196D03*
X1553740D03*
X1557480D03*
X1550000D03*
X1561219Y1071455D03*
X1553739D03*
X1553740Y1075196D03*
X1561220D03*
Y1078936D03*
X1550000Y1082677D03*
Y1086417D03*
X1553740Y1078936D03*
X1557480Y1082677D03*
Y1086417D03*
X1564960D03*
Y1082677D03*
X1561220Y1093897D03*
X1553740D03*
X1561220Y1086417D03*
Y1090157D03*
Y1082677D03*
X1557480Y1078936D03*
Y1090157D03*
X1553740Y1082677D03*
Y1086417D03*
Y1090157D03*
X1550000Y1078936D03*
Y1090157D03*
X1557480Y1082677D03*
X1553740Y1078936D03*
X1561220D03*
X1550000Y1086417D03*
Y1082677D03*
X1557480Y1086417D03*
X1564960Y1101376D03*
X1561220Y1097637D03*
X1564960Y1105117D03*
X1550000Y1101376D03*
X1553740Y1097637D03*
X1557480Y1101376D03*
Y1105117D03*
X1550000D03*
X1557480Y1101376D03*
X1561220Y1093897D03*
X1557480Y1105117D03*
X1561220Y1097637D03*
Y1105117D03*
X1553740D03*
X1561220Y1101377D03*
X1557480Y1097637D03*
Y1093897D03*
X1553740Y1101377D03*
X1550000Y1093897D03*
Y1097637D03*
Y1101376D03*
Y1105117D03*
X1553740Y1093897D03*
Y1097637D03*
X1551870Y1114468D03*
X1548130D03*
X1563090Y1118208D03*
X1559350D03*
X1555610D03*
X1551870D03*
X1548130D03*
X1563090Y1121948D03*
X1559350D03*
X1555610D03*
X1551870D03*
X1548130D03*
Y1110728D03*
X1561220Y1108858D03*
X1557480D03*
X1553740D03*
X1550000D03*
X1551870Y1110728D03*
X1559350Y1114468D03*
X1555610D03*
X1563090D03*
X1548130Y1140649D03*
X1563090Y1125688D03*
X1559350D03*
X1555610D03*
X1551870D03*
X1548130D03*
X1559350Y1129429D03*
X1555610D03*
X1551870D03*
X1548130D03*
X1559350Y1133169D03*
X1555610D03*
X1551870D03*
X1548130D03*
X1559350Y1136909D03*
X1551870D03*
X1548130D03*
X1559350Y1140649D03*
X1555610D03*
X1551870D03*
X1563090D03*
Y1136909D03*
X1555610D03*
X1563090Y1129429D03*
Y1133169D03*
X1551870Y1155610D03*
Y1151870D03*
X1559350Y1144389D03*
X1551870D03*
Y1148129D03*
X1559350Y1151870D03*
X1563090Y1155610D03*
Y1148129D03*
Y1144389D03*
Y1151869D03*
X1555610Y1144389D03*
X1548130Y1151870D03*
Y1148129D03*
Y1144389D03*
X1559350Y1155610D03*
X1555610Y1151870D03*
X1559350Y1148129D03*
Y1170570D03*
X1551870Y1166830D03*
X1559350Y1159350D03*
X1551870D03*
X1548130Y1170570D03*
X1551870D03*
X1563090Y1166830D03*
Y1159350D03*
Y1170570D03*
X1548130Y1166830D03*
Y1159350D03*
X1555610Y1170570D03*
X1559350Y1166830D03*
X1555610Y1159350D03*
X1551870Y1189271D03*
X1559350Y1185531D03*
X1551870D03*
Y1178051D03*
Y1174310D03*
X1559350Y1178051D03*
X1551870Y1181791D03*
X1563090D03*
Y1174310D03*
X1550000Y1187401D03*
X1548130Y1185531D03*
Y1174310D03*
Y1178051D03*
Y1181791D03*
X1563090Y1185531D03*
Y1178051D03*
X1555610Y1185531D03*
X1559350Y1174310D03*
Y1181791D03*
X1555610Y1178051D03*
X1551870Y1193011D03*
X1559350D03*
Y1196751D03*
Y1200491D03*
X1555610D03*
Y1204232D03*
X1559350D03*
X1563090D03*
Y1196751D03*
Y1200491D03*
X1555610Y1193011D03*
Y1196751D03*
X1550000Y1191141D03*
Y1194881D03*
Y1198621D03*
Y1202362D03*
X1563090Y1193011D03*
X1555610Y1211712D03*
X1559350D03*
X1563090D03*
Y1207972D03*
X1559350D03*
X1555610D03*
X1563090Y1219192D03*
X1550000Y1221062D03*
X1553740D03*
X1557480D03*
X1561220D03*
X1550000Y1206102D03*
Y1209842D03*
Y1213582D03*
Y1217322D03*
X1553740D03*
X1555610Y1215452D03*
X1563090D03*
X1559350D03*
X1564960Y1224803D03*
Y1228543D03*
X1561220Y1232283D03*
Y1236023D03*
X1553740D03*
Y1232283D03*
X1557480Y1228543D03*
Y1224803D03*
X1550000Y1228543D03*
Y1224803D03*
X1553740Y1232283D03*
X1550000Y1228543D03*
X1553740Y1236023D03*
X1550000Y1224803D03*
X1557480Y1228543D03*
X1561220Y1236023D03*
X1550000Y1232283D03*
Y1236023D03*
X1561220Y1224803D03*
Y1228543D03*
X1557480Y1232283D03*
Y1236023D03*
X1553740Y1228543D03*
Y1224803D03*
X1561220Y1232283D03*
X1557480Y1224803D03*
X1553740Y1254724D03*
Y1250984D03*
X1561220D03*
Y1254724D03*
X1557480Y1247243D03*
Y1243503D03*
X1550000Y1247243D03*
Y1243503D03*
X1564960D03*
Y1247243D03*
X1550000Y1250984D03*
Y1254724D03*
Y1239763D03*
X1557480Y1250984D03*
Y1254724D03*
X1561220Y1247243D03*
X1557480Y1239763D03*
X1561220D03*
Y1243503D03*
X1553740Y1247243D03*
Y1239763D03*
Y1243503D03*
X1561220Y1250984D03*
Y1254724D03*
X1550000Y1243503D03*
X1557480Y1247243D03*
X1550000D03*
X1557480Y1243503D03*
X1553740Y1250984D03*
Y1254724D03*
X1561220Y1258465D03*
X1553740D03*
X1557050Y1348187D03*
X1552690D03*
Y1360099D03*
X1557050D03*
Y1384297D03*
Y1372385D03*
X1552690D03*
Y1384297D03*
X1557050Y1396583D03*
X1552690D03*
X1557050Y1408495D03*
X1552690D03*
X1568700Y1075196D03*
X1576181D03*
X1572441D03*
X1564960D03*
X1576180Y1071455D03*
X1568699D03*
X1576181Y1075196D03*
X1568700D03*
Y1078936D03*
X1572441Y1082677D03*
Y1086417D03*
X1576181Y1078936D03*
X1579921Y1082677D03*
Y1086417D03*
X1568700Y1093897D03*
X1576181D03*
X1564960Y1090157D03*
Y1078936D03*
X1572441Y1090157D03*
Y1078936D03*
X1576181Y1082677D03*
Y1086417D03*
Y1090157D03*
X1568700Y1082677D03*
Y1086417D03*
Y1090157D03*
Y1078936D03*
X1572441Y1086417D03*
X1564960Y1082677D03*
Y1086417D03*
X1572441Y1082677D03*
X1576181Y1078936D03*
X1579921Y1101376D03*
Y1105117D03*
X1568700Y1097637D03*
X1572441Y1101376D03*
X1576181Y1097637D03*
X1572441Y1105117D03*
X1564960D03*
X1576181Y1097637D03*
X1568700D03*
X1576181Y1105117D03*
X1568700D03*
X1564960Y1093897D03*
Y1097637D03*
X1572441Y1093897D03*
Y1097637D03*
X1576181Y1101377D03*
X1568700D03*
X1576181Y1093897D03*
X1568700D03*
X1572441Y1101376D03*
Y1105117D03*
X1564960Y1101376D03*
X1566830Y1121948D03*
X1578051Y1118208D03*
X1574311D03*
Y1121948D03*
X1578051D03*
X1570571Y1118208D03*
X1566830D03*
X1570571Y1121948D03*
X1576181Y1108858D03*
X1572441D03*
X1568700D03*
X1564960D03*
X1574311Y1114468D03*
X1570571D03*
X1578051D03*
X1566830D03*
Y1133169D03*
Y1129429D03*
X1570571Y1140649D03*
X1574311D03*
X1578051D03*
X1570571Y1125688D03*
X1574311D03*
X1578051D03*
X1566830D03*
X1578051Y1133169D03*
X1574311D03*
X1570571D03*
X1566830Y1136909D03*
X1578051D03*
X1574311D03*
X1570571D03*
X1574311Y1129429D03*
X1570571D03*
X1578051D03*
X1566830Y1140649D03*
X1574311Y1148129D03*
X1570571D03*
X1578051D03*
X1570571Y1155610D03*
X1566830Y1151869D03*
X1578051Y1155610D03*
X1566830Y1144389D03*
X1578051D03*
X1574311D03*
X1570571D03*
X1578051Y1151870D03*
X1574311D03*
X1570571D03*
X1574311Y1155610D03*
X1566830Y1148129D03*
Y1155610D03*
Y1159350D03*
X1578051Y1166830D03*
X1574311Y1159350D03*
X1570571Y1166830D03*
X1566830Y1170570D03*
X1574311D03*
X1578051D03*
X1574311Y1166830D03*
X1570571Y1170570D03*
X1566830Y1166830D03*
X1578051Y1159350D03*
X1570571D03*
X1578051Y1181791D03*
X1574311D03*
X1570571D03*
X1578051Y1189271D03*
X1574311D03*
X1570571D03*
X1566830D03*
Y1178051D03*
X1570571Y1174310D03*
X1566830Y1185531D03*
X1578051Y1174310D03*
X1574311Y1185531D03*
X1570571D03*
X1578051D03*
Y1178051D03*
X1574311D03*
X1570571D03*
X1574311Y1174310D03*
X1566830Y1181791D03*
Y1174310D03*
X1574311Y1204232D03*
X1578051D03*
Y1196751D03*
X1574311D03*
X1570571D03*
X1566830Y1200491D03*
Y1196751D03*
Y1193011D03*
Y1204232D03*
X1570571D03*
Y1193011D03*
X1574311D03*
X1578051D03*
X1570571Y1200491D03*
X1578051D03*
X1574311D03*
X1566830Y1207972D03*
Y1211712D03*
X1578051Y1207972D03*
X1574311D03*
X1570571D03*
X1564960Y1221062D03*
X1568700D03*
X1572441D03*
X1576181D03*
X1578051Y1215452D03*
X1566830D03*
X1570571Y1211712D03*
X1566830Y1219192D03*
X1574311Y1215452D03*
X1570571D03*
X1578051Y1211712D03*
X1574311D03*
X1579921Y1224803D03*
Y1228543D03*
X1568700Y1236023D03*
Y1232283D03*
X1576181D03*
Y1236023D03*
X1572441Y1228543D03*
Y1224803D03*
Y1228543D03*
X1568700Y1236023D03*
X1564960Y1224803D03*
X1576181Y1236023D03*
X1564960Y1232283D03*
Y1236023D03*
X1576181Y1224803D03*
Y1228543D03*
X1572441Y1232283D03*
Y1236023D03*
X1568700Y1228543D03*
Y1224803D03*
X1572441D03*
X1564960Y1228543D03*
X1576181Y1232283D03*
X1568700D03*
Y1254724D03*
Y1250984D03*
X1576181D03*
Y1254724D03*
X1572441Y1247243D03*
Y1243503D03*
X1579921D03*
Y1247243D03*
X1564960Y1250984D03*
Y1254724D03*
Y1239763D03*
X1572441Y1250984D03*
Y1254724D03*
X1576181Y1247243D03*
Y1243503D03*
X1572441Y1239763D03*
X1576181D03*
X1568700Y1247243D03*
Y1243503D03*
Y1239763D03*
Y1254724D03*
X1572441Y1247243D03*
X1576181Y1254724D03*
X1564960Y1243503D03*
Y1247243D03*
X1576181Y1250984D03*
X1572441Y1243503D03*
X1568700Y1250984D03*
X1576181Y1258465D03*
X1568701D03*
X1564930Y1348187D03*
X1569290D03*
X1577170D03*
X1569290Y1360099D03*
X1577170D03*
X1564930D03*
X1577170Y1372385D03*
Y1384297D03*
X1569290Y1372385D03*
Y1384297D03*
X1564930D03*
Y1372385D03*
X1577170Y1396583D03*
X1569290D03*
X1564930D03*
X1577170Y1408495D03*
X1569290D03*
X1564930D03*
X1591141Y1075196D03*
X1583661D03*
X1579921D03*
X1587401D03*
X1594882D03*
X1591140Y1071455D03*
X1583660D03*
X1583661Y1075196D03*
X1591141D03*
X1587401Y1086417D03*
Y1082677D03*
X1591141Y1078936D03*
X1594882Y1082677D03*
Y1086417D03*
X1583661Y1078936D03*
X1591141Y1093897D03*
X1583661D03*
X1579921Y1090157D03*
X1583661D03*
Y1086417D03*
Y1082677D03*
X1579921Y1078936D03*
X1587401Y1090157D03*
Y1078936D03*
X1591141Y1082677D03*
Y1086417D03*
Y1090157D03*
X1594882D03*
Y1078936D03*
Y1082677D03*
X1579921D03*
X1583661Y1078936D03*
X1594882Y1086417D03*
X1587401Y1082677D03*
X1579921Y1086417D03*
X1587401D03*
X1591141Y1078936D03*
X1594881Y1101376D03*
Y1105117D03*
X1587401Y1101376D03*
X1591141Y1097637D03*
X1583661D03*
X1587401Y1105117D03*
X1594881D03*
X1591141Y1097637D03*
X1583661Y1093897D03*
X1594881Y1101376D03*
X1583661Y1097637D03*
Y1105117D03*
X1591141D03*
X1579921Y1093897D03*
Y1097637D03*
X1583661Y1101377D03*
X1587401Y1097637D03*
Y1093897D03*
X1594882D03*
Y1097637D03*
X1591141Y1101377D03*
X1587401Y1105117D03*
X1579921Y1101376D03*
X1591141Y1093897D03*
X1587401Y1101376D03*
X1579921Y1105117D03*
X1581791Y1121948D03*
X1585531Y1118208D03*
X1589271D03*
X1593011D03*
X1589271Y1121948D03*
X1593011D03*
X1585531D03*
X1581791Y1118208D03*
X1585531Y1114468D03*
X1594882Y1108858D03*
X1591141D03*
X1587401D03*
X1583661D03*
X1579921D03*
X1587401Y1112598D03*
X1593012Y1114468D03*
X1589271D03*
X1581791D03*
Y1133169D03*
Y1140649D03*
X1585531D03*
X1589271D03*
X1593011D03*
X1589271Y1125688D03*
X1585531D03*
X1581791D03*
X1593011D03*
Y1133169D03*
X1589271D03*
X1585531D03*
X1593011Y1136909D03*
X1589271D03*
X1585531D03*
X1581791D03*
X1589271Y1129429D03*
X1585531D03*
X1581791D03*
X1593011D03*
Y1148129D03*
X1589271D03*
X1585531D03*
X1581791D03*
X1593011Y1155610D03*
X1585531D03*
Y1144389D03*
X1581791D03*
X1593011D03*
X1589271D03*
X1593012Y1151870D03*
X1589271D03*
X1585531D03*
X1581791D03*
Y1155610D03*
X1589271D03*
Y1170570D03*
X1593012Y1166830D03*
X1585531D03*
X1581791Y1159350D03*
X1589271D03*
X1581791Y1170570D03*
X1593011D03*
X1585531D03*
X1589271Y1166830D03*
X1581791D03*
X1585531Y1159350D03*
X1593011D03*
Y1181791D03*
X1589271D03*
X1585531D03*
X1581791D03*
X1593011Y1189271D03*
X1589271D03*
X1585531D03*
X1581791D03*
X1585531Y1174310D03*
X1593011D03*
X1589271Y1185531D03*
X1585531D03*
X1581791D03*
X1593011D03*
X1581791Y1178051D03*
X1593011D03*
X1589271D03*
X1585531D03*
X1589271Y1174310D03*
X1581791D03*
X1593011Y1204232D03*
Y1196751D03*
X1589271D03*
X1585531D03*
X1581791D03*
Y1204232D03*
X1585531D03*
X1589271D03*
X1585531Y1193011D03*
X1589271D03*
X1593011D03*
X1581791D03*
X1589271Y1200491D03*
X1585531D03*
X1581791D03*
X1593011D03*
Y1219192D03*
X1591141Y1217322D03*
X1593011Y1207972D03*
X1589271D03*
X1585531D03*
X1589271Y1211712D03*
X1581791Y1207972D03*
Y1211712D03*
X1591141Y1221062D03*
X1587401D03*
X1579921D03*
X1583661D03*
X1594882D03*
X1593012Y1211712D03*
Y1215452D03*
X1581791D03*
X1589271D03*
X1585531D03*
Y1211712D03*
X1594882Y1224803D03*
Y1228543D03*
X1591141Y1232283D03*
Y1236023D03*
X1587401Y1228543D03*
Y1224803D03*
X1583661Y1236023D03*
Y1232283D03*
X1594882Y1224803D03*
X1591141Y1232283D03*
X1583661Y1236023D03*
X1579921Y1228543D03*
X1583661Y1232283D03*
X1594882Y1228543D03*
X1583661Y1224803D03*
Y1228543D03*
X1579921Y1232283D03*
Y1236023D03*
X1594882Y1232283D03*
Y1236023D03*
X1591141Y1228543D03*
Y1224803D03*
X1587401Y1232283D03*
Y1236023D03*
X1579921Y1224803D03*
X1587401Y1228543D03*
Y1224803D03*
X1591141Y1236023D03*
X1594882Y1243503D03*
Y1247243D03*
X1591141Y1250984D03*
Y1254724D03*
X1587401Y1247243D03*
Y1243503D03*
X1583661Y1254724D03*
Y1250984D03*
Y1243503D03*
Y1247243D03*
X1579921Y1254724D03*
Y1250984D03*
Y1239763D03*
X1583661D03*
X1587401Y1250984D03*
Y1254724D03*
X1591141Y1247243D03*
Y1243503D03*
X1594882Y1250984D03*
Y1254724D03*
Y1239763D03*
X1591141D03*
X1587401D03*
X1583661Y1254724D03*
X1579921Y1247243D03*
X1591141Y1254724D03*
X1587401Y1247243D03*
Y1243503D03*
X1594882D03*
X1579921D03*
X1594882Y1247243D03*
X1583661Y1250984D03*
X1591141D03*
X1591142Y1258465D03*
X1583661D03*
X1589410Y1348187D03*
X1581530D03*
X1589410Y1360099D03*
X1581530D03*
Y1384297D03*
Y1372385D03*
X1589410Y1384297D03*
Y1372385D03*
X1581530Y1396583D03*
X1589410D03*
X1581530Y1408495D03*
X1589410D03*
X1613581Y1075196D03*
X1606101Y1075195D03*
X1598622Y1075196D03*
X1609842D03*
X1602362D03*
X1606101Y1071454D03*
X1598621Y1071455D03*
X1606101Y1075195D03*
X1598622Y1075196D03*
X1602362Y1082677D03*
Y1086417D03*
X1609841Y1082676D03*
Y1086416D03*
X1606101Y1078935D03*
X1598622Y1078936D03*
X1613581D03*
Y1093897D03*
X1606101D03*
X1598622D03*
Y1082677D03*
Y1086417D03*
Y1090157D03*
X1606102Y1082677D03*
Y1086417D03*
X1609842Y1090157D03*
X1606102D03*
X1609842Y1078936D03*
X1602362Y1090157D03*
Y1078936D03*
X1609841Y1086416D03*
X1606101Y1078935D03*
X1609841Y1082676D03*
X1602362Y1082677D03*
Y1086417D03*
X1598622Y1078936D03*
X1613581Y1097637D03*
X1609842Y1101376D03*
Y1105117D03*
X1602362Y1101376D03*
X1606101Y1097637D03*
X1598622D03*
X1602362Y1105117D03*
X1606101Y1093897D03*
X1602362Y1101376D03*
X1598622Y1097637D03*
Y1105117D03*
X1606102D03*
X1598622Y1101377D03*
X1606102D03*
X1609842Y1093897D03*
Y1097637D03*
X1602362Y1093897D03*
Y1097637D03*
X1598622Y1093897D03*
X1602362Y1105117D03*
X1609842Y1101376D03*
Y1105117D03*
X1606101Y1097637D03*
X1596752Y1121948D03*
X1600492Y1118208D03*
Y1114468D03*
X1611712Y1121948D03*
X1607972D03*
X1596752Y1118208D03*
X1600492Y1121948D03*
X1609842Y1108858D03*
X1606102D03*
X1602362D03*
X1598622D03*
X1596752Y1114468D03*
X1607972D03*
X1611712Y1118208D03*
X1607972D03*
X1611712Y1114468D03*
X1607972Y1125688D03*
X1611712D03*
X1607972Y1133464D03*
X1611712Y1133169D03*
X1600590Y1132677D03*
X1596752Y1133169D03*
Y1140649D03*
X1600492D03*
Y1125688D03*
X1596752D03*
X1607972Y1140649D03*
X1611712D03*
X1600492Y1136909D03*
X1596752D03*
X1611712D03*
X1607972D03*
X1611712Y1129429D03*
X1607972D03*
X1600492D03*
X1596752D03*
X1600492Y1148129D03*
X1596752D03*
X1607972D03*
X1611712D03*
X1600492Y1155610D03*
X1611712D03*
X1600492Y1144389D03*
X1596752D03*
X1611712Y1151869D03*
X1607972D03*
X1611712Y1144389D03*
X1607972D03*
X1600492Y1151870D03*
X1596752D03*
Y1155610D03*
X1607972D03*
X1596752Y1170570D03*
Y1159350D03*
X1611712Y1166830D03*
X1607972Y1170570D03*
X1600492Y1166830D03*
X1607972Y1159350D03*
Y1166830D03*
X1611712Y1170570D03*
X1600492D03*
X1596752Y1166830D03*
X1611712Y1159350D03*
X1600492D03*
Y1181791D03*
X1611712D03*
X1607972D03*
Y1189271D03*
X1611712D03*
X1596752Y1181791D03*
X1600492Y1189271D03*
X1596752D03*
X1600492Y1174310D03*
X1611712D03*
X1600492Y1185531D03*
X1596752D03*
X1600492Y1178051D03*
X1596752D03*
X1611712Y1185531D03*
X1607972D03*
X1611712Y1178051D03*
X1607972D03*
Y1174310D03*
X1596752D03*
X1611712Y1204232D03*
X1607972D03*
Y1196751D03*
X1611712D03*
X1600492D03*
X1596752D03*
Y1204232D03*
X1600492D03*
X1607972Y1193011D03*
X1611712D03*
X1600492D03*
X1596752D03*
X1600492Y1200491D03*
X1596752D03*
X1611712D03*
X1607972D03*
X1606102Y1221062D03*
X1596752Y1207972D03*
X1607972D03*
X1611712D03*
Y1211712D03*
X1596752Y1219192D03*
X1600492Y1207972D03*
X1598622Y1221062D03*
X1609842D03*
X1602362D03*
X1600492Y1211712D03*
Y1215452D03*
X1596752Y1211712D03*
X1611712Y1215452D03*
X1607972D03*
Y1211712D03*
X1609842Y1217322D03*
Y1228543D03*
X1613582Y1236023D03*
Y1232283D03*
X1609842Y1224803D03*
X1602362Y1228543D03*
Y1224803D03*
X1606102Y1232283D03*
Y1236023D03*
X1598622Y1232283D03*
Y1236023D03*
D03*
X1606102D03*
X1609842Y1228543D03*
X1606102Y1232283D03*
X1602362Y1224803D03*
X1609842D03*
X1598622Y1228543D03*
Y1224803D03*
X1609842Y1232283D03*
Y1236023D03*
X1606102Y1228543D03*
Y1224803D03*
X1602362Y1232283D03*
Y1236023D03*
Y1228543D03*
X1598622Y1232283D03*
X1602362Y1247243D03*
Y1243503D03*
X1609842D03*
Y1247243D03*
X1606102Y1250984D03*
Y1254724D03*
X1598622D03*
Y1250984D03*
X1613582Y1254724D03*
Y1250984D03*
X1598622Y1239763D03*
Y1243503D03*
Y1247243D03*
X1609842Y1254724D03*
Y1250984D03*
X1606102Y1247243D03*
Y1243503D03*
Y1239763D03*
X1609842D03*
X1602362D03*
Y1250984D03*
Y1254724D03*
X1598622D03*
Y1250984D03*
X1609842Y1247243D03*
X1606102Y1250984D03*
Y1254724D03*
X1609842Y1243503D03*
X1602362Y1247243D03*
Y1243503D03*
X1606102Y1258465D03*
X1598623D03*
X1609158Y1348187D03*
Y1360099D03*
Y1384297D03*
Y1372385D03*
X1628542Y1075196D03*
X1621062D03*
X1624803D03*
X1617322D03*
X1621062Y1071455D03*
X1613581D03*
Y1075196D03*
X1621062D03*
X1624802Y1082676D03*
Y1086416D03*
X1621062Y1078936D03*
X1617321Y1086417D03*
Y1082677D03*
X1628542Y1078936D03*
Y1093897D03*
X1621062D03*
X1617322Y1090157D03*
Y1078936D03*
X1613582Y1090157D03*
Y1086417D03*
Y1082677D03*
X1624803Y1078936D03*
X1621063Y1082677D03*
Y1086417D03*
Y1090157D03*
X1624803D03*
X1613581Y1078936D03*
X1624802Y1082676D03*
X1617321Y1082677D03*
X1621062Y1078936D03*
X1617321Y1086417D03*
X1624802Y1086416D03*
X1628542Y1097637D03*
X1617322Y1105117D03*
X1624803D03*
Y1101376D03*
X1621062Y1097637D03*
X1617322Y1101376D03*
X1621062Y1093897D03*
X1617322Y1105117D03*
Y1093897D03*
Y1097637D03*
X1624803Y1093897D03*
Y1097637D03*
X1621063Y1101377D03*
Y1105117D03*
X1613582D03*
Y1101377D03*
X1617322Y1101376D03*
X1613581Y1093897D03*
Y1097637D03*
X1624803Y1101376D03*
Y1105117D03*
X1621062Y1097637D03*
X1626673Y1121948D03*
X1622933D03*
X1619193D03*
X1615452D03*
X1624803Y1108858D03*
X1621063D03*
X1617322D03*
X1613582D03*
X1615452Y1118208D03*
X1619193D03*
X1615452Y1114468D03*
X1619193D03*
X1622933D03*
X1626673D03*
Y1118208D03*
X1622933D03*
X1615452Y1133169D03*
X1619193D03*
X1622933D03*
X1626673D03*
X1615452Y1140649D03*
X1619193D03*
X1622933D03*
X1626673D03*
X1615452Y1125688D03*
X1619193D03*
X1622933D03*
X1626673D03*
Y1136909D03*
X1622933D03*
X1615452D03*
X1619193D03*
X1626673Y1129429D03*
X1622933D03*
X1619193D03*
X1615452D03*
Y1148129D03*
X1619193D03*
X1622933D03*
X1626673D03*
X1619193Y1155610D03*
X1626673D03*
X1615452Y1151869D03*
X1619193D03*
X1626673D03*
X1622933D03*
Y1144389D03*
X1615452D03*
X1619193D03*
X1626673D03*
X1622933Y1155610D03*
X1615452D03*
Y1170570D03*
X1622933D03*
X1626673Y1166830D03*
X1615452Y1159350D03*
X1619193Y1166830D03*
X1622933Y1159350D03*
X1615452Y1166830D03*
X1619193Y1170570D03*
X1626673Y1159350D03*
X1619193D03*
X1622933Y1166830D03*
X1626673Y1170570D03*
X1615452Y1181791D03*
X1619193D03*
X1622933D03*
X1626673D03*
X1615452Y1189271D03*
X1619193D03*
X1622933D03*
X1626673D03*
Y1174310D03*
X1619193D03*
Y1185531D03*
X1626673D03*
X1622933D03*
Y1178051D03*
X1615452D03*
X1619193D03*
X1626673D03*
X1615452Y1185531D03*
X1622933Y1174310D03*
X1615452D03*
X1619193Y1204232D03*
X1615452D03*
X1626673D03*
X1622933D03*
X1615452Y1196751D03*
X1619193D03*
X1622933D03*
X1626673D03*
X1622933Y1193011D03*
X1626673D03*
X1615452D03*
X1619193D03*
X1622933Y1200491D03*
X1619193D03*
X1615452D03*
X1626673D03*
X1617322Y1221062D03*
X1619193Y1207972D03*
X1622933D03*
X1626673Y1211712D03*
Y1207972D03*
X1615452Y1211712D03*
Y1207972D03*
X1621063Y1221062D03*
X1613582D03*
X1624803D03*
X1622933Y1215452D03*
X1619192Y1215451D03*
X1626673Y1215452D03*
X1615452D03*
X1613582Y1217322D03*
X1619192Y1211711D03*
X1622933D03*
X1628543Y1236023D03*
Y1232283D03*
X1617322Y1228543D03*
Y1224803D03*
X1624803D03*
Y1228543D03*
X1621063Y1232283D03*
Y1236023D03*
X1617322Y1228543D03*
X1624803Y1224803D03*
X1617322D03*
X1621063Y1236023D03*
X1613582D03*
X1621063Y1232283D03*
X1613582Y1228543D03*
Y1224803D03*
X1621063Y1228543D03*
Y1224803D03*
X1624803Y1232283D03*
Y1236023D03*
X1617322Y1232283D03*
Y1236023D03*
X1624803Y1228543D03*
X1613582Y1232283D03*
X1617322Y1243503D03*
Y1247243D03*
X1624803D03*
Y1243503D03*
X1621063Y1250984D03*
Y1254724D03*
X1628543D03*
Y1250984D03*
X1613582Y1239763D03*
Y1243503D03*
Y1247243D03*
X1621063Y1239763D03*
Y1243503D03*
Y1247243D03*
X1624803Y1239763D03*
Y1250984D03*
Y1254724D03*
X1617322Y1239763D03*
Y1250984D03*
Y1254724D03*
X1624803Y1247243D03*
Y1243503D03*
X1621063Y1254724D03*
X1613582Y1250984D03*
X1617322Y1243503D03*
Y1247243D03*
X1613582Y1254724D03*
X1621063Y1250984D03*
Y1258465D03*
X1613582D03*
X1617038Y1348187D03*
X1621398D03*
X1617038Y1360099D03*
X1621398D03*
X1617038Y1384297D03*
Y1372385D03*
X1621398D03*
Y1384297D03*
Y1396583D03*
Y1408495D03*
X1643503Y1075196D03*
X1636022D03*
X1639763D03*
X1632283D03*
X1643503Y1071455D03*
X1636022D03*
X1628542D03*
X1636022Y1075196D03*
X1643503D03*
X1628542D03*
X1632282Y1086417D03*
Y1082677D03*
X1636022Y1078936D03*
X1639762Y1082676D03*
Y1086416D03*
X1643503Y1078936D03*
Y1093897D03*
X1636022D03*
X1636023Y1090157D03*
X1643504Y1082677D03*
X1636023D03*
Y1086417D03*
X1643504Y1090157D03*
Y1086417D03*
X1639763Y1090157D03*
Y1078936D03*
X1632283D03*
X1628543Y1082677D03*
Y1086417D03*
Y1090157D03*
X1632283D03*
X1632282Y1082677D03*
X1643503Y1078936D03*
X1628542D03*
X1639762Y1086416D03*
X1632282Y1086417D03*
X1636022Y1078936D03*
X1639762Y1082676D03*
X1643503Y1097637D03*
X1639763Y1105117D03*
X1632283D03*
Y1101376D03*
X1636022Y1097637D03*
X1639763Y1101376D03*
D03*
X1628542Y1093897D03*
X1636022D03*
X1632283D03*
X1636023Y1101377D03*
X1643504D03*
X1628543D03*
X1632283Y1097637D03*
X1639763Y1093897D03*
Y1097637D03*
X1628543Y1105117D03*
X1636023D03*
X1643504D03*
X1639763D03*
X1632283D03*
Y1101376D03*
X1636022Y1097637D03*
X1643503D03*
Y1093897D03*
X1628542Y1097637D03*
X1641633Y1118208D03*
X1637893Y1121948D03*
X1634153D03*
X1630413D03*
X1641633D03*
X1643504Y1108858D03*
X1639763D03*
X1636023D03*
X1632283D03*
X1628543D03*
X1637893Y1118208D03*
Y1114468D03*
X1634153D03*
X1630413D03*
X1641633D03*
X1634153Y1118208D03*
X1630413D03*
X1641633Y1136909D03*
X1630413Y1133169D03*
X1634153D03*
X1637893D03*
X1641633D03*
X1634153Y1140649D03*
X1637893D03*
X1641633Y1125688D03*
Y1129429D03*
X1630413Y1125688D03*
X1634153D03*
X1637893D03*
X1641633Y1140649D03*
X1630413D03*
Y1136909D03*
X1637893D03*
X1634153D03*
X1630413Y1129429D03*
X1637893D03*
X1634153D03*
X1630413Y1148129D03*
X1634153D03*
X1637893D03*
X1641633Y1144389D03*
Y1148129D03*
Y1151869D03*
X1634153Y1155610D03*
X1641633D03*
X1630413Y1151869D03*
X1637893D03*
X1634153D03*
Y1144389D03*
X1630413D03*
X1637893D03*
Y1155610D03*
X1630413D03*
X1634153Y1166830D03*
X1630413Y1159350D03*
Y1170570D03*
X1637893D03*
X1641633D03*
X1634153D03*
X1641633Y1166830D03*
X1637893D03*
Y1159350D03*
X1641633D03*
X1634153D03*
X1630413Y1166830D03*
X1634153Y1189271D03*
X1637893D03*
X1641633Y1178051D03*
X1634153Y1174310D03*
X1641633Y1185531D03*
X1630413Y1181791D03*
X1634153D03*
X1637893D03*
X1641633Y1189271D03*
X1630413D03*
X1641633Y1174310D03*
Y1181791D03*
X1630413Y1185531D03*
X1634153D03*
X1630413Y1178051D03*
X1634153D03*
X1637893Y1185531D03*
Y1178051D03*
Y1174310D03*
X1630413D03*
X1641653Y1196732D03*
X1641633Y1204232D03*
X1630413D03*
X1634153D03*
X1637893D03*
X1641633Y1200491D03*
X1630413Y1196751D03*
X1634153D03*
X1637893D03*
X1641633Y1193011D03*
X1634153D03*
X1637893D03*
X1630413D03*
Y1200491D03*
X1637893D03*
X1634153D03*
X1641633Y1211712D03*
X1634153Y1207972D03*
X1630413D03*
X1634153Y1211712D03*
X1637893Y1207972D03*
Y1211712D03*
X1630413D03*
X1641633Y1207972D03*
X1628543Y1221062D03*
X1632283D03*
X1636023D03*
X1639763D03*
X1643504D03*
X1630413Y1215452D03*
X1637893D03*
X1634153D03*
X1643504Y1232283D03*
Y1236023D03*
X1639763Y1228543D03*
Y1224803D03*
X1636023Y1232283D03*
Y1236023D03*
X1632283Y1228543D03*
Y1224803D03*
Y1228543D03*
X1628543Y1236023D03*
Y1232283D03*
X1639763Y1224803D03*
X1636023Y1236023D03*
X1628543Y1228543D03*
Y1224803D03*
X1632283Y1232283D03*
Y1236023D03*
X1636023Y1228543D03*
Y1224803D03*
X1639763Y1232283D03*
Y1236023D03*
X1643504Y1228543D03*
Y1224803D03*
Y1232283D03*
X1632283Y1224803D03*
X1643504Y1236023D03*
X1636023Y1232283D03*
X1639763Y1228543D03*
X1643504Y1254724D03*
Y1250984D03*
X1639763Y1247243D03*
Y1243503D03*
X1636023Y1250984D03*
Y1254724D03*
X1632283Y1243503D03*
Y1247243D03*
Y1254724D03*
X1628543Y1247243D03*
Y1243503D03*
X1632283Y1239763D03*
Y1250984D03*
X1628543Y1239763D03*
X1636023Y1247243D03*
X1639763Y1250984D03*
Y1254724D03*
X1643504Y1247243D03*
X1636023Y1239763D03*
X1643504D03*
X1639763D03*
X1636023Y1243503D03*
X1643504D03*
X1632283D03*
X1636023Y1254724D03*
X1639763Y1243503D03*
X1636023Y1250984D03*
X1632283Y1247243D03*
X1643504Y1250984D03*
X1628543D03*
X1639763Y1247243D03*
X1628543Y1254724D03*
X1643504D03*
Y1258465D03*
X1636023D03*
X1628543D03*
X1629278Y1348187D03*
X1641518D03*
X1633638D03*
X1629278Y1360099D03*
X1641518D03*
X1633638D03*
X1629278Y1384297D03*
Y1372385D03*
X1641518Y1384297D03*
Y1372385D03*
X1633638Y1384297D03*
Y1372385D03*
X1629278Y1396583D03*
X1641518D03*
X1633638D03*
Y1408495D03*
X1629278D03*
X1641518D03*
X1658463Y1075196D03*
X1650983D03*
X1647244D03*
X1654724D03*
X1658463Y1071455D03*
X1650983D03*
Y1075196D03*
X1658463D03*
X1650983Y1078936D03*
X1654723Y1082676D03*
Y1086416D03*
X1658463Y1078936D03*
X1647242Y1086417D03*
Y1082677D03*
X1662203Y1086417D03*
Y1082677D03*
X1658463Y1093897D03*
X1650983D03*
X1654724Y1078936D03*
Y1090157D03*
X1658464D03*
Y1086417D03*
Y1082677D03*
X1650984D03*
Y1086417D03*
Y1090157D03*
X1647244D03*
Y1078936D03*
X1654723Y1086416D03*
Y1082676D03*
X1650983Y1078936D03*
X1647242Y1082677D03*
Y1086417D03*
X1658463Y1078936D03*
X1662204Y1105117D03*
Y1101376D03*
X1658463Y1097637D03*
X1654724Y1105117D03*
X1650983Y1097637D03*
X1647244Y1105117D03*
X1654724Y1101376D03*
X1647244D03*
X1658463Y1097637D03*
X1647244Y1101376D03*
Y1097637D03*
Y1093897D03*
X1654724Y1097637D03*
X1658464Y1101377D03*
X1654724Y1093897D03*
X1650984Y1101377D03*
X1658464Y1105117D03*
X1650984D03*
X1658463Y1093897D03*
X1654724Y1105117D03*
X1650983Y1093897D03*
X1647244Y1105117D03*
X1654724Y1101376D03*
X1650983Y1097637D03*
X1645374Y1118208D03*
X1649114D03*
Y1121948D03*
X1645374D03*
X1658464Y1108858D03*
X1654724D03*
X1650984D03*
X1647244D03*
X1656594Y1118208D03*
X1652854D03*
Y1114468D03*
X1645374D03*
X1649114D03*
X1656594D03*
X1649114Y1133169D03*
Y1140649D03*
X1652854Y1136909D03*
X1649114Y1125688D03*
X1645374D03*
X1649114Y1129429D03*
Y1136909D03*
X1652854Y1140649D03*
X1645374Y1129429D03*
Y1136909D03*
Y1140649D03*
X1656594Y1133169D03*
Y1140649D03*
Y1136909D03*
X1660334Y1140649D03*
X1645374Y1155610D03*
Y1151869D03*
Y1148129D03*
X1652854D03*
X1649114Y1144389D03*
X1652854Y1155610D03*
X1649114Y1148129D03*
X1652854Y1151869D03*
X1656594D03*
X1660334D03*
Y1155610D03*
Y1144389D03*
X1649114Y1151870D03*
Y1155610D03*
X1656594D03*
X1645374Y1144389D03*
X1660334Y1148129D03*
X1652854Y1144389D03*
X1656594Y1148129D03*
Y1144389D03*
X1645374Y1166830D03*
X1652854Y1159350D03*
X1660334Y1166830D03*
Y1170570D03*
X1645374Y1159350D03*
X1660334D03*
X1645374Y1170570D03*
X1652854D03*
Y1166830D03*
X1649114Y1159350D03*
Y1170570D03*
Y1166830D03*
X1656594Y1170570D03*
Y1166830D03*
Y1159350D03*
X1652854Y1185531D03*
X1656594Y1181791D03*
X1652854Y1178051D03*
Y1174310D03*
X1649114Y1181791D03*
X1656594Y1185531D03*
X1660334Y1174310D03*
Y1178051D03*
Y1185531D03*
X1645374Y1181791D03*
Y1174310D03*
X1649114Y1178051D03*
Y1189271D03*
X1652854D03*
X1649114Y1185531D03*
X1656594Y1189271D03*
X1649114Y1174310D03*
X1656594D03*
X1652854Y1181791D03*
X1660334Y1189271D03*
X1645374Y1185531D03*
Y1189271D03*
X1660334Y1181791D03*
X1656594Y1178051D03*
X1645374D03*
Y1204232D03*
X1656594Y1193011D03*
X1652854Y1204232D03*
X1660334D03*
Y1200491D03*
Y1193011D03*
X1652854Y1196751D03*
Y1193011D03*
X1649114D03*
X1645374Y1196751D03*
X1660334D03*
X1645374Y1200491D03*
Y1193011D03*
X1656594Y1196751D03*
Y1204232D03*
X1652854Y1200491D03*
X1649114Y1204232D03*
Y1196751D03*
Y1200491D03*
X1656594D03*
X1649114Y1211712D03*
X1645374Y1207972D03*
X1660334D03*
Y1215452D03*
Y1211712D03*
X1654724Y1221062D03*
X1658464D03*
X1650984D03*
X1647244D03*
X1645374Y1215452D03*
X1649114D03*
X1652854D03*
X1656594Y1211712D03*
X1645374D03*
X1656594Y1215452D03*
Y1207972D03*
X1649114D03*
X1652854D03*
Y1211712D03*
X1662204Y1224803D03*
Y1228543D03*
X1658464Y1236023D03*
Y1232283D03*
X1650984D03*
Y1236023D03*
X1654724Y1228543D03*
Y1224803D03*
X1647244D03*
Y1228543D03*
X1654724D03*
X1647244D03*
X1658464Y1232283D03*
X1647244D03*
Y1236023D03*
X1654724Y1232283D03*
X1658464Y1228543D03*
X1654724Y1236023D03*
X1658464Y1224803D03*
X1650984Y1228543D03*
Y1224803D03*
X1654724D03*
X1658464Y1236023D03*
X1650984D03*
X1647244Y1224803D03*
X1650984Y1232283D03*
Y1250984D03*
Y1254724D03*
X1654724Y1243503D03*
X1658464Y1250984D03*
Y1254724D03*
X1654724Y1247243D03*
X1647244Y1243503D03*
Y1247243D03*
X1662204D03*
Y1243503D03*
X1647244Y1254724D03*
Y1250984D03*
Y1239763D03*
X1654724Y1250984D03*
Y1254724D03*
X1658464Y1247243D03*
X1654724Y1239763D03*
X1658464D03*
Y1243503D03*
X1650984Y1247243D03*
Y1239763D03*
Y1243503D03*
X1654724D03*
X1650984Y1250984D03*
X1647244Y1247243D03*
X1654724D03*
X1647244Y1243503D03*
X1650984Y1254724D03*
X1658464D03*
Y1250984D03*
Y1258465D03*
X1650984D03*
X1645878Y1348187D03*
X1653758D03*
X1658118D03*
X1645878Y1360099D03*
X1653758D03*
X1658118D03*
X1645878Y1384297D03*
Y1372385D03*
X1653758D03*
Y1384297D03*
X1658118D03*
Y1372385D03*
X1645878Y1396583D03*
X1653758D03*
X1658118D03*
X1645878Y1408495D03*
X1653758D03*
X1658118D03*
X1665944Y1075196D03*
X1673424D03*
X1662204D03*
X1669685D03*
X1673425Y1071455D03*
X1665944D03*
X1673424Y1075196D03*
X1665944D03*
Y1078936D03*
X1673424D03*
X1669684Y1086416D03*
Y1082676D03*
X1677164Y1082677D03*
Y1086417D03*
X1665944Y1093897D03*
X1673424D03*
X1662204Y1078936D03*
X1662203Y1090157D03*
X1669686Y1078936D03*
X1673424Y1082677D03*
X1673425Y1086417D03*
X1669684Y1090157D03*
X1673424D03*
X1665944Y1082677D03*
X1665945Y1086417D03*
X1665944Y1090157D03*
X1662203Y1086417D03*
Y1082677D03*
X1669684Y1086416D03*
X1665944Y1078936D03*
X1673424D03*
X1669684Y1082676D03*
X1677165Y1105117D03*
Y1101376D03*
X1669685Y1105117D03*
X1665944Y1097637D03*
X1673424D03*
X1669685Y1101376D03*
X1665944Y1093897D03*
X1662204Y1105117D03*
X1669685D03*
X1673424Y1097637D03*
X1669685Y1101376D03*
X1662204Y1093897D03*
Y1097637D03*
X1669685Y1093897D03*
Y1097637D03*
X1673425Y1101377D03*
X1665944D03*
X1673425Y1105117D03*
X1665945D03*
X1673424Y1093897D03*
X1665944Y1097637D03*
X1662204Y1101376D03*
X1665944Y1123818D03*
Y1116338D03*
X1669685Y1123818D03*
Y1116338D03*
X1673425Y1120078D03*
Y1112598D03*
X1677165Y1120078D03*
Y1112598D03*
X1673425D03*
X1665944Y1123818D03*
X1669685Y1108858D03*
X1673425D03*
Y1116338D03*
X1669685Y1112598D03*
Y1120078D03*
X1673425Y1123818D03*
X1665944Y1112598D03*
Y1120078D03*
X1665945Y1108858D03*
X1662204Y1123818D03*
Y1120078D03*
Y1116338D03*
Y1108858D03*
X1673425Y1120078D03*
X1669685Y1123818D03*
X1665944Y1116338D03*
X1669685D03*
X1677165Y1135039D03*
Y1127559D03*
X1673425Y1135039D03*
X1665944Y1131299D03*
X1669685D03*
X1673425Y1127559D03*
X1665944Y1131299D03*
X1675295Y1140649D03*
X1671555D03*
Y1136909D03*
X1669685Y1127558D03*
X1673425Y1131299D03*
X1665945Y1127558D03*
X1669685Y1135039D03*
X1665945D03*
X1662204D03*
Y1131299D03*
Y1127558D03*
Y1138779D03*
X1669685Y1131299D03*
X1673425Y1127559D03*
Y1135039D03*
X1664075Y1140649D03*
X1667815Y1151869D03*
X1664074D03*
X1675295Y1155610D03*
Y1148129D03*
X1671555Y1155610D03*
Y1151869D03*
Y1148129D03*
Y1144389D03*
X1664074D03*
X1667815D03*
Y1155610D03*
X1664075Y1148129D03*
Y1155610D03*
X1675295Y1144389D03*
Y1151869D03*
X1664074Y1159350D03*
X1667815D03*
X1671555D03*
X1667815Y1166830D03*
X1664074D03*
X1675295Y1170570D03*
X1671555D03*
Y1166830D03*
X1675295D03*
Y1159350D03*
X1664075Y1170570D03*
X1667815D03*
X1664074Y1189271D03*
Y1174310D03*
X1671555Y1185531D03*
Y1181791D03*
Y1178051D03*
Y1174310D03*
X1667815D03*
Y1181791D03*
X1664074D03*
X1667815Y1189271D03*
X1675295Y1185531D03*
Y1178051D03*
X1671555Y1189271D03*
X1675295D03*
Y1174310D03*
Y1181791D03*
X1677165Y1202362D03*
X1669685Y1198621D03*
X1673425Y1202362D03*
X1665945Y1198621D03*
X1669685Y1206102D03*
X1665945D03*
Y1194881D03*
X1669685D03*
X1664074Y1204232D03*
X1675295Y1193011D03*
X1671555D03*
X1665945Y1202362D03*
X1669685D03*
X1673425Y1198621D03*
Y1202362D03*
X1665945Y1198621D03*
X1669685D03*
X1665945Y1213582D03*
X1673425Y1209842D03*
X1669685Y1213582D03*
X1673425Y1217322D03*
X1677165Y1209842D03*
Y1217322D03*
X1673425Y1221062D03*
X1669685D03*
Y1217322D03*
X1673425Y1213582D03*
X1669685Y1209842D03*
X1665945Y1221062D03*
Y1217322D03*
Y1209842D03*
X1673425Y1206102D03*
X1662204Y1221062D03*
X1665945Y1206102D03*
X1669685Y1213582D03*
X1673425Y1209842D03*
X1669685Y1206102D03*
X1665945Y1213582D03*
X1673425Y1217322D03*
X1677165Y1228543D03*
Y1224803D03*
X1665945Y1232283D03*
Y1236023D03*
X1673425D03*
Y1232283D03*
X1669685Y1228543D03*
Y1224803D03*
X1662204Y1232283D03*
Y1236023D03*
X1673425Y1224803D03*
Y1228543D03*
X1669685Y1232283D03*
Y1236023D03*
X1665945Y1224803D03*
Y1228543D03*
X1673425Y1236023D03*
X1662204Y1228543D03*
X1669685D03*
X1673425Y1232283D03*
X1665945D03*
Y1236023D03*
X1662204Y1224803D03*
X1669685D03*
Y1243503D03*
Y1247243D03*
X1673425Y1250984D03*
Y1254724D03*
X1665945D03*
Y1250984D03*
X1677165Y1247243D03*
Y1243503D03*
X1665945Y1247243D03*
Y1243503D03*
Y1239763D03*
X1662204Y1250984D03*
Y1254724D03*
Y1239763D03*
X1669685Y1250984D03*
Y1254724D03*
X1673425Y1247243D03*
Y1243503D03*
X1669685Y1239763D03*
X1673425D03*
Y1250984D03*
X1662204Y1247243D03*
X1665945Y1254724D03*
X1673425D03*
X1662204Y1243503D03*
X1665945Y1250984D03*
X1669685Y1247243D03*
Y1243503D03*
X1673425Y1258465D03*
X1665945D03*
X1665998Y1348187D03*
X1670358D03*
X1665998Y1360099D03*
X1670358D03*
X1665998Y1384297D03*
Y1372385D03*
X1670358D03*
Y1384297D03*
X1665998Y1396583D03*
X1670358D03*
X1665998Y1408495D03*
X1670358D03*
X1688384Y1075196D03*
X1680904D03*
X1677166D03*
X1684646D03*
X1692126D03*
X1688385Y1071455D03*
X1680905D03*
X1680904Y1075196D03*
X1688384D03*
X1692126Y1090157D03*
Y1082676D03*
X1684644Y1082677D03*
Y1086417D03*
X1688384Y1078936D03*
X1680904D03*
X1688385Y1093897D03*
X1680904D03*
X1677166Y1078936D03*
X1680904Y1082677D03*
X1680905Y1086417D03*
X1677164Y1090157D03*
X1680904D03*
X1692126Y1078936D03*
X1684646D03*
X1688385Y1082677D03*
X1692126Y1086417D03*
X1688386D03*
X1684644Y1090157D03*
X1688385D03*
X1692126D03*
Y1082676D03*
X1684644Y1082677D03*
Y1086417D03*
X1680904Y1078936D03*
X1688384D03*
X1677164Y1086417D03*
Y1082677D03*
X1692126Y1101377D03*
X1684645Y1105117D03*
Y1101377D03*
X1688385Y1097637D03*
X1680904D03*
X1692126Y1108858D03*
Y1101377D03*
X1684645D03*
X1677165Y1105117D03*
Y1093897D03*
Y1097637D03*
X1680905Y1101377D03*
X1684645Y1093897D03*
Y1097637D03*
X1688385Y1101377D03*
X1692126Y1093897D03*
Y1097637D03*
X1680905Y1105117D03*
X1688386D03*
X1692126D03*
X1680904Y1097637D03*
X1677165Y1101376D03*
X1688385Y1097637D03*
X1684645Y1105117D03*
X1680904Y1093897D03*
X1688385D03*
Y1112598D03*
X1684645D03*
X1692126Y1116338D03*
X1684645Y1120078D03*
X1688385D03*
X1692126Y1123818D03*
X1677165Y1120078D03*
Y1112598D03*
X1677164Y1108857D03*
X1680904Y1108858D03*
X1680905Y1116338D03*
X1677165D03*
X1680905Y1112598D03*
Y1123818D03*
X1677165D03*
X1680905Y1120078D03*
X1684645Y1108858D03*
X1688385D03*
X1684645Y1116338D03*
X1688385D03*
X1692126Y1112598D03*
X1684645Y1123818D03*
X1688385D03*
X1692126Y1120078D03*
Y1116338D03*
Y1108858D03*
X1684645Y1120078D03*
X1688385D03*
X1684645Y1112598D03*
X1692126Y1123818D03*
X1688385Y1112598D03*
X1692126Y1131299D03*
X1688385Y1135039D03*
X1684645D03*
Y1127558D03*
X1688385D03*
X1690256Y1140649D03*
X1686515Y1136909D03*
X1690256D03*
X1682775D03*
X1679035Y1140649D03*
X1680905Y1127558D03*
Y1131299D03*
X1677165D03*
X1692126Y1127558D03*
X1688385Y1131299D03*
X1684644D03*
X1680905Y1135039D03*
X1692126D03*
X1677165D03*
Y1127559D03*
X1684645Y1135039D03*
Y1127558D03*
X1692126Y1131299D03*
X1688385Y1127558D03*
Y1135039D03*
X1686515Y1140649D03*
X1682775D03*
X1690256Y1144389D03*
X1682775D03*
X1679035Y1148129D03*
X1682775Y1151869D03*
X1679035Y1155610D03*
X1686515Y1144389D03*
X1690256Y1155610D03*
X1686515Y1151869D03*
X1690256D03*
Y1148129D03*
X1679035Y1151869D03*
Y1144389D03*
X1682775Y1148129D03*
X1686515Y1155610D03*
Y1148129D03*
X1682775Y1155610D03*
Y1166830D03*
X1679035Y1170570D03*
X1686515Y1159350D03*
X1690256D03*
X1682775D03*
X1679035D03*
X1686515Y1166830D03*
X1690256Y1170570D03*
Y1166830D03*
X1679035D03*
X1686515Y1170570D03*
X1682775D03*
X1690256Y1178051D03*
X1686515Y1174310D03*
X1690256D03*
X1682775D03*
X1679035Y1178051D03*
X1682775Y1181791D03*
X1679035Y1185531D03*
X1682775Y1189271D03*
X1686515Y1181791D03*
Y1189271D03*
X1690256D03*
Y1185531D03*
Y1181791D03*
X1679035D03*
Y1189271D03*
Y1174310D03*
X1686515Y1185531D03*
X1682775Y1178051D03*
X1686515D03*
X1682775Y1185531D03*
X1692126Y1198621D03*
X1684645Y1202362D03*
X1688385D03*
X1692126Y1206102D03*
X1680905Y1194881D03*
X1690256Y1193011D03*
X1679035D03*
X1692126Y1202362D03*
X1688385Y1198621D03*
X1684645D03*
X1680905Y1202362D03*
Y1198621D03*
X1677165D03*
X1684645Y1202362D03*
X1692126Y1198621D03*
X1688385Y1202362D03*
X1677165D03*
X1686515Y1193011D03*
X1682775D03*
X1688385Y1209842D03*
X1684645D03*
Y1217322D03*
X1688385D03*
X1692126Y1221062D03*
Y1213582D03*
Y1217322D03*
X1688385Y1221062D03*
X1684645D03*
X1692126Y1209842D03*
X1688385Y1213582D03*
X1684645D03*
X1680905Y1221062D03*
Y1217322D03*
X1677165Y1221062D03*
Y1213582D03*
X1680905D03*
Y1209842D03*
X1688385Y1206102D03*
X1684645D03*
X1680905D03*
X1677165D03*
X1692126Y1213582D03*
X1684645Y1217322D03*
Y1209842D03*
X1692126Y1206102D03*
X1677165Y1209842D03*
X1692126Y1221062D03*
X1688385Y1209842D03*
X1677165Y1217322D03*
X1688385D03*
X1692126Y1228543D03*
X1680905Y1232283D03*
Y1236023D03*
X1688385D03*
Y1232283D03*
X1684645Y1228543D03*
Y1224803D03*
X1692126Y1239763D03*
Y1224803D03*
X1688385D03*
Y1228543D03*
X1684645Y1236023D03*
Y1232283D03*
X1692126D03*
Y1236023D03*
X1680905Y1224803D03*
Y1228543D03*
X1677165Y1232283D03*
Y1236023D03*
X1682775Y1222932D03*
X1677165Y1228543D03*
X1680905Y1236023D03*
Y1232283D03*
X1692126Y1228543D03*
X1684645Y1224803D03*
Y1228543D03*
X1677165Y1224803D03*
X1688385Y1232283D03*
Y1236023D03*
X1680905Y1254724D03*
Y1250984D03*
X1684645Y1243503D03*
Y1247243D03*
X1688385Y1254724D03*
Y1250984D03*
X1692126Y1247243D03*
X1684645Y1250984D03*
Y1254724D03*
X1692126Y1250984D03*
X1688385Y1247243D03*
Y1243503D03*
X1692126D03*
X1684645Y1239763D03*
X1688385D03*
X1692126Y1254724D03*
X1677165Y1250984D03*
Y1254724D03*
X1680905Y1247243D03*
Y1243503D03*
X1677165Y1239763D03*
X1680905D03*
X1684645Y1243503D03*
X1677165D03*
X1692126Y1247243D03*
X1684645D03*
X1677165D03*
X1688385Y1254724D03*
Y1250984D03*
X1692126Y1239763D03*
X1680905Y1254724D03*
Y1250984D03*
X1688385Y1258465D03*
X1680905D03*
X1678238Y1348187D03*
X1690478D03*
X1682598D03*
X1678238Y1360099D03*
X1690478D03*
X1682598D03*
X1678238Y1372385D03*
Y1384297D03*
X1690478D03*
Y1372385D03*
X1682598Y1384297D03*
Y1372385D03*
X1678238Y1396583D03*
X1690478D03*
X1682598D03*
X1678238Y1408495D03*
X1690478D03*
X1682598D03*
X1695866Y1090157D03*
Y1082676D03*
Y1090157D03*
Y1086417D03*
Y1078936D03*
X1699607Y1090158D03*
Y1082677D03*
X1695866Y1082676D03*
Y1101377D03*
Y1108858D03*
Y1093897D03*
Y1097637D03*
Y1105117D03*
X1699607Y1101378D03*
X1695866Y1101377D03*
Y1116338D03*
Y1123818D03*
Y1112598D03*
Y1120078D03*
X1699607Y1123819D03*
Y1116339D03*
Y1108859D03*
X1695866Y1123818D03*
Y1116338D03*
Y1108858D03*
Y1131299D03*
X1700236Y1136909D03*
X1697736Y1140649D03*
X1693996D03*
X1695866Y1127558D03*
Y1135039D03*
X1699607Y1131300D03*
X1695866Y1131299D03*
X1693996Y1136909D03*
X1697736D03*
Y1148129D03*
X1693996D03*
X1697736Y1155610D03*
X1693996D03*
Y1151870D03*
X1697736D03*
X1693996Y1144389D03*
X1697736D03*
X1693996Y1170570D03*
Y1166830D03*
X1697736D03*
Y1170570D03*
Y1159350D03*
X1693996D03*
X1697736Y1178051D03*
X1693996D03*
X1697736Y1185531D03*
X1693996D03*
X1697736Y1174310D03*
X1693996Y1189271D03*
X1697736D03*
Y1181791D03*
X1693996D03*
Y1174310D03*
X1695866Y1198621D03*
Y1206102D03*
X1693996Y1193011D03*
X1697676D03*
X1695866Y1202362D03*
X1699607Y1198621D03*
X1695866D03*
Y1221062D03*
Y1213582D03*
Y1217322D03*
Y1209842D03*
X1699607Y1221062D03*
Y1213582D03*
Y1206102D03*
X1695866Y1221062D03*
Y1213582D03*
Y1206102D03*
Y1228543D03*
Y1239763D03*
Y1232283D03*
Y1236023D03*
Y1224803D03*
X1699607Y1228543D03*
X1695866D03*
Y1247243D03*
Y1250984D03*
Y1243503D03*
X1699607Y1247243D03*
Y1239762D03*
X1695866Y1239763D03*
Y1247243D03*
X1694838Y1348187D03*
X1702718D03*
X1707078D03*
X1702718Y1360099D03*
X1707078D03*
X1694838D03*
Y1384297D03*
Y1372385D03*
X1702718D03*
Y1384297D03*
X1707078D03*
Y1372385D03*
X1694838Y1396583D03*
X1702718D03*
X1707078D03*
X1694838Y1408495D03*
X1702718D03*
X1707078D03*
X1714958Y1348187D03*
X1719318D03*
X1714958Y1360099D03*
X1719318D03*
X1714958Y1384297D03*
Y1372385D03*
X1719318D03*
Y1384297D03*
X1714958Y1396583D03*
X1719318D03*
X1714958Y1408495D03*
X1719318D03*
X1727198Y1348187D03*
X1739438D03*
X1731558D03*
X1727198Y1360099D03*
X1739438D03*
X1731558D03*
X1739438Y1372385D03*
X1731558Y1384297D03*
Y1372385D03*
X1727198D03*
Y1384297D03*
X1739438D03*
X1727198Y1396583D03*
X1739438D03*
X1731558D03*
X1727198Y1408495D03*
X1739438D03*
X1731558D03*
X1796283Y441086D03*
Y433999D03*
Y437543D03*
X1793483Y441086D03*
Y433999D03*
Y437543D03*
X1796283Y444629D03*
X1793483D03*
X2575564Y2408401D03*
X2589291Y2768713D03*
X2609880Y2024066D03*
X2644196Y1310303D03*
Y1660321D03*
X2785168Y931963D03*
X3481496Y2799598D03*
G54D28*
X895384Y228740D03*
Y276772D03*
X923336Y226772D03*
Y278740D03*
X2785168Y699913D03*
G54D29*
X909360Y230906D03*
Y274606D03*
X2785168Y268963D03*
M02*
